G04 ================== begin FILE IDENTIFICATION RECORD ==================*
G04 Layout Name:  15126-1b.brd*
G04 Film Name:    NOTICE*
G04 File Format:  Gerber RS274X*
G04 File Origin:  Cadence Allegro 16.6-2015-S079*
G04 Origin Date:  Fri Feb 10 17:21:54 2017*
G04 *
G04 Layer:  MANUFACTURING/THERMAL*
G04 *
G04 Offset:    (0.00 0.00)*
G04 Mirror:    No*
G04 Mode:      Positive*
G04 Rotation:  0*
G04 FullContactRelief:  No*
G04 UndefLineWidth:     6.00*
G04 ================== end FILE IDENTIFICATION RECORD ====================*
%FSLAX35Y35*MOIN*%
%IR0*IPPOS*OFA0.00000B0.00000*MIA0B0*SFA1.00000B1.00000*%
%ADD10C,.004*%
%ADD11C,.006*%
%ADD12C,.0033*%
%ADD13C,.008*%
%ADD14C,.0055*%
G75*
%LPD*%
G75*
G36*
G01X301800Y213890D02*
G02X352500Y214150I25558J-40503D01*
G01X341350Y192820D01*
X312850D01*
X301800Y213890D01*
G37*
G36*
G01X298620Y274980D02*
X307300D01*
G03X341410Y274970I17058J11442D01*
G01X348960D01*
X338090Y253970D01*
X309590D01*
X298620Y274980D01*
G37*
G54D10*
G01X770009Y207889D02*
Y217889D01*
G01X790009Y207889D02*
X770009D01*
G01Y177889D02*
X790009D01*
G01X820009Y167889D02*
X770009D01*
G01D02*
Y177889D01*
G01Y257889D02*
X790009D01*
G01X770009Y247889D02*
Y257889D01*
G01X790009Y247889D02*
X770009D01*
G01Y217889D02*
X790009D01*
G01X770009Y297889D02*
X810009D01*
G01X770009Y287889D02*
Y297889D01*
G01X790009Y287889D02*
X770009D01*
G01X859454Y153868D02*
X840594D01*
G01X852594Y155868D02*
X840594Y153868D01*
G01Y141868D02*
Y161868D01*
G01Y153868D02*
X852594Y151868D01*
G01X820594Y153868D02*
X808594Y155868D01*
G01X820594Y161868D02*
Y141868D01*
G01X808594Y155868D02*
Y151868D01*
G01D02*
X820594Y153868D01*
G01X796594D02*
X820594D01*
G01X840009Y167889D02*
X890009D01*
G01X840009Y225249D02*
Y167889D01*
G01X820009Y224740D02*
Y167889D01*
G01X790009Y177889D02*
Y207889D01*
G01X845009Y225249D02*
X961000D01*
G01X850009Y235249D02*
X840009Y225249D01*
G01X810005Y234744D02*
X810009Y234740D01*
G01Y297889D02*
Y234740D01*
G01D02*
X820009Y224740D01*
G01X790009Y257889D02*
Y287889D01*
G01Y217889D02*
Y247889D01*
G01X838514Y309548D02*
Y305548D01*
G01X850514Y307548D02*
X838514Y309548D01*
G01Y305548D02*
X850514Y307548D01*
G01X810514Y319548D02*
Y299548D01*
G01X822514Y305548D02*
Y309548D01*
G01X810514Y307548D02*
X822514Y305548D01*
G01Y309548D02*
X810514Y307548D01*
G01D02*
X850514D01*
G01X852594Y151868D02*
Y155868D01*
G01X890009Y207889D02*
X890000Y217800D01*
G01X890009Y167889D02*
Y177889D01*
G01X870009Y207889D02*
X890009D01*
G01X870009Y177889D02*
Y207889D01*
G01X890009Y177889D02*
X870009D01*
G01X895009Y217889D02*
X961000D01*
G01X890009Y247889D02*
Y257889D01*
G01X870009D02*
Y287889D01*
G01X890009Y257889D02*
X870009D01*
G01Y247889D02*
X890009D01*
G01X870009Y217889D02*
Y247889D01*
G01X890009Y217889D02*
X870009D01*
G01X850009Y297889D02*
Y235249D01*
G01X890009Y287889D02*
Y297889D01*
G01X870009Y287889D02*
X890009D01*
G01X850514Y319548D02*
Y299548D01*
G01Y307548D02*
X859374D01*
G01X890009Y297889D02*
X850009D01*
G01X958000Y205889D02*
X956000Y217889D01*
X954000Y205889D01*
X958000D01*
G01X956000Y193889D02*
Y217889D01*
G01X954000Y237249D02*
X956000Y225249D01*
X958000Y237249D01*
X954000D01*
G01X956000Y249249D02*
Y225249D01*
G01X1081654Y209388D02*
X1101654D01*
G01X1081654Y219388D02*
Y209388D01*
G01X1101654Y179388D02*
X1081654D01*
G01Y169388D02*
X1121654D01*
G01X1081654Y179388D02*
Y169388D01*
G01Y249388D02*
X1101654D01*
G01X1081654Y259388D02*
Y249388D01*
G01X1101654Y259388D02*
X1081654D01*
G01X1101654Y219388D02*
X1081654D01*
G01X1131654Y299388D02*
X1081654D01*
G01Y289388D02*
X1101654D01*
G01X1081654Y299388D02*
Y289388D01*
G01X1149654Y153388D02*
Y149388D01*
G01X1161654Y151388D02*
X1149654Y153388D01*
G01Y149388D02*
X1161654Y151388D01*
G01X1133654Y149388D02*
Y153388D01*
G01X1121654Y151388D02*
X1133654Y149388D01*
G01Y153388D02*
X1121654Y151388D01*
G01D02*
X1161654D01*
G01X1121654Y163388D02*
Y143388D01*
G01Y169388D02*
Y232028D01*
G01X1101654Y209388D02*
Y179388D01*
G01X1151654Y242537D02*
Y299388D01*
G01X1161654Y232537D02*
X1151654Y242537D01*
G01X1131654Y242028D02*
Y299388D01*
G01X1121654Y232028D02*
X1131654Y242028D01*
G01X1101654Y289388D02*
Y259388D01*
G01Y249388D02*
Y219388D01*
G01X1170514Y319388D02*
X1151654D01*
G01D02*
X1163654Y317388D01*
G01Y321388D02*
X1151654Y319388D01*
G01Y307388D02*
Y327388D01*
G01Y299388D02*
X1201654D01*
G01X1119654Y321388D02*
Y317388D01*
G01X1131654Y319388D02*
X1119654Y321388D01*
G01Y317388D02*
X1131654Y319388D01*
G01Y327388D02*
Y307388D01*
G01X1107654Y319388D02*
X1131654D01*
G01X1161654Y151388D02*
X1170514D01*
G01X1161654Y163388D02*
Y143388D01*
G01X1201654Y219388D02*
Y209388D01*
G01Y179388D02*
Y169388D01*
G01Y209388D02*
X1181654D01*
G01Y179388D02*
X1201654D01*
G01X1181654Y209388D02*
Y179388D01*
G01X1161654Y169388D02*
Y232537D01*
G01X1201654Y169388D02*
X1161654D01*
G01X1201654Y259388D02*
Y249388D01*
G01D02*
X1181654D01*
G01Y259388D02*
X1201654D01*
G01X1181654Y289388D02*
Y259388D01*
G01Y219388D02*
X1201654D01*
G01X1181654Y249388D02*
Y219388D01*
G01X1161658Y232533D02*
X1161654Y232537D01*
G01X1201654Y299388D02*
Y289388D01*
G01X1163654Y317388D02*
Y321388D01*
G01X1201654Y289388D02*
X1181654D01*
G54D11*
G01X4300Y524700D02*
X4250D01*
G01X54300Y770700D02*
X54250D01*
G01X288350Y208820D02*
X283350D01*
Y182820D01*
X288350D01*
G01Y187820D02*
X307850D01*
X296850Y208820D01*
X288350D01*
Y213820D01*
X301850D01*
X312850Y192820D01*
X341350D01*
X352350Y213820D01*
X365850D01*
Y208820D01*
X357350D01*
X346350Y187820D01*
X365850D01*
G01X288350D02*
Y182820D01*
X365850D01*
Y187820D01*
G01X285090Y269970D02*
X280090D01*
Y243970D01*
X285090D01*
G01Y248970D02*
X304590D01*
X293590Y269970D01*
X285090D01*
Y274970D01*
X298590D01*
X309590Y253970D01*
X338090D01*
X349090Y274970D01*
X362590D01*
Y269970D01*
X354090D01*
X343090Y248970D01*
X362590D01*
G01X285090D02*
Y243970D01*
X362590D01*
Y248970D01*
G01X283590Y340830D02*
X278590D01*
Y314830D01*
X283590D01*
G01Y319830D02*
Y314830D01*
X361090D01*
Y319830D01*
G01X283590D02*
X303090D01*
X292090Y340830D01*
X283590D01*
Y345830D01*
X297090D01*
X308090Y324830D01*
X336590D01*
X347590Y345830D01*
X361090D01*
Y340830D01*
X352590D01*
X341590Y319830D01*
X361090D01*
G01X304090Y354830D02*
X292090Y352830D01*
X304090Y350830D01*
Y354830D01*
G01X311290Y352830D02*
X292090D01*
G01X332370Y221310D02*
X388140D01*
G01X329290Y266000D02*
X387990D01*
G01X346210Y275010D02*
X387990D01*
G01X329590Y306830D02*
X341590Y308830D01*
X329590Y310830D01*
Y306830D01*
G01X339890Y308830D02*
X341590D01*
G01X315090Y310830D02*
X303090Y308830D01*
X315090Y306830D01*
Y310830D01*
G01X306290Y308830D02*
X303090D01*
G01X339590D02*
X304090D01*
G01X340590Y350830D02*
X352590Y352830D01*
X340590Y354830D01*
Y350830D01*
G01X334890Y352830D02*
X352590D01*
G01X385140Y202130D02*
X383140Y214130D01*
X381140Y202130D01*
X385140D01*
G01X383140Y197250D02*
Y214130D01*
G01X357370D02*
X388140D01*
G01X365850Y208820D02*
X370850D01*
Y182820D01*
X365850D01*
G01X385140Y233310D02*
X383140Y221310D01*
X381140Y233310D01*
X385140D01*
G01X383140Y237850D02*
Y221310D01*
G01X384990Y287010D02*
X382990Y275010D01*
X380990Y287010D01*
X384990D01*
G01X382990Y275010D02*
Y290150D01*
G01X384990Y254000D02*
X382990Y266000D01*
X380990Y254000D01*
X384990D01*
G01X382990Y250500D02*
Y266000D01*
G01X362590Y269970D02*
X367590D01*
Y243970D01*
X362590D01*
G01X361090Y340830D02*
X366090D01*
Y314830D01*
X361090D01*
G01X849500Y-12451D02*
X821000Y-12500D01*
G01X837503Y-14472D02*
X849500Y-12451D01*
X837497Y-10472D01*
X837503Y-14472D01*
G01X827500Y639629D02*
X830000Y624629D01*
X832500Y639629D01*
X827500D01*
G01X830000Y661875D02*
Y624629D01*
G01X931340D02*
X820000D01*
G01X832500Y710829D02*
X830000Y725829D01*
X827500Y710829D01*
X832500D01*
G01X830000Y693125D02*
Y725829D01*
G01X846340D02*
X820000D01*
G01X849500Y-12500D02*
Y59500D01*
X893500D01*
Y-12500D01*
X849500D01*
G01X903500D02*
X944500D01*
G01X903500Y59500D02*
X944500D01*
G01X878500Y67000D02*
X893500Y69500D01*
X878500Y72000D01*
Y67000D01*
G01X901475Y69500D02*
X893500D01*
G01X864500Y72000D02*
X849500Y69500D01*
X864500Y67000D01*
Y72000D01*
G01X893500Y69500D02*
X849500D01*
G01X893500Y64500D02*
Y79500D01*
G01X849500Y64500D02*
Y79500D01*
G01X932000Y2500D02*
X934500Y-12500D01*
X937000Y2500D01*
X932000D01*
G01X934500Y11875D02*
Y-12500D01*
G01X937000Y44500D02*
X934500Y59500D01*
X932000Y44500D01*
X937000D01*
G01X934500Y43125D02*
Y59500D01*
G01X1114953Y628479D02*
X1131500Y617000D01*
X1132500D01*
G01X1119916Y626861D02*
X1114953Y628479D01*
X1118206Y624397D01*
X1119916Y626861D01*
G01X1156654Y242537D02*
X1274500D01*
G01X1206654Y249388D02*
X1274500D01*
G01X1267500Y261388D02*
X1269500Y249388D01*
X1271500Y261388D01*
X1267500D01*
G01X1269500Y277200D02*
Y249388D01*
G01X1271500Y230537D02*
X1269500Y242537D01*
X1267500Y230537D01*
X1271500D01*
G01X1269500Y218537D02*
Y242537D01*
G01X11600Y-48833D02*
X12133Y-49250D01*
X12733Y-49500D01*
X13267D01*
X13800Y-49250D01*
X14200Y-48833D01*
X14400Y-48250D01*
X14267Y-47667D01*
X13933Y-47167D01*
X13333Y-46833D01*
X12533Y-46667D01*
X12067Y-46333D01*
X11867Y-45750D01*
X12000Y-45167D01*
X12333Y-44750D01*
X12800Y-44500D01*
X13267D01*
X13733Y-44667D01*
X14133Y-45083D01*
G01X18100Y-46167D02*
Y-49500D01*
G01Y-44833D02*
X17967Y-44750D01*
Y-44583D01*
X18100Y-44500D01*
X18233Y-44583D01*
Y-44750D01*
X18100Y-44833D01*
G01X23200Y-49500D02*
Y-44500D01*
G01X27167Y-49500D02*
Y-44500D01*
G01X29300Y-46167D02*
X27167Y-48083D01*
G01X28033Y-47333D02*
X29433Y-49500D01*
G01X32400Y-48917D02*
X32733Y-49250D01*
X33200Y-49500D01*
X33600D01*
X34000Y-49333D01*
X34267Y-49083D01*
X34400Y-48750D01*
X34333Y-48250D01*
X34067Y-48000D01*
X32867Y-47500D01*
X32600Y-46917D01*
X32733Y-46500D01*
X33000Y-46250D01*
X33400Y-46167D01*
X33800Y-46250D01*
X34200Y-46500D01*
G01X39567Y-46583D02*
X39100Y-46250D01*
X38700Y-46167D01*
X38167Y-46333D01*
X37767Y-46667D01*
X37500Y-47250D01*
X37433Y-47833D01*
X37500Y-48417D01*
X37767Y-48917D01*
X38167Y-49333D01*
X38700Y-49500D01*
X39167Y-49333D01*
X39567Y-49000D01*
G01X42667Y-49500D02*
Y-46167D01*
G01Y-46833D02*
X43000Y-46500D01*
X43333Y-46250D01*
X43800Y-46167D01*
X44133Y-46250D01*
X44533Y-46500D01*
G01X47700Y-47250D02*
X49833D01*
X49633Y-46667D01*
X49300Y-46333D01*
X48833Y-46167D01*
X48367Y-46250D01*
X47967Y-46500D01*
X47700Y-47083D01*
X47567Y-47583D01*
Y-48083D01*
X47700Y-48583D01*
X48033Y-49083D01*
X48433Y-49417D01*
X48900Y-49500D01*
X49367Y-49333D01*
X49833Y-48833D01*
G01X52800Y-47250D02*
X54933D01*
X54733Y-46667D01*
X54400Y-46333D01*
X53933Y-46167D01*
X53467Y-46250D01*
X53067Y-46500D01*
X52800Y-47083D01*
X52667Y-47583D01*
Y-48083D01*
X52800Y-48583D01*
X53133Y-49083D01*
X53533Y-49417D01*
X54000Y-49500D01*
X54467Y-49333D01*
X54933Y-48833D01*
G01X57767Y-49500D02*
Y-46167D01*
G01Y-47000D02*
X58033Y-46583D01*
X58433Y-46250D01*
X58967Y-46167D01*
X59433Y-46250D01*
X59833Y-46583D01*
X60033Y-47167D01*
Y-49500D01*
G01X0Y716000D02*
Y-69500D01*
G01D02*
X694500D01*
G01X11600Y-3833D02*
X12133Y-4250D01*
X12733Y-4500D01*
X13267D01*
X13800Y-4250D01*
X14200Y-3833D01*
X14400Y-3250D01*
X14267Y-2667D01*
X13933Y-2167D01*
X13333Y-1833D01*
X12533Y-1667D01*
X12067Y-1333D01*
X11867Y-750D01*
X12000Y-167D01*
X12333Y250D01*
X12800Y500D01*
X13267D01*
X13733Y333D01*
X14133Y-83D01*
G01X18100Y-4500D02*
X17700Y-4417D01*
X17300Y-4083D01*
X17033Y-3500D01*
X16900Y-2833D01*
X17033Y-2167D01*
X17300Y-1583D01*
X17700Y-1250D01*
X18100Y-1167D01*
X18500Y-1250D01*
X18900Y-1583D01*
X19167Y-2167D01*
X19233Y-2833D01*
X19167Y-3500D01*
X18900Y-4083D01*
X18500Y-4417D01*
X18100Y-4500D01*
G01X23200D02*
Y500D01*
G01X29500D02*
Y-4500D01*
G01Y-3750D02*
X29233Y-4167D01*
X28833Y-4417D01*
X28367Y-4500D01*
X27833Y-4333D01*
X27433Y-3917D01*
X27167Y-3417D01*
X27100Y-2833D01*
X27167Y-2250D01*
X27433Y-1750D01*
X27833Y-1333D01*
X28367Y-1167D01*
X28833Y-1250D01*
X29167Y-1417D01*
X29500Y-1750D01*
G01X32400Y-2250D02*
X34533D01*
X34333Y-1667D01*
X34000Y-1333D01*
X33533Y-1167D01*
X33067Y-1250D01*
X32667Y-1500D01*
X32400Y-2083D01*
X32267Y-2583D01*
Y-3083D01*
X32400Y-3583D01*
X32733Y-4083D01*
X33133Y-4417D01*
X33600Y-4500D01*
X34067Y-4333D01*
X34533Y-3833D01*
G01X37567Y-4500D02*
Y-1167D01*
G01Y-1833D02*
X37900Y-1500D01*
X38233Y-1250D01*
X38700Y-1167D01*
X39033Y-1250D01*
X39433Y-1500D01*
G01X46700Y-4500D02*
Y-1167D01*
G01Y-2083D02*
X46900Y-1667D01*
X47233Y-1333D01*
X47700Y-1167D01*
X48167Y-1333D01*
X48500Y-1667D01*
X48700Y-2083D01*
Y-4500D01*
G01Y-2083D02*
X48900Y-1667D01*
X49233Y-1333D01*
X49700Y-1167D01*
X50167Y-1333D01*
X50500Y-1667D01*
X50700Y-2167D01*
Y-4500D01*
G01X55000D02*
Y-1167D01*
G01Y-1750D02*
X54733Y-1417D01*
X54333Y-1250D01*
X53867Y-1167D01*
X53400Y-1333D01*
X53000Y-1667D01*
X52733Y-2167D01*
X52600Y-2833D01*
X52733Y-3500D01*
X53000Y-4000D01*
X53400Y-4333D01*
X53867Y-4500D01*
X54333Y-4417D01*
X54733Y-4167D01*
X55000Y-3833D01*
G01X57900Y-3917D02*
X58233Y-4250D01*
X58700Y-4500D01*
X59100D01*
X59500Y-4333D01*
X59767Y-4083D01*
X59900Y-3750D01*
X59833Y-3250D01*
X59567Y-3000D01*
X58367Y-2500D01*
X58100Y-1917D01*
X58233Y-1500D01*
X58500Y-1250D01*
X58900Y-1167D01*
X59300Y-1250D01*
X59700Y-1500D01*
G01X62867Y-4500D02*
Y500D01*
G01X65000Y-1167D02*
X62867Y-3083D01*
G01X63733Y-2333D02*
X65133Y-4500D01*
G01X0Y-24500D02*
X694500D01*
G01X0Y19500D02*
X694500D01*
G01X14333Y64000D02*
X11667D01*
Y69000D01*
X14333D01*
G01X13267Y66583D02*
X11667D01*
G01X18100Y69000D02*
Y64000D01*
G01X17167Y67333D02*
X19033D01*
G01X24267Y66917D02*
X23800Y67250D01*
X23400Y67333D01*
X22867Y67167D01*
X22467Y66833D01*
X22200Y66250D01*
X22133Y65667D01*
X22200Y65083D01*
X22467Y64583D01*
X22867Y64167D01*
X23400Y64000D01*
X23867Y64167D01*
X24267Y64500D01*
G01X27167Y64000D02*
Y69000D01*
G01Y66583D02*
X27500Y67000D01*
X27833Y67250D01*
X28367Y67333D01*
X28767Y67250D01*
X29233Y66917D01*
X29433Y66417D01*
Y64000D01*
G01X14333Y111500D02*
X11667D01*
Y116500D01*
X14333D01*
G01X13267Y114083D02*
X11667D01*
G01X17100Y114833D02*
X19100Y111500D01*
G01Y114833D02*
X17100Y111500D01*
G01X23200Y116500D02*
Y111500D01*
G01X22267Y114833D02*
X24133D01*
G01X27300Y113750D02*
X29433D01*
X29233Y114333D01*
X28900Y114667D01*
X28433Y114833D01*
X27967Y114750D01*
X27567Y114500D01*
X27300Y113917D01*
X27167Y113417D01*
Y112917D01*
X27300Y112417D01*
X27633Y111917D01*
X28033Y111583D01*
X28500Y111500D01*
X28967Y111667D01*
X29433Y112167D01*
G01X32467Y111500D02*
Y114833D01*
G01Y114167D02*
X32800Y114500D01*
X33133Y114750D01*
X33600Y114833D01*
X33933Y114750D01*
X34333Y114500D01*
G01X37367Y111500D02*
Y114833D01*
G01Y114000D02*
X37633Y114417D01*
X38033Y114750D01*
X38567Y114833D01*
X39033Y114750D01*
X39433Y114417D01*
X39633Y113833D01*
Y111500D01*
G01X44800D02*
Y114833D01*
G01Y114250D02*
X44533Y114583D01*
X44133Y114750D01*
X43667Y114833D01*
X43200Y114667D01*
X42800Y114333D01*
X42533Y113833D01*
X42400Y113167D01*
X42533Y112500D01*
X42800Y112000D01*
X43200Y111667D01*
X43667Y111500D01*
X44133Y111583D01*
X44533Y111833D01*
X44800Y112167D01*
G01X48700Y111500D02*
Y116500D01*
G01X58900Y111500D02*
Y116500D01*
G01X65200Y111500D02*
Y114833D01*
G01Y114250D02*
X64933Y114583D01*
X64533Y114750D01*
X64067Y114833D01*
X63600Y114667D01*
X63200Y114333D01*
X62933Y113833D01*
X62800Y113167D01*
X62933Y112500D01*
X63200Y112000D01*
X63600Y111667D01*
X64067Y111500D01*
X64533Y111583D01*
X64933Y111833D01*
X65200Y112167D01*
G01X67700Y110000D02*
X68100Y109833D01*
X68633Y110000D01*
X68967Y110333D01*
X69233Y110750D01*
X69633Y112083D01*
X70500Y114833D01*
G01X68367D02*
X69633Y112083D01*
G01X73200Y113750D02*
X75333D01*
X75133Y114333D01*
X74800Y114667D01*
X74333Y114833D01*
X73867Y114750D01*
X73467Y114500D01*
X73200Y113917D01*
X73067Y113417D01*
Y112917D01*
X73200Y112417D01*
X73533Y111917D01*
X73933Y111583D01*
X74400Y111500D01*
X74867Y111667D01*
X75333Y112167D01*
G01X78367Y111500D02*
Y114833D01*
G01Y114167D02*
X78700Y114500D01*
X79033Y114750D01*
X79500Y114833D01*
X79833Y114750D01*
X80233Y114500D01*
G01X14467Y146083D02*
X14067Y146333D01*
X13600Y146500D01*
X13067D01*
X12467Y146250D01*
X12000Y145833D01*
X11667Y145333D01*
X11400Y144500D01*
X11333Y143750D01*
X11467Y143000D01*
X11667Y142500D01*
X12067Y142000D01*
X12533Y141667D01*
X13000Y141500D01*
X13467D01*
X13933Y141667D01*
X14333Y141917D01*
X14667Y142250D01*
G01X18100Y141500D02*
X17700Y141583D01*
X17300Y141917D01*
X17033Y142500D01*
X16900Y143167D01*
X17033Y143833D01*
X17300Y144417D01*
X17700Y144750D01*
X18100Y144833D01*
X18500Y144750D01*
X18900Y144417D01*
X19167Y143833D01*
X19233Y143167D01*
X19167Y142500D01*
X18900Y141917D01*
X18500Y141583D01*
X18100Y141500D01*
G01X22000Y139833D02*
Y144833D01*
G01Y144083D02*
X22333Y144500D01*
X22667Y144750D01*
X23200Y144833D01*
X23667Y144750D01*
X24133Y144333D01*
X24333Y143750D01*
X24400Y143167D01*
X24333Y142583D01*
X24133Y142000D01*
X23733Y141667D01*
X23200Y141500D01*
X22733Y141583D01*
X22267Y141833D01*
X22000Y142167D01*
G01X27100Y139833D02*
Y144833D01*
G01Y144083D02*
X27433Y144500D01*
X27767Y144750D01*
X28300Y144833D01*
X28767Y144750D01*
X29233Y144333D01*
X29433Y143750D01*
X29500Y143167D01*
X29433Y142583D01*
X29233Y142000D01*
X28833Y141667D01*
X28300Y141500D01*
X27833Y141583D01*
X27367Y141833D01*
X27100Y142167D01*
G01X32400Y143750D02*
X34533D01*
X34333Y144333D01*
X34000Y144667D01*
X33533Y144833D01*
X33067Y144750D01*
X32667Y144500D01*
X32400Y143917D01*
X32267Y143417D01*
Y142917D01*
X32400Y142417D01*
X32733Y141917D01*
X33133Y141583D01*
X33600Y141500D01*
X34067Y141667D01*
X34533Y142167D01*
G01X37567Y141500D02*
Y144833D01*
G01Y144167D02*
X37900Y144500D01*
X38233Y144750D01*
X38700Y144833D01*
X39033Y144750D01*
X39433Y144500D01*
G01X47367Y141500D02*
Y146500D01*
X48967D01*
X49500Y146250D01*
X49900Y145667D01*
X50033Y145000D01*
X49900Y144333D01*
X49567Y143833D01*
X48967Y143583D01*
X47367D01*
G01X53800Y141500D02*
Y146500D01*
G01X60100Y141500D02*
Y144833D01*
G01Y144250D02*
X59833Y144583D01*
X59433Y144750D01*
X58967Y144833D01*
X58500Y144667D01*
X58100Y144333D01*
X57833Y143833D01*
X57700Y143167D01*
X57833Y142500D01*
X58100Y142000D01*
X58500Y141667D01*
X58967Y141500D01*
X59433Y141583D01*
X59833Y141833D01*
X60100Y142167D01*
G01X64000Y146500D02*
Y141500D01*
G01X63067Y144833D02*
X64933D01*
G01X69100D02*
Y141500D01*
G01Y146167D02*
X68967Y146250D01*
Y146417D01*
X69100Y146500D01*
X69233Y146417D01*
Y146250D01*
X69100Y146167D01*
G01X73067Y141500D02*
Y144833D01*
G01Y144000D02*
X73333Y144417D01*
X73733Y144750D01*
X74267Y144833D01*
X74733Y144750D01*
X75133Y144417D01*
X75333Y143833D01*
Y141500D01*
G01X78367Y140250D02*
X78833Y139917D01*
X79367Y139833D01*
X79833Y139917D01*
X80233Y140333D01*
X80500Y140917D01*
Y144833D01*
G01Y144167D02*
X80233Y144500D01*
X79833Y144750D01*
X79367Y144833D01*
X78833Y144667D01*
X78500Y144333D01*
X78233Y143750D01*
X78100Y143167D01*
X78167Y142667D01*
X78433Y142083D01*
X78833Y141667D01*
X79367Y141500D01*
X79767Y141583D01*
X80233Y141917D01*
X80500Y142250D01*
G01X0Y105500D02*
X694500D01*
G01X0Y120500D02*
X694500D01*
G01X1500Y175500D02*
X694500D01*
G01X11533Y459000D02*
Y464000D01*
X12867D01*
X13400Y463750D01*
X13800Y463417D01*
X14133Y462917D01*
X14400Y462333D01*
X14467Y461500D01*
X14400Y460667D01*
X14133Y460083D01*
X13800Y459583D01*
X13400Y459250D01*
X12867Y459000D01*
X11533D01*
G01X17167D02*
Y462333D01*
G01Y461667D02*
X17500Y462000D01*
X17833Y462250D01*
X18300Y462333D01*
X18633Y462250D01*
X19033Y462000D01*
G01X23200Y462333D02*
Y459000D01*
G01Y463667D02*
X23067Y463750D01*
Y463917D01*
X23200Y464000D01*
X23333Y463917D01*
Y463750D01*
X23200Y463667D01*
G01X28300Y459000D02*
Y464000D01*
G01X33400Y459000D02*
Y464000D01*
G01X24660Y626740D02*
X26260D01*
G01X25460D02*
Y621740D01*
G01X24660D02*
X26260D01*
G01X29427D02*
Y625073D01*
G01Y624240D02*
X29693Y624657D01*
X30093Y624990D01*
X30627Y625073D01*
X31093Y624990D01*
X31493Y624657D01*
X31693Y624073D01*
Y621740D01*
G01X34527D02*
Y625073D01*
G01Y624240D02*
X34793Y624657D01*
X35193Y624990D01*
X35727Y625073D01*
X36193Y624990D01*
X36593Y624657D01*
X36793Y624073D01*
Y621740D01*
G01X39760Y623990D02*
X41893D01*
X41693Y624573D01*
X41360Y624907D01*
X40893Y625073D01*
X40427Y624990D01*
X40027Y624740D01*
X39760Y624157D01*
X39627Y623657D01*
Y623157D01*
X39760Y622657D01*
X40093Y622157D01*
X40493Y621823D01*
X40960Y621740D01*
X41427Y621907D01*
X41893Y622407D01*
G01X44927Y621740D02*
Y625073D01*
G01Y624407D02*
X45260Y624740D01*
X45593Y624990D01*
X46060Y625073D01*
X46393Y624990D01*
X46793Y624740D01*
G01X56060Y621740D02*
Y626740D01*
G01X62360Y621740D02*
Y625073D01*
G01Y624490D02*
X62093Y624823D01*
X61693Y624990D01*
X61227Y625073D01*
X60760Y624907D01*
X60360Y624573D01*
X60093Y624073D01*
X59960Y623407D01*
X60093Y622740D01*
X60360Y622240D01*
X60760Y621907D01*
X61227Y621740D01*
X61693Y621823D01*
X62093Y622073D01*
X62360Y622407D01*
G01X64860Y620240D02*
X65260Y620073D01*
X65793Y620240D01*
X66127Y620573D01*
X66393Y620990D01*
X66793Y622323D01*
X67660Y625073D01*
G01X65527D02*
X66793Y622323D01*
G01X70360Y623990D02*
X72493D01*
X72293Y624573D01*
X71960Y624907D01*
X71493Y625073D01*
X71027Y624990D01*
X70627Y624740D01*
X70360Y624157D01*
X70227Y623657D01*
Y623157D01*
X70360Y622657D01*
X70693Y622157D01*
X71093Y621823D01*
X71560Y621740D01*
X72027Y621907D01*
X72493Y622407D01*
G01X75527Y621740D02*
Y625073D01*
G01Y624407D02*
X75860Y624740D01*
X76193Y624990D01*
X76660Y625073D01*
X76993Y624990D01*
X77393Y624740D01*
G01X0Y599000D02*
X694500D01*
G01X9733Y693667D02*
X10133Y694167D01*
X10600Y694417D01*
X11133Y694500D01*
X11800Y694333D01*
X12267Y693917D01*
X12400Y693417D01*
X12333Y692917D01*
X12067Y692500D01*
X10733Y691667D01*
X10133Y691083D01*
X9733Y690250D01*
X9600Y689500D01*
X12400D01*
G01X16100Y689333D02*
X15967Y689417D01*
Y689583D01*
X16100Y689667D01*
X16233Y689583D01*
Y689417D01*
X16100Y689333D01*
G01X21200Y694500D02*
Y689500D01*
G01X19667Y694500D02*
X22733D01*
G01X26300Y689500D02*
X25900Y689583D01*
X25500Y689917D01*
X25233Y690500D01*
X25100Y691167D01*
X25233Y691833D01*
X25500Y692417D01*
X25900Y692750D01*
X26300Y692833D01*
X26700Y692750D01*
X27100Y692417D01*
X27367Y691833D01*
X27433Y691167D01*
X27367Y690500D01*
X27100Y689917D01*
X26700Y689583D01*
X26300Y689500D01*
G01X31400D02*
Y694500D01*
G01X35500Y691750D02*
X37633D01*
X37433Y692333D01*
X37100Y692667D01*
X36633Y692833D01*
X36167Y692750D01*
X35767Y692500D01*
X35500Y691917D01*
X35367Y691417D01*
Y690917D01*
X35500Y690417D01*
X35833Y689917D01*
X36233Y689583D01*
X36700Y689500D01*
X37167Y689667D01*
X37633Y690167D01*
G01X40667Y689500D02*
Y692833D01*
G01Y692167D02*
X41000Y692500D01*
X41333Y692750D01*
X41800Y692833D01*
X42133Y692750D01*
X42533Y692500D01*
G01X47900Y689500D02*
Y692833D01*
G01Y692250D02*
X47633Y692583D01*
X47233Y692750D01*
X46767Y692833D01*
X46300Y692667D01*
X45900Y692333D01*
X45633Y691833D01*
X45500Y691167D01*
X45633Y690500D01*
X45900Y690000D01*
X46300Y689667D01*
X46767Y689500D01*
X47233Y689583D01*
X47633Y689833D01*
X47900Y690167D01*
G01X50667Y689500D02*
Y692833D01*
G01Y692000D02*
X50933Y692417D01*
X51333Y692750D01*
X51867Y692833D01*
X52333Y692750D01*
X52733Y692417D01*
X52933Y691833D01*
Y689500D01*
G01X57967Y692417D02*
X57500Y692750D01*
X57100Y692833D01*
X56567Y692667D01*
X56167Y692333D01*
X55900Y691750D01*
X55833Y691167D01*
X55900Y690583D01*
X56167Y690083D01*
X56567Y689667D01*
X57100Y689500D01*
X57567Y689667D01*
X57967Y690000D01*
G01X61000Y691750D02*
X63133D01*
X62933Y692333D01*
X62600Y692667D01*
X62133Y692833D01*
X61667Y692750D01*
X61267Y692500D01*
X61000Y691917D01*
X60867Y691417D01*
Y690917D01*
X61000Y690417D01*
X61333Y689917D01*
X61733Y689583D01*
X62200Y689500D01*
X62667Y689667D01*
X63133Y690167D01*
G01X72200Y694500D02*
Y689500D01*
G01X71267Y692833D02*
X73133D01*
G01X78500Y689500D02*
Y692833D01*
G01Y692250D02*
X78233Y692583D01*
X77833Y692750D01*
X77367Y692833D01*
X76900Y692667D01*
X76500Y692333D01*
X76233Y691833D01*
X76100Y691167D01*
X76233Y690500D01*
X76500Y690000D01*
X76900Y689667D01*
X77367Y689500D01*
X77833Y689583D01*
X78233Y689833D01*
X78500Y690167D01*
G01X81200Y689500D02*
Y694500D01*
G01Y692000D02*
X81533Y692500D01*
X81933Y692750D01*
X82333Y692833D01*
X82933Y692667D01*
X83333Y692333D01*
X83600Y691750D01*
Y691083D01*
X83467Y690417D01*
X83200Y689917D01*
X82733Y689583D01*
X82333Y689500D01*
X81933Y689583D01*
X81533Y689833D01*
X81200Y690250D01*
G01X87500Y689500D02*
Y694500D01*
G01X91600Y691750D02*
X93733D01*
X93533Y692333D01*
X93200Y692667D01*
X92733Y692833D01*
X92267Y692750D01*
X91867Y692500D01*
X91600Y691917D01*
X91467Y691417D01*
Y690917D01*
X91600Y690417D01*
X91933Y689917D01*
X92333Y689583D01*
X92800Y689500D01*
X93267Y689667D01*
X93733Y690167D01*
G01X97700Y689333D02*
X97567Y689417D01*
Y689583D01*
X97700Y689667D01*
X97833Y689583D01*
Y689417D01*
X97700Y689333D01*
G01Y691583D02*
X97567Y691667D01*
Y691833D01*
X97700Y691917D01*
X97833Y691833D01*
Y691667D01*
X97700Y691583D01*
G01X33800Y663333D02*
Y668333D01*
G01Y667583D02*
X34133Y668000D01*
X34467Y668250D01*
X35000Y668333D01*
X35467Y668250D01*
X35933Y667833D01*
X36133Y667250D01*
X36200Y666667D01*
X36133Y666083D01*
X35933Y665500D01*
X35533Y665167D01*
X35000Y665000D01*
X34533Y665083D01*
X34067Y665333D01*
X33800Y665667D01*
G01X39167Y665000D02*
Y668333D01*
G01Y667667D02*
X39500Y668000D01*
X39833Y668250D01*
X40300Y668333D01*
X40633Y668250D01*
X41033Y668000D01*
G01X45200Y665000D02*
X44800Y665083D01*
X44400Y665417D01*
X44133Y666000D01*
X44000Y666667D01*
X44133Y667333D01*
X44400Y667917D01*
X44800Y668250D01*
X45200Y668333D01*
X45600Y668250D01*
X46000Y667917D01*
X46267Y667333D01*
X46333Y666667D01*
X46267Y666000D01*
X46000Y665417D01*
X45600Y665083D01*
X45200Y665000D01*
G01X51367Y667917D02*
X50900Y668250D01*
X50500Y668333D01*
X49967Y668167D01*
X49567Y667833D01*
X49300Y667250D01*
X49233Y666667D01*
X49300Y666083D01*
X49567Y665583D01*
X49967Y665167D01*
X50500Y665000D01*
X50967Y665167D01*
X51367Y665500D01*
G01X54400Y667250D02*
X56533D01*
X56333Y667833D01*
X56000Y668167D01*
X55533Y668333D01*
X55067Y668250D01*
X54667Y668000D01*
X54400Y667417D01*
X54267Y666917D01*
Y666417D01*
X54400Y665917D01*
X54733Y665417D01*
X55133Y665083D01*
X55600Y665000D01*
X56067Y665167D01*
X56533Y665667D01*
G01X59500Y665583D02*
X59833Y665250D01*
X60300Y665000D01*
X60700D01*
X61100Y665167D01*
X61367Y665417D01*
X61500Y665750D01*
X61433Y666250D01*
X61167Y666500D01*
X59967Y667000D01*
X59700Y667583D01*
X59833Y668000D01*
X60100Y668250D01*
X60500Y668333D01*
X60900Y668250D01*
X61300Y668000D01*
G01X64600Y665583D02*
X64933Y665250D01*
X65400Y665000D01*
X65800D01*
X66200Y665167D01*
X66467Y665417D01*
X66600Y665750D01*
X66533Y666250D01*
X66267Y666500D01*
X65067Y667000D01*
X64800Y667583D01*
X64933Y668000D01*
X65200Y668250D01*
X65600Y668333D01*
X66000Y668250D01*
X66400Y668000D01*
G01X0Y679000D02*
X694500D01*
G01X-1000Y654000D02*
X694500D01*
G01X0Y850500D02*
Y709000D01*
X694500D01*
Y850500D01*
G01X6500Y832500D02*
Y837500D01*
X5700Y836500D01*
G01Y832500D02*
X7300D01*
G01X11600Y832333D02*
X11467Y832417D01*
Y832583D01*
X11600Y832667D01*
X11733Y832583D01*
Y832417D01*
X11600Y832333D01*
G01X15300Y833167D02*
X15833Y832750D01*
X16433Y832500D01*
X16967D01*
X17500Y832750D01*
X17900Y833167D01*
X18100Y833750D01*
X17967Y834333D01*
X17633Y834833D01*
X17033Y835167D01*
X16233Y835333D01*
X15767Y835667D01*
X15567Y836250D01*
X15700Y836833D01*
X16033Y837250D01*
X16500Y837500D01*
X16967D01*
X17433Y837333D01*
X17833Y836917D01*
G01X20600Y830833D02*
Y835833D01*
G01Y835083D02*
X20933Y835500D01*
X21267Y835750D01*
X21800Y835833D01*
X22267Y835750D01*
X22733Y835333D01*
X22933Y834750D01*
X23000Y834167D01*
X22933Y833583D01*
X22733Y833000D01*
X22333Y832667D01*
X21800Y832500D01*
X21333Y832583D01*
X20867Y832833D01*
X20600Y833167D01*
G01X25900Y834750D02*
X28033D01*
X27833Y835333D01*
X27500Y835667D01*
X27033Y835833D01*
X26567Y835750D01*
X26167Y835500D01*
X25900Y834917D01*
X25767Y834417D01*
Y833917D01*
X25900Y833417D01*
X26233Y832917D01*
X26633Y832583D01*
X27100Y832500D01*
X27567Y832667D01*
X28033Y833167D01*
G01X33067Y835417D02*
X32600Y835750D01*
X32200Y835833D01*
X31667Y835667D01*
X31267Y835333D01*
X31000Y834750D01*
X30933Y834167D01*
X31000Y833583D01*
X31267Y833083D01*
X31667Y832667D01*
X32200Y832500D01*
X32667Y832667D01*
X33067Y833000D01*
G01X37100Y835833D02*
Y832500D01*
G01Y837167D02*
X36967Y837250D01*
Y837417D01*
X37100Y837500D01*
X37233Y837417D01*
Y837250D01*
X37100Y837167D01*
G01X41800Y832500D02*
Y836750D01*
X41933Y837167D01*
X42200Y837417D01*
X42600Y837500D01*
X43000Y837333D01*
X43200Y836917D01*
G01X42400Y835500D02*
X41067D01*
G01X47300Y835833D02*
Y832500D01*
G01Y837167D02*
X47167Y837250D01*
Y837417D01*
X47300Y837500D01*
X47433Y837417D01*
Y837250D01*
X47300Y837167D01*
G01X53467Y835417D02*
X53000Y835750D01*
X52600Y835833D01*
X52067Y835667D01*
X51667Y835333D01*
X51400Y834750D01*
X51333Y834167D01*
X51400Y833583D01*
X51667Y833083D01*
X52067Y832667D01*
X52600Y832500D01*
X53067Y832667D01*
X53467Y833000D01*
G01X58700Y832500D02*
Y835833D01*
G01Y835250D02*
X58433Y835583D01*
X58033Y835750D01*
X57567Y835833D01*
X57100Y835667D01*
X56700Y835333D01*
X56433Y834833D01*
X56300Y834167D01*
X56433Y833500D01*
X56700Y833000D01*
X57100Y832667D01*
X57567Y832500D01*
X58033Y832583D01*
X58433Y832833D01*
X58700Y833167D01*
G01X62600Y837500D02*
Y832500D01*
G01X61667Y835833D02*
X63533D01*
G01X67700D02*
Y832500D01*
G01Y837167D02*
X67567Y837250D01*
Y837417D01*
X67700Y837500D01*
X67833Y837417D01*
Y837250D01*
X67700Y837167D01*
G01X72800Y832500D02*
X72400Y832583D01*
X72000Y832917D01*
X71733Y833500D01*
X71600Y834167D01*
X71733Y834833D01*
X72000Y835417D01*
X72400Y835750D01*
X72800Y835833D01*
X73200Y835750D01*
X73600Y835417D01*
X73867Y834833D01*
X73933Y834167D01*
X73867Y833500D01*
X73600Y832917D01*
X73200Y832583D01*
X72800Y832500D01*
G01X76767D02*
Y835833D01*
G01Y835000D02*
X77033Y835417D01*
X77433Y835750D01*
X77967Y835833D01*
X78433Y835750D01*
X78833Y835417D01*
X79033Y834833D01*
Y832500D01*
G01X89300Y837500D02*
Y832500D01*
G01Y833250D02*
X89033Y832833D01*
X88633Y832583D01*
X88167Y832500D01*
X87633Y832667D01*
X87233Y833083D01*
X86967Y833583D01*
X86900Y834167D01*
X86967Y834750D01*
X87233Y835250D01*
X87633Y835667D01*
X88167Y835833D01*
X88633Y835750D01*
X88967Y835583D01*
X89300Y835250D01*
G01X93200Y832500D02*
X92800Y832583D01*
X92400Y832917D01*
X92133Y833500D01*
X92000Y834167D01*
X92133Y834833D01*
X92400Y835417D01*
X92800Y835750D01*
X93200Y835833D01*
X93600Y835750D01*
X94000Y835417D01*
X94267Y834833D01*
X94333Y834167D01*
X94267Y833500D01*
X94000Y832917D01*
X93600Y832583D01*
X93200Y832500D01*
G01X99367Y835417D02*
X98900Y835750D01*
X98500Y835833D01*
X97967Y835667D01*
X97567Y835333D01*
X97300Y834750D01*
X97233Y834167D01*
X97300Y833583D01*
X97567Y833083D01*
X97967Y832667D01*
X98500Y832500D01*
X98967Y832667D01*
X99367Y833000D01*
G01X102267Y835833D02*
Y833500D01*
X102533Y832917D01*
X102933Y832583D01*
X103400Y832500D01*
X103867Y832583D01*
X104267Y832917D01*
X104533Y833500D01*
G01Y832500D02*
Y835833D01*
G01X106500Y832500D02*
Y835833D01*
G01Y834917D02*
X106700Y835333D01*
X107033Y835667D01*
X107500Y835833D01*
X107967Y835667D01*
X108300Y835333D01*
X108500Y834917D01*
Y832500D01*
G01Y834917D02*
X108700Y835333D01*
X109033Y835667D01*
X109500Y835833D01*
X109967Y835667D01*
X110300Y835333D01*
X110500Y834833D01*
Y832500D01*
G01X112600Y834750D02*
X114733D01*
X114533Y835333D01*
X114200Y835667D01*
X113733Y835833D01*
X113267Y835750D01*
X112867Y835500D01*
X112600Y834917D01*
X112467Y834417D01*
Y833917D01*
X112600Y833417D01*
X112933Y832917D01*
X113333Y832583D01*
X113800Y832500D01*
X114267Y832667D01*
X114733Y833167D01*
G01X117567Y832500D02*
Y835833D01*
G01Y835000D02*
X117833Y835417D01*
X118233Y835750D01*
X118767Y835833D01*
X119233Y835750D01*
X119633Y835417D01*
X119833Y834833D01*
Y832500D01*
G01X123800Y837500D02*
Y832500D01*
G01X122867Y835833D02*
X124733D01*
G01X128900Y832333D02*
X128767Y832417D01*
Y832583D01*
X128900Y832667D01*
X129033Y832583D01*
Y832417D01*
X128900Y832333D01*
G01Y834583D02*
X128767Y834667D01*
Y834833D01*
X128900Y834917D01*
X129033Y834833D01*
Y834667D01*
X128900Y834583D01*
G01X0Y820500D02*
X694500D01*
G01X0Y850500D02*
X694500D01*
G01X103500Y679000D02*
Y-69500D01*
G01Y-54500D02*
X694500D01*
G01X103500Y-9500D02*
X694500D01*
G01X103500Y60500D02*
X694500D01*
G01X105000Y364500D02*
X694500D01*
G01X103500Y449000D02*
X694500D01*
G01X104000Y464000D02*
X694500D01*
G01X103500Y424000D02*
X694500D01*
G01X103500Y584000D02*
X694500D01*
G01X103500Y614000D02*
X694500D01*
G01X103500Y629000D02*
X694500D01*
G01X66500Y725433D02*
X66367Y725517D01*
Y725683D01*
X66500Y725767D01*
X66633Y725683D01*
Y725517D01*
X66500Y725433D01*
G01Y734433D02*
X66367Y734517D01*
Y734683D01*
X66500Y734767D01*
X66633Y734683D01*
Y734517D01*
X66500Y734433D01*
G01Y743433D02*
X66367Y743517D01*
Y743683D01*
X66500Y743767D01*
X66633Y743683D01*
Y743517D01*
X66500Y743433D01*
G01Y752433D02*
X66367Y752517D01*
Y752683D01*
X66500Y752767D01*
X66633Y752683D01*
Y752517D01*
X66500Y752433D01*
G01Y761433D02*
X66367Y761517D01*
Y761683D01*
X66500Y761767D01*
X66633Y761683D01*
Y761517D01*
X66500Y761433D01*
G01Y770433D02*
X66367Y770517D01*
Y770683D01*
X66500Y770767D01*
X66633Y770683D01*
Y770517D01*
X66500Y770433D01*
G01X70700Y729600D02*
X72300D01*
G01X71500D02*
Y724600D01*
G01X70700D02*
X72300D01*
G01X75267D02*
Y729600D01*
X76867D01*
X77400Y729350D01*
X77800Y728767D01*
X77933Y728100D01*
X77800Y727433D01*
X77467Y726933D01*
X76867Y726683D01*
X75267D01*
G01X83167Y729183D02*
X82767Y729433D01*
X82300Y729600D01*
X81767D01*
X81167Y729350D01*
X80700Y728933D01*
X80367Y728433D01*
X80100Y727600D01*
X80033Y726850D01*
X80167Y726100D01*
X80367Y725600D01*
X80767Y725100D01*
X81233Y724767D01*
X81700Y724600D01*
X82167D01*
X82633Y724767D01*
X83033Y725017D01*
X83367Y725350D01*
G01X85933Y726267D02*
X87667D01*
G01X90567Y729600D02*
Y724600D01*
X93233D01*
G01X96133Y726267D02*
X97867D01*
G01X102100Y724600D02*
Y729600D01*
X101300Y728600D01*
G01Y724600D02*
X102900D01*
G01X107200Y729600D02*
X106667Y729433D01*
X106267Y729017D01*
X106000Y728517D01*
X105800Y727850D01*
X105733Y727100D01*
X105800Y726350D01*
X106000Y725683D01*
X106267Y725183D01*
X106667Y724767D01*
X107200Y724600D01*
X107733Y724767D01*
X108133Y725183D01*
X108400Y725683D01*
X108600Y726350D01*
X108667Y727100D01*
X108600Y727850D01*
X108400Y728517D01*
X108133Y729017D01*
X107733Y729433D01*
X107200Y729600D01*
G01X111167Y725183D02*
X111633Y724767D01*
X112167Y724600D01*
X112700Y724767D01*
X113167Y725267D01*
X113500Y726017D01*
X113633Y726767D01*
Y727683D01*
X113500Y728433D01*
X113167Y729100D01*
X112767Y729433D01*
X112300Y729600D01*
X111767Y729433D01*
X111367Y729100D01*
X111100Y728600D01*
X110967Y727933D01*
X111100Y727350D01*
X111433Y726767D01*
X111833Y726433D01*
X112300Y726350D01*
X112833Y726517D01*
X113233Y726933D01*
X113633Y727683D01*
G01X121100Y725267D02*
X121633Y724850D01*
X122233Y724600D01*
X122767D01*
X123300Y724850D01*
X123700Y725267D01*
X123900Y725850D01*
X123767Y726433D01*
X123433Y726933D01*
X122833Y727267D01*
X122033Y727433D01*
X121567Y727767D01*
X121367Y728350D01*
X121500Y728933D01*
X121833Y729350D01*
X122300Y729600D01*
X122767D01*
X123233Y729433D01*
X123633Y729017D01*
G01X126400Y722933D02*
Y727933D01*
G01Y727183D02*
X126733Y727600D01*
X127067Y727850D01*
X127600Y727933D01*
X128067Y727850D01*
X128533Y727433D01*
X128733Y726850D01*
X128800Y726267D01*
X128733Y725683D01*
X128533Y725100D01*
X128133Y724767D01*
X127600Y724600D01*
X127133Y724683D01*
X126667Y724933D01*
X126400Y725267D01*
G01X131700Y726850D02*
X133833D01*
X133633Y727433D01*
X133300Y727767D01*
X132833Y727933D01*
X132367Y727850D01*
X131967Y727600D01*
X131700Y727017D01*
X131567Y726517D01*
Y726017D01*
X131700Y725517D01*
X132033Y725017D01*
X132433Y724683D01*
X132900Y724600D01*
X133367Y724767D01*
X133833Y725267D01*
G01X138867Y727517D02*
X138400Y727850D01*
X138000Y727933D01*
X137467Y727767D01*
X137067Y727433D01*
X136800Y726850D01*
X136733Y726267D01*
X136800Y725683D01*
X137067Y725183D01*
X137467Y724767D01*
X138000Y724600D01*
X138467Y724767D01*
X138867Y725100D01*
G01X142900Y727933D02*
Y724600D01*
G01Y729267D02*
X142767Y729350D01*
Y729517D01*
X142900Y729600D01*
X143033Y729517D01*
Y729350D01*
X142900Y729267D01*
G01X147600Y724600D02*
Y728850D01*
X147733Y729267D01*
X148000Y729517D01*
X148400Y729600D01*
X148800Y729433D01*
X149000Y729017D01*
G01X148200Y727600D02*
X146867D01*
G01X153100Y727933D02*
Y724600D01*
G01Y729267D02*
X152967Y729350D01*
Y729517D01*
X153100Y729600D01*
X153233Y729517D01*
Y729350D01*
X153100Y729267D01*
G01X159267Y727517D02*
X158800Y727850D01*
X158400Y727933D01*
X157867Y727767D01*
X157467Y727433D01*
X157200Y726850D01*
X157133Y726267D01*
X157200Y725683D01*
X157467Y725183D01*
X157867Y724767D01*
X158400Y724600D01*
X158867Y724767D01*
X159267Y725100D01*
G01X164500Y724600D02*
Y727933D01*
G01Y727350D02*
X164233Y727683D01*
X163833Y727850D01*
X163367Y727933D01*
X162900Y727767D01*
X162500Y727433D01*
X162233Y726933D01*
X162100Y726267D01*
X162233Y725600D01*
X162500Y725100D01*
X162900Y724767D01*
X163367Y724600D01*
X163833Y724683D01*
X164233Y724933D01*
X164500Y725267D01*
G01X168400Y729600D02*
Y724600D01*
G01X167467Y727933D02*
X169333D01*
G01X173500D02*
Y724600D01*
G01Y729267D02*
X173367Y729350D01*
Y729517D01*
X173500Y729600D01*
X173633Y729517D01*
Y729350D01*
X173500Y729267D01*
G01X178600Y724600D02*
X178200Y724683D01*
X177800Y725017D01*
X177533Y725600D01*
X177400Y726267D01*
X177533Y726933D01*
X177800Y727517D01*
X178200Y727850D01*
X178600Y727933D01*
X179000Y727850D01*
X179400Y727517D01*
X179667Y726933D01*
X179733Y726267D01*
X179667Y725600D01*
X179400Y725017D01*
X179000Y724683D01*
X178600Y724600D01*
G01X182567D02*
Y727933D01*
G01Y727100D02*
X182833Y727517D01*
X183233Y727850D01*
X183767Y727933D01*
X184233Y727850D01*
X184633Y727517D01*
X184833Y726933D01*
Y724600D01*
G01X193500D02*
Y728850D01*
X193633Y729267D01*
X193900Y729517D01*
X194300Y729600D01*
X194700Y729433D01*
X194900Y729017D01*
G01X194100Y727600D02*
X192767D01*
G01X199000Y724600D02*
X198600Y724683D01*
X198200Y725017D01*
X197933Y725600D01*
X197800Y726267D01*
X197933Y726933D01*
X198200Y727517D01*
X198600Y727850D01*
X199000Y727933D01*
X199400Y727850D01*
X199800Y727517D01*
X200067Y726933D01*
X200133Y726267D01*
X200067Y725600D01*
X199800Y725017D01*
X199400Y724683D01*
X199000Y724600D01*
G01X203167D02*
Y727933D01*
G01Y727267D02*
X203500Y727600D01*
X203833Y727850D01*
X204300Y727933D01*
X204633Y727850D01*
X205033Y727600D01*
G01X212967Y724600D02*
Y729600D01*
X214633D01*
X215167Y729350D01*
X215500Y729017D01*
X215633Y728350D01*
X215500Y727683D01*
X215100Y727267D01*
X214633Y727017D01*
X212967D01*
G01X214633D02*
X215633Y724600D01*
G01X218400Y726850D02*
X220533D01*
X220333Y727433D01*
X220000Y727767D01*
X219533Y727933D01*
X219067Y727850D01*
X218667Y727600D01*
X218400Y727017D01*
X218267Y726517D01*
Y726017D01*
X218400Y725517D01*
X218733Y725017D01*
X219133Y724683D01*
X219600Y724600D01*
X220067Y724767D01*
X220533Y725267D01*
G01X223500Y725183D02*
X223833Y724850D01*
X224300Y724600D01*
X224700D01*
X225100Y724767D01*
X225367Y725017D01*
X225500Y725350D01*
X225433Y725850D01*
X225167Y726100D01*
X223967Y726600D01*
X223700Y727183D01*
X223833Y727600D01*
X224100Y727850D01*
X224500Y727933D01*
X224900Y727850D01*
X225300Y727600D01*
G01X229600Y727933D02*
Y724600D01*
G01Y729267D02*
X229467Y729350D01*
Y729517D01*
X229600Y729600D01*
X229733Y729517D01*
Y729350D01*
X229600Y729267D01*
G01X233567Y724600D02*
Y727933D01*
G01Y727100D02*
X233833Y727517D01*
X234233Y727850D01*
X234767Y727933D01*
X235233Y727850D01*
X235633Y727517D01*
X235833Y726933D01*
Y724600D01*
G01X244100Y729600D02*
X245700D01*
G01X244900D02*
Y724600D01*
G01X244100D02*
X245700D01*
G01X248000D02*
Y727933D01*
G01Y727017D02*
X248200Y727433D01*
X248533Y727767D01*
X249000Y727933D01*
X249467Y727767D01*
X249800Y727433D01*
X250000Y727017D01*
Y724600D01*
G01Y727017D02*
X250200Y727433D01*
X250533Y727767D01*
X251000Y727933D01*
X251467Y727767D01*
X251800Y727433D01*
X252000Y726933D01*
Y724600D01*
G01X253900Y722933D02*
Y727933D01*
G01Y727183D02*
X254233Y727600D01*
X254567Y727850D01*
X255100Y727933D01*
X255567Y727850D01*
X256033Y727433D01*
X256233Y726850D01*
X256300Y726267D01*
X256233Y725683D01*
X256033Y725100D01*
X255633Y724767D01*
X255100Y724600D01*
X254633Y724683D01*
X254167Y724933D01*
X253900Y725267D01*
G01X259267Y724600D02*
Y727933D01*
G01Y727267D02*
X259600Y727600D01*
X259933Y727850D01*
X260400Y727933D01*
X260733Y727850D01*
X261133Y727600D01*
G01X264300Y726850D02*
X266433D01*
X266233Y727433D01*
X265900Y727767D01*
X265433Y727933D01*
X264967Y727850D01*
X264567Y727600D01*
X264300Y727017D01*
X264167Y726517D01*
Y726017D01*
X264300Y725517D01*
X264633Y725017D01*
X265033Y724683D01*
X265500Y724600D01*
X265967Y724767D01*
X266433Y725267D01*
G01X269467Y723350D02*
X269933Y723017D01*
X270467Y722933D01*
X270933Y723017D01*
X271333Y723433D01*
X271600Y724017D01*
Y727933D01*
G01Y727267D02*
X271333Y727600D01*
X270933Y727850D01*
X270467Y727933D01*
X269933Y727767D01*
X269600Y727433D01*
X269333Y726850D01*
X269200Y726267D01*
X269267Y725767D01*
X269533Y725183D01*
X269933Y724767D01*
X270467Y724600D01*
X270867Y724683D01*
X271333Y725017D01*
X271600Y725350D01*
G01X274367Y724600D02*
Y727933D01*
G01Y727100D02*
X274633Y727517D01*
X275033Y727850D01*
X275567Y727933D01*
X276033Y727850D01*
X276433Y727517D01*
X276633Y726933D01*
Y724600D01*
G01X281800D02*
Y727933D01*
G01Y727350D02*
X281533Y727683D01*
X281133Y727850D01*
X280667Y727933D01*
X280200Y727767D01*
X279800Y727433D01*
X279533Y726933D01*
X279400Y726267D01*
X279533Y725600D01*
X279800Y725100D01*
X280200Y724767D01*
X280667Y724600D01*
X281133Y724683D01*
X281533Y724933D01*
X281800Y725267D01*
G01X285700Y729600D02*
Y724600D01*
G01X284767Y727933D02*
X286633D01*
G01X289800Y726850D02*
X291933D01*
X291733Y727433D01*
X291400Y727767D01*
X290933Y727933D01*
X290467Y727850D01*
X290067Y727600D01*
X289800Y727017D01*
X289667Y726517D01*
Y726017D01*
X289800Y725517D01*
X290133Y725017D01*
X290533Y724683D01*
X291000Y724600D01*
X291467Y724767D01*
X291933Y725267D01*
G01X297100Y729600D02*
Y724600D01*
G01Y725350D02*
X296833Y724933D01*
X296433Y724683D01*
X295967Y724600D01*
X295433Y724767D01*
X295033Y725183D01*
X294767Y725683D01*
X294700Y726267D01*
X294767Y726850D01*
X295033Y727350D01*
X295433Y727767D01*
X295967Y727933D01*
X296433Y727850D01*
X296767Y727683D01*
X297100Y727350D01*
G01X304833Y724600D02*
Y729600D01*
X307367D01*
G01X306433Y727183D02*
X304833D01*
G01X312400Y724600D02*
Y727933D01*
G01Y727350D02*
X312133Y727683D01*
X311733Y727850D01*
X311267Y727933D01*
X310800Y727767D01*
X310400Y727433D01*
X310133Y726933D01*
X310000Y726267D01*
X310133Y725600D01*
X310400Y725100D01*
X310800Y724767D01*
X311267Y724600D01*
X311733Y724683D01*
X312133Y724933D01*
X312400Y725267D01*
G01X315100Y724600D02*
Y729600D01*
G01Y727100D02*
X315433Y727600D01*
X315833Y727850D01*
X316233Y727933D01*
X316833Y727767D01*
X317233Y727433D01*
X317500Y726850D01*
Y726183D01*
X317367Y725517D01*
X317100Y725017D01*
X316633Y724683D01*
X316233Y724600D01*
X315833Y724683D01*
X315433Y724933D01*
X315100Y725350D01*
G01X320467Y724600D02*
Y727933D01*
G01Y727267D02*
X320800Y727600D01*
X321133Y727850D01*
X321600Y727933D01*
X321933Y727850D01*
X322333Y727600D01*
G01X326500Y727933D02*
Y724600D01*
G01Y729267D02*
X326367Y729350D01*
Y729517D01*
X326500Y729600D01*
X326633Y729517D01*
Y729350D01*
X326500Y729267D01*
G01X332667Y727517D02*
X332200Y727850D01*
X331800Y727933D01*
X331267Y727767D01*
X330867Y727433D01*
X330600Y726850D01*
X330533Y726267D01*
X330600Y725683D01*
X330867Y725183D01*
X331267Y724767D01*
X331800Y724600D01*
X332267Y724767D01*
X332667Y725100D01*
G01X336367Y722933D02*
X335700Y723767D01*
X335367Y724600D01*
Y727933D01*
X335700Y728767D01*
X336367Y729600D01*
G01X340467Y724600D02*
Y729600D01*
X342067D01*
X342600Y729350D01*
X343000Y728767D01*
X343133Y728100D01*
X343000Y727433D01*
X342667Y726933D01*
X342067Y726683D01*
X340467D01*
G01X345967Y724600D02*
Y727933D01*
G01Y727267D02*
X346300Y727600D01*
X346633Y727850D01*
X347100Y727933D01*
X347433Y727850D01*
X347833Y727600D01*
G01X351000Y726850D02*
X353133D01*
X352933Y727433D01*
X352600Y727767D01*
X352133Y727933D01*
X351667Y727850D01*
X351267Y727600D01*
X351000Y727017D01*
X350867Y726517D01*
Y726017D01*
X351000Y725517D01*
X351333Y725017D01*
X351733Y724683D01*
X352200Y724600D01*
X352667Y724767D01*
X353133Y725267D01*
G01X355900Y722933D02*
Y727933D01*
G01Y727183D02*
X356233Y727600D01*
X356567Y727850D01*
X357100Y727933D01*
X357567Y727850D01*
X358033Y727433D01*
X358233Y726850D01*
X358300Y726267D01*
X358233Y725683D01*
X358033Y725100D01*
X357633Y724767D01*
X357100Y724600D01*
X356633Y724683D01*
X356167Y724933D01*
X355900Y725267D01*
G01X361267Y724600D02*
Y727933D01*
G01Y727267D02*
X361600Y727600D01*
X361933Y727850D01*
X362400Y727933D01*
X362733Y727850D01*
X363133Y727600D01*
G01X366300Y726850D02*
X368433D01*
X368233Y727433D01*
X367900Y727767D01*
X367433Y727933D01*
X366967Y727850D01*
X366567Y727600D01*
X366300Y727017D01*
X366167Y726517D01*
Y726017D01*
X366300Y725517D01*
X366633Y725017D01*
X367033Y724683D01*
X367500Y724600D01*
X367967Y724767D01*
X368433Y725267D01*
G01X371467Y723350D02*
X371933Y723017D01*
X372467Y722933D01*
X372933Y723017D01*
X373333Y723433D01*
X373600Y724017D01*
Y727933D01*
G01Y727267D02*
X373333Y727600D01*
X372933Y727850D01*
X372467Y727933D01*
X371933Y727767D01*
X371600Y727433D01*
X371333Y726850D01*
X371200Y726267D01*
X371267Y725767D01*
X371533Y725183D01*
X371933Y724767D01*
X372467Y724600D01*
X372867Y724683D01*
X373333Y725017D01*
X373600Y725350D01*
G01X377833Y722933D02*
X378500Y723767D01*
X378833Y724600D01*
Y727933D01*
X378500Y728767D01*
X377833Y729600D01*
G01X387300Y724600D02*
Y728850D01*
X387433Y729267D01*
X387700Y729517D01*
X388100Y729600D01*
X388500Y729433D01*
X388700Y729017D01*
G01X387900Y727600D02*
X386567D01*
G01X392800Y724600D02*
X392400Y724683D01*
X392000Y725017D01*
X391733Y725600D01*
X391600Y726267D01*
X391733Y726933D01*
X392000Y727517D01*
X392400Y727850D01*
X392800Y727933D01*
X393200Y727850D01*
X393600Y727517D01*
X393867Y726933D01*
X393933Y726267D01*
X393867Y725600D01*
X393600Y725017D01*
X393200Y724683D01*
X392800Y724600D01*
G01X396967D02*
Y727933D01*
G01Y727267D02*
X397300Y727600D01*
X397633Y727850D01*
X398100Y727933D01*
X398433Y727850D01*
X398833Y727600D01*
G01X406367Y724600D02*
Y729600D01*
X408100Y725433D01*
X409833Y729600D01*
Y724600D01*
G01X412067Y727933D02*
Y725600D01*
X412333Y725017D01*
X412733Y724683D01*
X413200Y724600D01*
X413667Y724683D01*
X414067Y725017D01*
X414333Y725600D01*
G01Y724600D02*
Y727933D01*
G01X418300Y724600D02*
Y729600D01*
G01X423400D02*
Y724600D01*
G01X422467Y727933D02*
X424333D01*
G01X428500D02*
Y724600D01*
G01Y729267D02*
X428367Y729350D01*
Y729517D01*
X428500Y729600D01*
X428633Y729517D01*
Y729350D01*
X428500Y729267D01*
G01X433600Y724600D02*
Y729600D01*
G01X439900Y724600D02*
Y727933D01*
G01Y727350D02*
X439633Y727683D01*
X439233Y727850D01*
X438767Y727933D01*
X438300Y727767D01*
X437900Y727433D01*
X437633Y726933D01*
X437500Y726267D01*
X437633Y725600D01*
X437900Y725100D01*
X438300Y724767D01*
X438767Y724600D01*
X439233Y724683D01*
X439633Y724933D01*
X439900Y725267D01*
G01X442400Y723100D02*
X442800Y722933D01*
X443333Y723100D01*
X443667Y723433D01*
X443933Y723850D01*
X444333Y725183D01*
X445200Y727933D01*
G01X443067D02*
X444333Y725183D01*
G01X447900Y726850D02*
X450033D01*
X449833Y727433D01*
X449500Y727767D01*
X449033Y727933D01*
X448567Y727850D01*
X448167Y727600D01*
X447900Y727017D01*
X447767Y726517D01*
Y726017D01*
X447900Y725517D01*
X448233Y725017D01*
X448633Y724683D01*
X449100Y724600D01*
X449567Y724767D01*
X450033Y725267D01*
G01X453067Y724600D02*
Y727933D01*
G01Y727267D02*
X453400Y727600D01*
X453733Y727850D01*
X454200Y727933D01*
X454533Y727850D01*
X454933Y727600D01*
G01X462867Y724600D02*
Y729600D01*
X464467D01*
X465000Y729350D01*
X465400Y728767D01*
X465533Y728100D01*
X465400Y727433D01*
X465067Y726933D01*
X464467Y726683D01*
X462867D01*
G01X468367Y724600D02*
Y727933D01*
G01Y727267D02*
X468700Y727600D01*
X469033Y727850D01*
X469500Y727933D01*
X469833Y727850D01*
X470233Y727600D01*
G01X474400Y727933D02*
Y724600D01*
G01Y729267D02*
X474267Y729350D01*
Y729517D01*
X474400Y729600D01*
X474533Y729517D01*
Y729350D01*
X474400Y729267D01*
G01X478367Y724600D02*
Y727933D01*
G01Y727100D02*
X478633Y727517D01*
X479033Y727850D01*
X479567Y727933D01*
X480033Y727850D01*
X480433Y727517D01*
X480633Y726933D01*
Y724600D01*
G01X484600Y729600D02*
Y724600D01*
G01X483667Y727933D02*
X485533D01*
G01X488700Y726850D02*
X490833D01*
X490633Y727433D01*
X490300Y727767D01*
X489833Y727933D01*
X489367Y727850D01*
X488967Y727600D01*
X488700Y727017D01*
X488567Y726517D01*
Y726017D01*
X488700Y725517D01*
X489033Y725017D01*
X489433Y724683D01*
X489900Y724600D01*
X490367Y724767D01*
X490833Y725267D01*
G01X496000Y729600D02*
Y724600D01*
G01Y725350D02*
X495733Y724933D01*
X495333Y724683D01*
X494867Y724600D01*
X494333Y724767D01*
X493933Y725183D01*
X493667Y725683D01*
X493600Y726267D01*
X493667Y726850D01*
X493933Y727350D01*
X494333Y727767D01*
X494867Y727933D01*
X495333Y727850D01*
X495667Y727683D01*
X496000Y727350D01*
G01X505533Y727267D02*
X505800Y727517D01*
X506000Y727933D01*
X506133Y728517D01*
X506000Y729017D01*
X505733Y729350D01*
X505267Y729600D01*
X503467D01*
Y724600D01*
X505667D01*
X506133Y724933D01*
X506400Y725433D01*
X506533Y726017D01*
X506400Y726600D01*
X506000Y727100D01*
X505533Y727267D01*
X503467D01*
G01X510100Y724600D02*
X509700Y724683D01*
X509300Y725017D01*
X509033Y725600D01*
X508900Y726267D01*
X509033Y726933D01*
X509300Y727517D01*
X509700Y727850D01*
X510100Y727933D01*
X510500Y727850D01*
X510900Y727517D01*
X511167Y726933D01*
X511233Y726267D01*
X511167Y725600D01*
X510900Y725017D01*
X510500Y724683D01*
X510100Y724600D01*
G01X516400D02*
Y727933D01*
G01Y727350D02*
X516133Y727683D01*
X515733Y727850D01*
X515267Y727933D01*
X514800Y727767D01*
X514400Y727433D01*
X514133Y726933D01*
X514000Y726267D01*
X514133Y725600D01*
X514400Y725100D01*
X514800Y724767D01*
X515267Y724600D01*
X515733Y724683D01*
X516133Y724933D01*
X516400Y725267D01*
G01X519367Y724600D02*
Y727933D01*
G01Y727267D02*
X519700Y727600D01*
X520033Y727850D01*
X520500Y727933D01*
X520833Y727850D01*
X521233Y727600D01*
G01X526600Y729600D02*
Y724600D01*
G01Y725350D02*
X526333Y724933D01*
X525933Y724683D01*
X525467Y724600D01*
X524933Y724767D01*
X524533Y725183D01*
X524267Y725683D01*
X524200Y726267D01*
X524267Y726850D01*
X524533Y727350D01*
X524933Y727767D01*
X525467Y727933D01*
X525933Y727850D01*
X526267Y727683D01*
X526600Y727350D01*
G01X529500Y725183D02*
X529833Y724850D01*
X530300Y724600D01*
X530700D01*
X531100Y724767D01*
X531367Y725017D01*
X531500Y725350D01*
X531433Y725850D01*
X531167Y726100D01*
X529967Y726600D01*
X529700Y727183D01*
X529833Y727600D01*
X530100Y727850D01*
X530500Y727933D01*
X530900Y727850D01*
X531300Y727600D01*
G01X70700Y738600D02*
X72300D01*
G01X71500D02*
Y733600D01*
G01X70700D02*
X72300D01*
G01X75267D02*
Y738600D01*
X76867D01*
X77400Y738350D01*
X77800Y737767D01*
X77933Y737100D01*
X77800Y736433D01*
X77467Y735933D01*
X76867Y735683D01*
X75267D01*
G01X83167Y738183D02*
X82767Y738433D01*
X82300Y738600D01*
X81767D01*
X81167Y738350D01*
X80700Y737933D01*
X80367Y737433D01*
X80100Y736600D01*
X80033Y735850D01*
X80167Y735100D01*
X80367Y734600D01*
X80767Y734100D01*
X81233Y733767D01*
X81700Y733600D01*
X82167D01*
X82633Y733767D01*
X83033Y734017D01*
X83367Y734350D01*
G01X85933Y735267D02*
X87667D01*
G01X90167Y733600D02*
Y738600D01*
X91900Y734433D01*
X93633Y738600D01*
Y733600D01*
G01X95733D02*
Y738600D01*
X98267D01*
G01X97333Y736183D02*
X95733D01*
G01X101233Y735267D02*
X102967D01*
G01X107200Y733600D02*
Y738600D01*
X106400Y737600D01*
G01Y733600D02*
X108000D01*
G01X110833Y734350D02*
X111233Y733933D01*
X111700Y733683D01*
X112300Y733600D01*
X112900Y733767D01*
X113367Y734100D01*
X113700Y734683D01*
X113767Y735350D01*
X113633Y736017D01*
X113300Y736433D01*
X112833Y736767D01*
X112367Y736850D01*
X111900Y736767D01*
X111300Y736433D01*
X111500Y738600D01*
X113300D01*
G01X117400D02*
X116867Y738433D01*
X116467Y738017D01*
X116200Y737517D01*
X116000Y736850D01*
X115933Y736100D01*
X116000Y735350D01*
X116200Y734683D01*
X116467Y734183D01*
X116867Y733767D01*
X117400Y733600D01*
X117933Y733767D01*
X118333Y734183D01*
X118600Y734683D01*
X118800Y735350D01*
X118867Y736100D01*
X118800Y736850D01*
X118600Y737517D01*
X118333Y738017D01*
X117933Y738433D01*
X117400Y738600D01*
G01X125867Y733600D02*
Y738600D01*
X127600Y734433D01*
X129333Y738600D01*
Y733600D01*
G01X131700Y735850D02*
X133833D01*
X133633Y736433D01*
X133300Y736767D01*
X132833Y736933D01*
X132367Y736850D01*
X131967Y736600D01*
X131700Y736017D01*
X131567Y735517D01*
Y735017D01*
X131700Y734517D01*
X132033Y734017D01*
X132433Y733683D01*
X132900Y733600D01*
X133367Y733767D01*
X133833Y734267D01*
G01X137800Y738600D02*
Y733600D01*
G01X136867Y736933D02*
X138733D01*
G01X144100Y733600D02*
Y736933D01*
G01Y736350D02*
X143833Y736683D01*
X143433Y736850D01*
X142967Y736933D01*
X142500Y736767D01*
X142100Y736433D01*
X141833Y735933D01*
X141700Y735267D01*
X141833Y734600D01*
X142100Y734100D01*
X142500Y733767D01*
X142967Y733600D01*
X143433Y733683D01*
X143833Y733933D01*
X144100Y734267D01*
G01X148000Y733600D02*
Y738600D01*
G01X156933Y733600D02*
Y738600D01*
X159467D01*
G01X158533Y736183D02*
X156933D01*
G01X163300Y733600D02*
X162900Y733683D01*
X162500Y734017D01*
X162233Y734600D01*
X162100Y735267D01*
X162233Y735933D01*
X162500Y736517D01*
X162900Y736850D01*
X163300Y736933D01*
X163700Y736850D01*
X164100Y736517D01*
X164367Y735933D01*
X164433Y735267D01*
X164367Y734600D01*
X164100Y734017D01*
X163700Y733683D01*
X163300Y733600D01*
G01X168400Y736933D02*
Y733600D01*
G01Y738267D02*
X168267Y738350D01*
Y738517D01*
X168400Y738600D01*
X168533Y738517D01*
Y738350D01*
X168400Y738267D01*
G01X173500Y733600D02*
Y738600D01*
G01X183300Y733600D02*
Y737850D01*
X183433Y738267D01*
X183700Y738517D01*
X184100Y738600D01*
X184500Y738433D01*
X184700Y738017D01*
G01X183900Y736600D02*
X182567D01*
G01X188800Y733600D02*
X188400Y733683D01*
X188000Y734017D01*
X187733Y734600D01*
X187600Y735267D01*
X187733Y735933D01*
X188000Y736517D01*
X188400Y736850D01*
X188800Y736933D01*
X189200Y736850D01*
X189600Y736517D01*
X189867Y735933D01*
X189933Y735267D01*
X189867Y734600D01*
X189600Y734017D01*
X189200Y733683D01*
X188800Y733600D01*
G01X192967D02*
Y736933D01*
G01Y736267D02*
X193300Y736600D01*
X193633Y736850D01*
X194100Y736933D01*
X194433Y736850D01*
X194833Y736600D01*
G01X202767Y733600D02*
Y738600D01*
X204367D01*
X204900Y738350D01*
X205300Y737767D01*
X205433Y737100D01*
X205300Y736433D01*
X204967Y735933D01*
X204367Y735683D01*
X202767D01*
G01X208267Y733600D02*
Y736933D01*
G01Y736267D02*
X208600Y736600D01*
X208933Y736850D01*
X209400Y736933D01*
X209733Y736850D01*
X210133Y736600D01*
G01X214300Y736933D02*
Y733600D01*
G01Y738267D02*
X214167Y738350D01*
Y738517D01*
X214300Y738600D01*
X214433Y738517D01*
Y738350D01*
X214300Y738267D01*
G01X218267Y733600D02*
Y736933D01*
G01Y736100D02*
X218533Y736517D01*
X218933Y736850D01*
X219467Y736933D01*
X219933Y736850D01*
X220333Y736517D01*
X220533Y735933D01*
Y733600D01*
G01X224500Y738600D02*
Y733600D01*
G01X223567Y736933D02*
X225433D01*
G01X228600Y735850D02*
X230733D01*
X230533Y736433D01*
X230200Y736767D01*
X229733Y736933D01*
X229267Y736850D01*
X228867Y736600D01*
X228600Y736017D01*
X228467Y735517D01*
Y735017D01*
X228600Y734517D01*
X228933Y734017D01*
X229333Y733683D01*
X229800Y733600D01*
X230267Y733767D01*
X230733Y734267D01*
G01X235900Y738600D02*
Y733600D01*
G01Y734350D02*
X235633Y733933D01*
X235233Y733683D01*
X234767Y733600D01*
X234233Y733767D01*
X233833Y734183D01*
X233567Y734683D01*
X233500Y735267D01*
X233567Y735850D01*
X233833Y736350D01*
X234233Y736767D01*
X234767Y736933D01*
X235233Y736850D01*
X235567Y736683D01*
X235900Y736350D01*
G01X242900Y738600D02*
X243833Y733600D01*
X244900Y738600D01*
X245967Y733600D01*
X246900Y738600D01*
G01X250000Y736933D02*
Y733600D01*
G01Y738267D02*
X249867Y738350D01*
Y738517D01*
X250000Y738600D01*
X250133Y738517D01*
Y738350D01*
X250000Y738267D01*
G01X254167Y733600D02*
Y736933D01*
G01Y736267D02*
X254500Y736600D01*
X254833Y736850D01*
X255300Y736933D01*
X255633Y736850D01*
X256033Y736600D01*
G01X260200Y736933D02*
Y733600D01*
G01Y738267D02*
X260067Y738350D01*
Y738517D01*
X260200Y738600D01*
X260333Y738517D01*
Y738350D01*
X260200Y738267D01*
G01X264167Y733600D02*
Y736933D01*
G01Y736100D02*
X264433Y736517D01*
X264833Y736850D01*
X265367Y736933D01*
X265833Y736850D01*
X266233Y736517D01*
X266433Y735933D01*
Y733600D01*
G01X269467Y732350D02*
X269933Y732017D01*
X270467Y731933D01*
X270933Y732017D01*
X271333Y732433D01*
X271600Y733017D01*
Y736933D01*
G01Y736267D02*
X271333Y736600D01*
X270933Y736850D01*
X270467Y736933D01*
X269933Y736767D01*
X269600Y736433D01*
X269333Y735850D01*
X269200Y735267D01*
X269267Y734767D01*
X269533Y734183D01*
X269933Y733767D01*
X270467Y733600D01*
X270867Y733683D01*
X271333Y734017D01*
X271600Y734350D01*
G01X278933Y733600D02*
X280600Y738600D01*
X282267Y733600D01*
G01X281667Y735350D02*
X279533D01*
G01X284500Y731933D02*
Y736933D01*
G01Y736183D02*
X284833Y736600D01*
X285167Y736850D01*
X285700Y736933D01*
X286167Y736850D01*
X286633Y736433D01*
X286833Y735850D01*
X286900Y735267D01*
X286833Y734683D01*
X286633Y734100D01*
X286233Y733767D01*
X285700Y733600D01*
X285233Y733683D01*
X284767Y733933D01*
X284500Y734267D01*
G01X289600Y731933D02*
Y736933D01*
G01Y736183D02*
X289933Y736600D01*
X290267Y736850D01*
X290800Y736933D01*
X291267Y736850D01*
X291733Y736433D01*
X291933Y735850D01*
X292000Y735267D01*
X291933Y734683D01*
X291733Y734100D01*
X291333Y733767D01*
X290800Y733600D01*
X290333Y733683D01*
X289867Y733933D01*
X289600Y734267D01*
G01X295900Y733600D02*
Y738600D01*
G01X301000Y736933D02*
Y733600D01*
G01Y738267D02*
X300867Y738350D01*
Y738517D01*
X301000Y738600D01*
X301133Y738517D01*
Y738350D01*
X301000Y738267D01*
G01X307167Y736517D02*
X306700Y736850D01*
X306300Y736933D01*
X305767Y736767D01*
X305367Y736433D01*
X305100Y735850D01*
X305033Y735267D01*
X305100Y734683D01*
X305367Y734183D01*
X305767Y733767D01*
X306300Y733600D01*
X306767Y733767D01*
X307167Y734100D01*
G01X312400Y733600D02*
Y736933D01*
G01Y736350D02*
X312133Y736683D01*
X311733Y736850D01*
X311267Y736933D01*
X310800Y736767D01*
X310400Y736433D01*
X310133Y735933D01*
X310000Y735267D01*
X310133Y734600D01*
X310400Y734100D01*
X310800Y733767D01*
X311267Y733600D01*
X311733Y733683D01*
X312133Y733933D01*
X312400Y734267D01*
G01X316300Y738600D02*
Y733600D01*
G01X315367Y736933D02*
X317233D01*
G01X321400D02*
Y733600D01*
G01Y738267D02*
X321267Y738350D01*
Y738517D01*
X321400Y738600D01*
X321533Y738517D01*
Y738350D01*
X321400Y738267D01*
G01X326500Y733600D02*
X326100Y733683D01*
X325700Y734017D01*
X325433Y734600D01*
X325300Y735267D01*
X325433Y735933D01*
X325700Y736517D01*
X326100Y736850D01*
X326500Y736933D01*
X326900Y736850D01*
X327300Y736517D01*
X327567Y735933D01*
X327633Y735267D01*
X327567Y734600D01*
X327300Y734017D01*
X326900Y733683D01*
X326500Y733600D01*
G01X330467D02*
Y736933D01*
G01Y736100D02*
X330733Y736517D01*
X331133Y736850D01*
X331667Y736933D01*
X332133Y736850D01*
X332533Y736517D01*
X332733Y735933D01*
Y733600D01*
G01X335700Y734183D02*
X336033Y733850D01*
X336500Y733600D01*
X336900D01*
X337300Y733767D01*
X337567Y734017D01*
X337700Y734350D01*
X337633Y734850D01*
X337367Y735100D01*
X336167Y735600D01*
X335900Y736183D01*
X336033Y736600D01*
X336300Y736850D01*
X336700Y736933D01*
X337100Y736850D01*
X337500Y736600D01*
G01X70700Y747600D02*
X72300D01*
G01X71500D02*
Y742600D01*
G01X70700D02*
X72300D01*
G01X75267D02*
Y747600D01*
X76867D01*
X77400Y747350D01*
X77800Y746767D01*
X77933Y746100D01*
X77800Y745433D01*
X77467Y744933D01*
X76867Y744683D01*
X75267D01*
G01X83167Y747183D02*
X82767Y747433D01*
X82300Y747600D01*
X81767D01*
X81167Y747350D01*
X80700Y746933D01*
X80367Y746433D01*
X80100Y745600D01*
X80033Y744850D01*
X80167Y744100D01*
X80367Y743600D01*
X80767Y743100D01*
X81233Y742767D01*
X81700Y742600D01*
X82167D01*
X82633Y742767D01*
X83033Y743017D01*
X83367Y743350D01*
G01X85933Y744267D02*
X87667D01*
G01X92700Y742600D02*
Y747600D01*
X90233Y744017D01*
X93567D01*
G01X97000Y742600D02*
Y747600D01*
X96200Y746600D01*
G01Y742600D02*
X97800D01*
G01X102100Y747600D02*
X101567Y747433D01*
X101167Y747017D01*
X100900Y746517D01*
X100700Y745850D01*
X100633Y745100D01*
X100700Y744350D01*
X100900Y743683D01*
X101167Y743183D01*
X101567Y742767D01*
X102100Y742600D01*
X102633Y742767D01*
X103033Y743183D01*
X103300Y743683D01*
X103500Y744350D01*
X103567Y745100D01*
X103500Y745850D01*
X103300Y746517D01*
X103033Y747017D01*
X102633Y747433D01*
X102100Y747600D01*
G01X107200Y742600D02*
Y747600D01*
X106400Y746600D01*
G01Y742600D02*
X108000D01*
G01X116000Y743267D02*
X116533Y742850D01*
X117133Y742600D01*
X117667D01*
X118200Y742850D01*
X118600Y743267D01*
X118800Y743850D01*
X118667Y744433D01*
X118333Y744933D01*
X117733Y745267D01*
X116933Y745433D01*
X116467Y745767D01*
X116267Y746350D01*
X116400Y746933D01*
X116733Y747350D01*
X117200Y747600D01*
X117667D01*
X118133Y747433D01*
X118533Y747017D01*
G01X121300Y740933D02*
Y745933D01*
G01Y745183D02*
X121633Y745600D01*
X121967Y745850D01*
X122500Y745933D01*
X122967Y745850D01*
X123433Y745433D01*
X123633Y744850D01*
X123700Y744267D01*
X123633Y743683D01*
X123433Y743100D01*
X123033Y742767D01*
X122500Y742600D01*
X122033Y742683D01*
X121567Y742933D01*
X121300Y743267D01*
G01X126600Y744850D02*
X128733D01*
X128533Y745433D01*
X128200Y745767D01*
X127733Y745933D01*
X127267Y745850D01*
X126867Y745600D01*
X126600Y745017D01*
X126467Y744517D01*
Y744017D01*
X126600Y743517D01*
X126933Y743017D01*
X127333Y742683D01*
X127800Y742600D01*
X128267Y742767D01*
X128733Y743267D01*
G01X133767Y745517D02*
X133300Y745850D01*
X132900Y745933D01*
X132367Y745767D01*
X131967Y745433D01*
X131700Y744850D01*
X131633Y744267D01*
X131700Y743683D01*
X131967Y743183D01*
X132367Y742767D01*
X132900Y742600D01*
X133367Y742767D01*
X133767Y743100D01*
G01X137800Y745933D02*
Y742600D01*
G01Y747267D02*
X137667Y747350D01*
Y747517D01*
X137800Y747600D01*
X137933Y747517D01*
Y747350D01*
X137800Y747267D01*
G01X142500Y742600D02*
Y746850D01*
X142633Y747267D01*
X142900Y747517D01*
X143300Y747600D01*
X143700Y747433D01*
X143900Y747017D01*
G01X143100Y745600D02*
X141767D01*
G01X148000Y745933D02*
Y742600D01*
G01Y747267D02*
X147867Y747350D01*
Y747517D01*
X148000Y747600D01*
X148133Y747517D01*
Y747350D01*
X148000Y747267D01*
G01X154167Y745517D02*
X153700Y745850D01*
X153300Y745933D01*
X152767Y745767D01*
X152367Y745433D01*
X152100Y744850D01*
X152033Y744267D01*
X152100Y743683D01*
X152367Y743183D01*
X152767Y742767D01*
X153300Y742600D01*
X153767Y742767D01*
X154167Y743100D01*
G01X159400Y742600D02*
Y745933D01*
G01Y745350D02*
X159133Y745683D01*
X158733Y745850D01*
X158267Y745933D01*
X157800Y745767D01*
X157400Y745433D01*
X157133Y744933D01*
X157000Y744267D01*
X157133Y743600D01*
X157400Y743100D01*
X157800Y742767D01*
X158267Y742600D01*
X158733Y742683D01*
X159133Y742933D01*
X159400Y743267D01*
G01X163300Y747600D02*
Y742600D01*
G01X162367Y745933D02*
X164233D01*
G01X168400D02*
Y742600D01*
G01Y747267D02*
X168267Y747350D01*
Y747517D01*
X168400Y747600D01*
X168533Y747517D01*
Y747350D01*
X168400Y747267D01*
G01X173500Y742600D02*
X173100Y742683D01*
X172700Y743017D01*
X172433Y743600D01*
X172300Y744267D01*
X172433Y744933D01*
X172700Y745517D01*
X173100Y745850D01*
X173500Y745933D01*
X173900Y745850D01*
X174300Y745517D01*
X174567Y744933D01*
X174633Y744267D01*
X174567Y743600D01*
X174300Y743017D01*
X173900Y742683D01*
X173500Y742600D01*
G01X177467D02*
Y745933D01*
G01Y745100D02*
X177733Y745517D01*
X178133Y745850D01*
X178667Y745933D01*
X179133Y745850D01*
X179533Y745517D01*
X179733Y744933D01*
Y742600D01*
G01X188400D02*
Y746850D01*
X188533Y747267D01*
X188800Y747517D01*
X189200Y747600D01*
X189600Y747433D01*
X189800Y747017D01*
G01X189000Y745600D02*
X187667D01*
G01X193900Y742600D02*
X193500Y742683D01*
X193100Y743017D01*
X192833Y743600D01*
X192700Y744267D01*
X192833Y744933D01*
X193100Y745517D01*
X193500Y745850D01*
X193900Y745933D01*
X194300Y745850D01*
X194700Y745517D01*
X194967Y744933D01*
X195033Y744267D01*
X194967Y743600D01*
X194700Y743017D01*
X194300Y742683D01*
X193900Y742600D01*
G01X198067D02*
Y745933D01*
G01Y745267D02*
X198400Y745600D01*
X198733Y745850D01*
X199200Y745933D01*
X199533Y745850D01*
X199933Y745600D01*
G01X209733Y745267D02*
X210000Y745517D01*
X210200Y745933D01*
X210333Y746517D01*
X210200Y747017D01*
X209933Y747350D01*
X209467Y747600D01*
X207667D01*
Y742600D01*
X209867D01*
X210333Y742933D01*
X210600Y743433D01*
X210733Y744017D01*
X210600Y744600D01*
X210200Y745100D01*
X209733Y745267D01*
X207667D01*
G01X215500Y742600D02*
Y745933D01*
G01Y745350D02*
X215233Y745683D01*
X214833Y745850D01*
X214367Y745933D01*
X213900Y745767D01*
X213500Y745433D01*
X213233Y744933D01*
X213100Y744267D01*
X213233Y743600D01*
X213500Y743100D01*
X213900Y742767D01*
X214367Y742600D01*
X214833Y742683D01*
X215233Y742933D01*
X215500Y743267D01*
G01X218400Y743183D02*
X218733Y742850D01*
X219200Y742600D01*
X219600D01*
X220000Y742767D01*
X220267Y743017D01*
X220400Y743350D01*
X220333Y743850D01*
X220067Y744100D01*
X218867Y744600D01*
X218600Y745183D01*
X218733Y745600D01*
X219000Y745850D01*
X219400Y745933D01*
X219800Y745850D01*
X220200Y745600D01*
G01X223500Y744850D02*
X225633D01*
X225433Y745433D01*
X225100Y745767D01*
X224633Y745933D01*
X224167Y745850D01*
X223767Y745600D01*
X223500Y745017D01*
X223367Y744517D01*
Y744017D01*
X223500Y743517D01*
X223833Y743017D01*
X224233Y742683D01*
X224700Y742600D01*
X225167Y742767D01*
X225633Y743267D01*
G01X232967Y742600D02*
Y747600D01*
X234700Y743433D01*
X236433Y747600D01*
Y742600D01*
G01X241000D02*
Y745933D01*
G01Y745350D02*
X240733Y745683D01*
X240333Y745850D01*
X239867Y745933D01*
X239400Y745767D01*
X239000Y745433D01*
X238733Y744933D01*
X238600Y744267D01*
X238733Y743600D01*
X239000Y743100D01*
X239400Y742767D01*
X239867Y742600D01*
X240333Y742683D01*
X240733Y742933D01*
X241000Y743267D01*
G01X244900Y747600D02*
Y742600D01*
G01X243967Y745933D02*
X245833D01*
G01X249000Y744850D02*
X251133D01*
X250933Y745433D01*
X250600Y745767D01*
X250133Y745933D01*
X249667Y745850D01*
X249267Y745600D01*
X249000Y745017D01*
X248867Y744517D01*
Y744017D01*
X249000Y743517D01*
X249333Y743017D01*
X249733Y742683D01*
X250200Y742600D01*
X250667Y742767D01*
X251133Y743267D01*
G01X254167Y742600D02*
Y745933D01*
G01Y745267D02*
X254500Y745600D01*
X254833Y745850D01*
X255300Y745933D01*
X255633Y745850D01*
X256033Y745600D01*
G01X260200Y745933D02*
Y742600D01*
G01Y747267D02*
X260067Y747350D01*
Y747517D01*
X260200Y747600D01*
X260333Y747517D01*
Y747350D01*
X260200Y747267D01*
G01X266500Y742600D02*
Y745933D01*
G01Y745350D02*
X266233Y745683D01*
X265833Y745850D01*
X265367Y745933D01*
X264900Y745767D01*
X264500Y745433D01*
X264233Y744933D01*
X264100Y744267D01*
X264233Y743600D01*
X264500Y743100D01*
X264900Y742767D01*
X265367Y742600D01*
X265833Y742683D01*
X266233Y742933D01*
X266500Y743267D01*
G01X270400Y742600D02*
Y747600D01*
G01X274500Y743183D02*
X274833Y742850D01*
X275300Y742600D01*
X275700D01*
X276100Y742767D01*
X276367Y743017D01*
X276500Y743350D01*
X276433Y743850D01*
X276167Y744100D01*
X274967Y744600D01*
X274700Y745183D01*
X274833Y745600D01*
X275100Y745850D01*
X275500Y745933D01*
X275900Y745850D01*
X276300Y745600D01*
G01X285300Y742600D02*
Y746850D01*
X285433Y747267D01*
X285700Y747517D01*
X286100Y747600D01*
X286500Y747433D01*
X286700Y747017D01*
G01X285900Y745600D02*
X284567D01*
G01X290800Y742600D02*
X290400Y742683D01*
X290000Y743017D01*
X289733Y743600D01*
X289600Y744267D01*
X289733Y744933D01*
X290000Y745517D01*
X290400Y745850D01*
X290800Y745933D01*
X291200Y745850D01*
X291600Y745517D01*
X291867Y744933D01*
X291933Y744267D01*
X291867Y743600D01*
X291600Y743017D01*
X291200Y742683D01*
X290800Y742600D01*
G01X294967D02*
Y745933D01*
G01Y745267D02*
X295300Y745600D01*
X295633Y745850D01*
X296100Y745933D01*
X296433Y745850D01*
X296833Y745600D01*
G01X304767Y742600D02*
Y747600D01*
X306433D01*
X306967Y747350D01*
X307300Y747017D01*
X307433Y746350D01*
X307300Y745683D01*
X306900Y745267D01*
X306433Y745017D01*
X304767D01*
G01X306433D02*
X307433Y742600D01*
G01X311200Y745933D02*
Y742600D01*
G01Y747267D02*
X311067Y747350D01*
Y747517D01*
X311200Y747600D01*
X311333Y747517D01*
Y747350D01*
X311200Y747267D01*
G01X315367Y741350D02*
X315833Y741017D01*
X316367Y740933D01*
X316833Y741017D01*
X317233Y741433D01*
X317500Y742017D01*
Y745933D01*
G01Y745267D02*
X317233Y745600D01*
X316833Y745850D01*
X316367Y745933D01*
X315833Y745767D01*
X315500Y745433D01*
X315233Y744850D01*
X315100Y744267D01*
X315167Y743767D01*
X315433Y743183D01*
X315833Y742767D01*
X316367Y742600D01*
X316767Y742683D01*
X317233Y743017D01*
X317500Y743350D01*
G01X321400Y745933D02*
Y742600D01*
G01Y747267D02*
X321267Y747350D01*
Y747517D01*
X321400Y747600D01*
X321533Y747517D01*
Y747350D01*
X321400Y747267D01*
G01X327700Y747600D02*
Y742600D01*
G01Y743350D02*
X327433Y742933D01*
X327033Y742683D01*
X326567Y742600D01*
X326033Y742767D01*
X325633Y743183D01*
X325367Y743683D01*
X325300Y744267D01*
X325367Y744850D01*
X325633Y745350D01*
X326033Y745767D01*
X326567Y745933D01*
X327033Y745850D01*
X327367Y745683D01*
X327700Y745350D01*
G01X337900Y742600D02*
Y745933D01*
G01Y745350D02*
X337633Y745683D01*
X337233Y745850D01*
X336767Y745933D01*
X336300Y745767D01*
X335900Y745433D01*
X335633Y744933D01*
X335500Y744267D01*
X335633Y743600D01*
X335900Y743100D01*
X336300Y742767D01*
X336767Y742600D01*
X337233Y742683D01*
X337633Y742933D01*
X337900Y743267D01*
G01X340667Y742600D02*
Y745933D01*
G01Y745100D02*
X340933Y745517D01*
X341333Y745850D01*
X341867Y745933D01*
X342333Y745850D01*
X342733Y745517D01*
X342933Y744933D01*
Y742600D01*
G01X348100Y747600D02*
Y742600D01*
G01Y743350D02*
X347833Y742933D01*
X347433Y742683D01*
X346967Y742600D01*
X346433Y742767D01*
X346033Y743183D01*
X345767Y743683D01*
X345700Y744267D01*
X345767Y744850D01*
X346033Y745350D01*
X346433Y745767D01*
X346967Y745933D01*
X347433Y745850D01*
X347767Y745683D01*
X348100Y745350D01*
G01X355367Y742600D02*
Y747600D01*
X357100Y743433D01*
X358833Y747600D01*
Y742600D01*
G01X361067Y745933D02*
Y743600D01*
X361333Y743017D01*
X361733Y742683D01*
X362200Y742600D01*
X362667Y742683D01*
X363067Y743017D01*
X363333Y743600D01*
G01Y742600D02*
Y745933D01*
G01X367300Y742600D02*
Y747600D01*
G01X372400D02*
Y742600D01*
G01X371467Y745933D02*
X373333D01*
G01X377500D02*
Y742600D01*
G01Y747267D02*
X377367Y747350D01*
Y747517D01*
X377500Y747600D01*
X377633Y747517D01*
Y747350D01*
X377500Y747267D01*
G01X382600Y742600D02*
Y747600D01*
G01X388900Y742600D02*
Y745933D01*
G01Y745350D02*
X388633Y745683D01*
X388233Y745850D01*
X387767Y745933D01*
X387300Y745767D01*
X386900Y745433D01*
X386633Y744933D01*
X386500Y744267D01*
X386633Y743600D01*
X386900Y743100D01*
X387300Y742767D01*
X387767Y742600D01*
X388233Y742683D01*
X388633Y742933D01*
X388900Y743267D01*
G01X391400Y741100D02*
X391800Y740933D01*
X392333Y741100D01*
X392667Y741433D01*
X392933Y741850D01*
X393333Y743183D01*
X394200Y745933D01*
G01X392067D02*
X393333Y743183D01*
G01X396900Y744850D02*
X399033D01*
X398833Y745433D01*
X398500Y745767D01*
X398033Y745933D01*
X397567Y745850D01*
X397167Y745600D01*
X396900Y745017D01*
X396767Y744517D01*
Y744017D01*
X396900Y743517D01*
X397233Y743017D01*
X397633Y742683D01*
X398100Y742600D01*
X398567Y742767D01*
X399033Y743267D01*
G01X402067Y742600D02*
Y745933D01*
G01Y745267D02*
X402400Y745600D01*
X402733Y745850D01*
X403200Y745933D01*
X403533Y745850D01*
X403933Y745600D01*
G01X411867Y742600D02*
Y747600D01*
X413467D01*
X414000Y747350D01*
X414400Y746767D01*
X414533Y746100D01*
X414400Y745433D01*
X414067Y744933D01*
X413467Y744683D01*
X411867D01*
G01X417367Y742600D02*
Y745933D01*
G01Y745267D02*
X417700Y745600D01*
X418033Y745850D01*
X418500Y745933D01*
X418833Y745850D01*
X419233Y745600D01*
G01X423400Y745933D02*
Y742600D01*
G01Y747267D02*
X423267Y747350D01*
Y747517D01*
X423400Y747600D01*
X423533Y747517D01*
Y747350D01*
X423400Y747267D01*
G01X427367Y742600D02*
Y745933D01*
G01Y745100D02*
X427633Y745517D01*
X428033Y745850D01*
X428567Y745933D01*
X429033Y745850D01*
X429433Y745517D01*
X429633Y744933D01*
Y742600D01*
G01X433600Y747600D02*
Y742600D01*
G01X432667Y745933D02*
X434533D01*
G01X437700Y744850D02*
X439833D01*
X439633Y745433D01*
X439300Y745767D01*
X438833Y745933D01*
X438367Y745850D01*
X437967Y745600D01*
X437700Y745017D01*
X437567Y744517D01*
Y744017D01*
X437700Y743517D01*
X438033Y743017D01*
X438433Y742683D01*
X438900Y742600D01*
X439367Y742767D01*
X439833Y743267D01*
G01X445000Y747600D02*
Y742600D01*
G01Y743350D02*
X444733Y742933D01*
X444333Y742683D01*
X443867Y742600D01*
X443333Y742767D01*
X442933Y743183D01*
X442667Y743683D01*
X442600Y744267D01*
X442667Y744850D01*
X442933Y745350D01*
X443333Y745767D01*
X443867Y745933D01*
X444333Y745850D01*
X444667Y745683D01*
X445000Y745350D01*
G01X454533Y745267D02*
X454800Y745517D01*
X455000Y745933D01*
X455133Y746517D01*
X455000Y747017D01*
X454733Y747350D01*
X454267Y747600D01*
X452467D01*
Y742600D01*
X454667D01*
X455133Y742933D01*
X455400Y743433D01*
X455533Y744017D01*
X455400Y744600D01*
X455000Y745100D01*
X454533Y745267D01*
X452467D01*
G01X459100Y742600D02*
X458700Y742683D01*
X458300Y743017D01*
X458033Y743600D01*
X457900Y744267D01*
X458033Y744933D01*
X458300Y745517D01*
X458700Y745850D01*
X459100Y745933D01*
X459500Y745850D01*
X459900Y745517D01*
X460167Y744933D01*
X460233Y744267D01*
X460167Y743600D01*
X459900Y743017D01*
X459500Y742683D01*
X459100Y742600D01*
G01X465400D02*
Y745933D01*
G01Y745350D02*
X465133Y745683D01*
X464733Y745850D01*
X464267Y745933D01*
X463800Y745767D01*
X463400Y745433D01*
X463133Y744933D01*
X463000Y744267D01*
X463133Y743600D01*
X463400Y743100D01*
X463800Y742767D01*
X464267Y742600D01*
X464733Y742683D01*
X465133Y742933D01*
X465400Y743267D01*
G01X468367Y742600D02*
Y745933D01*
G01Y745267D02*
X468700Y745600D01*
X469033Y745850D01*
X469500Y745933D01*
X469833Y745850D01*
X470233Y745600D01*
G01X475600Y747600D02*
Y742600D01*
G01Y743350D02*
X475333Y742933D01*
X474933Y742683D01*
X474467Y742600D01*
X473933Y742767D01*
X473533Y743183D01*
X473267Y743683D01*
X473200Y744267D01*
X473267Y744850D01*
X473533Y745350D01*
X473933Y745767D01*
X474467Y745933D01*
X474933Y745850D01*
X475267Y745683D01*
X475600Y745350D01*
G01X478500Y743183D02*
X478833Y742850D01*
X479300Y742600D01*
X479700D01*
X480100Y742767D01*
X480367Y743017D01*
X480500Y743350D01*
X480433Y743850D01*
X480167Y744100D01*
X478967Y744600D01*
X478700Y745183D01*
X478833Y745600D01*
X479100Y745850D01*
X479500Y745933D01*
X479900Y745850D01*
X480300Y745600D01*
G01X70700Y756600D02*
X72300D01*
G01X71500D02*
Y751600D01*
G01X70700D02*
X72300D01*
G01X75267D02*
Y756600D01*
X76867D01*
X77400Y756350D01*
X77800Y755767D01*
X77933Y755100D01*
X77800Y754433D01*
X77467Y753933D01*
X76867Y753683D01*
X75267D01*
G01X83167Y756183D02*
X82767Y756433D01*
X82300Y756600D01*
X81767D01*
X81167Y756350D01*
X80700Y755933D01*
X80367Y755433D01*
X80100Y754600D01*
X80033Y753850D01*
X80167Y753100D01*
X80367Y752600D01*
X80767Y752100D01*
X81233Y751767D01*
X81700Y751600D01*
X82167D01*
X82633Y751767D01*
X83033Y752017D01*
X83367Y752350D01*
G01X85933Y753267D02*
X87667D01*
G01X91900Y756600D02*
Y751600D01*
G01X90367Y756600D02*
X93433D01*
G01X95267Y751600D02*
Y756600D01*
X97000Y752433D01*
X98733Y756600D01*
Y751600D01*
G01X101233Y753267D02*
X102967D01*
G01X105933Y753683D02*
X106400Y754267D01*
X106800Y754600D01*
X107333Y754767D01*
X107800Y754600D01*
X108133Y754267D01*
X108400Y753767D01*
X108467Y753183D01*
X108400Y752683D01*
X108133Y752183D01*
X107733Y751767D01*
X107267Y751600D01*
X106733Y751767D01*
X106267Y752267D01*
X106000Y753017D01*
X105933Y753850D01*
X106067Y754933D01*
X106267Y755517D01*
X106600Y756100D01*
X107067Y756517D01*
X107533Y756600D01*
X108000Y756433D01*
X108333Y756017D01*
G01X110833Y752350D02*
X111233Y751933D01*
X111700Y751683D01*
X112300Y751600D01*
X112900Y751767D01*
X113367Y752100D01*
X113700Y752683D01*
X113767Y753350D01*
X113633Y754017D01*
X113300Y754433D01*
X112833Y754767D01*
X112367Y754850D01*
X111900Y754767D01*
X111300Y754433D01*
X111500Y756600D01*
X113300D01*
G01X117400D02*
X116867Y756433D01*
X116467Y756017D01*
X116200Y755517D01*
X116000Y754850D01*
X115933Y754100D01*
X116000Y753350D01*
X116200Y752683D01*
X116467Y752183D01*
X116867Y751767D01*
X117400Y751600D01*
X117933Y751767D01*
X118333Y752183D01*
X118600Y752683D01*
X118800Y753350D01*
X118867Y754100D01*
X118800Y754850D01*
X118600Y755517D01*
X118333Y756017D01*
X117933Y756433D01*
X117400Y756600D01*
G01X127600D02*
Y751600D01*
G01X126067Y756600D02*
X129133D01*
G01X131700Y753850D02*
X133833D01*
X133633Y754433D01*
X133300Y754767D01*
X132833Y754933D01*
X132367Y754850D01*
X131967Y754600D01*
X131700Y754017D01*
X131567Y753517D01*
Y753017D01*
X131700Y752517D01*
X132033Y752017D01*
X132433Y751683D01*
X132900Y751600D01*
X133367Y751767D01*
X133833Y752267D01*
G01X136800Y752183D02*
X137133Y751850D01*
X137600Y751600D01*
X138000D01*
X138400Y751767D01*
X138667Y752017D01*
X138800Y752350D01*
X138733Y752850D01*
X138467Y753100D01*
X137267Y753600D01*
X137000Y754183D01*
X137133Y754600D01*
X137400Y754850D01*
X137800Y754933D01*
X138200Y754850D01*
X138600Y754600D01*
G01X142900Y756600D02*
Y751600D01*
G01X141967Y754933D02*
X143833D01*
G01X151367Y751600D02*
Y756600D01*
X153100Y752433D01*
X154833Y756600D01*
Y751600D01*
G01X157200Y753850D02*
X159333D01*
X159133Y754433D01*
X158800Y754767D01*
X158333Y754933D01*
X157867Y754850D01*
X157467Y754600D01*
X157200Y754017D01*
X157067Y753517D01*
Y753017D01*
X157200Y752517D01*
X157533Y752017D01*
X157933Y751683D01*
X158400Y751600D01*
X158867Y751767D01*
X159333Y752267D01*
G01X163300Y756600D02*
Y751600D01*
G01X162367Y754933D02*
X164233D01*
G01X167267Y751600D02*
Y756600D01*
G01Y754183D02*
X167600Y754600D01*
X167933Y754850D01*
X168467Y754933D01*
X168867Y754850D01*
X169333Y754517D01*
X169533Y754017D01*
Y751600D01*
G01X173500D02*
X173100Y751683D01*
X172700Y752017D01*
X172433Y752600D01*
X172300Y753267D01*
X172433Y753933D01*
X172700Y754517D01*
X173100Y754850D01*
X173500Y754933D01*
X173900Y754850D01*
X174300Y754517D01*
X174567Y753933D01*
X174633Y753267D01*
X174567Y752600D01*
X174300Y752017D01*
X173900Y751683D01*
X173500Y751600D01*
G01X179800Y756600D02*
Y751600D01*
G01Y752350D02*
X179533Y751933D01*
X179133Y751683D01*
X178667Y751600D01*
X178133Y751767D01*
X177733Y752183D01*
X177467Y752683D01*
X177400Y753267D01*
X177467Y753850D01*
X177733Y754350D01*
X178133Y754767D01*
X178667Y754933D01*
X179133Y754850D01*
X179467Y754683D01*
X179800Y754350D01*
G01X182700Y752183D02*
X183033Y751850D01*
X183500Y751600D01*
X183900D01*
X184300Y751767D01*
X184567Y752017D01*
X184700Y752350D01*
X184633Y752850D01*
X184367Y753100D01*
X183167Y753600D01*
X182900Y754183D01*
X183033Y754600D01*
X183300Y754850D01*
X183700Y754933D01*
X184100Y754850D01*
X184500Y754600D01*
G01X192167Y751600D02*
Y756600D01*
X193900Y752433D01*
X195633Y756600D01*
Y751600D01*
G01X200200D02*
Y754933D01*
G01Y754350D02*
X199933Y754683D01*
X199533Y754850D01*
X199067Y754933D01*
X198600Y754767D01*
X198200Y754433D01*
X197933Y753933D01*
X197800Y753267D01*
X197933Y752600D01*
X198200Y752100D01*
X198600Y751767D01*
X199067Y751600D01*
X199533Y751683D01*
X199933Y751933D01*
X200200Y752267D01*
G01X202967Y751600D02*
Y754933D01*
G01Y754100D02*
X203233Y754517D01*
X203633Y754850D01*
X204167Y754933D01*
X204633Y754850D01*
X205033Y754517D01*
X205233Y753933D01*
Y751600D01*
G01X208067Y754933D02*
Y752600D01*
X208333Y752017D01*
X208733Y751683D01*
X209200Y751600D01*
X209667Y751683D01*
X210067Y752017D01*
X210333Y752600D01*
G01Y751600D02*
Y754933D01*
G01X215500Y751600D02*
Y754933D01*
G01Y754350D02*
X215233Y754683D01*
X214833Y754850D01*
X214367Y754933D01*
X213900Y754767D01*
X213500Y754433D01*
X213233Y753933D01*
X213100Y753267D01*
X213233Y752600D01*
X213500Y752100D01*
X213900Y751767D01*
X214367Y751600D01*
X214833Y751683D01*
X215233Y751933D01*
X215500Y752267D01*
G01X219400Y751600D02*
Y756600D01*
G01X70700Y765600D02*
X72300D01*
G01X71500D02*
Y760600D01*
G01X70700D02*
X72300D01*
G01X75267D02*
Y765600D01*
X76867D01*
X77400Y765350D01*
X77800Y764767D01*
X77933Y764100D01*
X77800Y763433D01*
X77467Y762933D01*
X76867Y762683D01*
X75267D01*
G01X83167Y765183D02*
X82767Y765433D01*
X82300Y765600D01*
X81767D01*
X81167Y765350D01*
X80700Y764933D01*
X80367Y764433D01*
X80100Y763600D01*
X80033Y762850D01*
X80167Y762100D01*
X80367Y761600D01*
X80767Y761100D01*
X81233Y760767D01*
X81700Y760600D01*
X82167D01*
X82633Y760767D01*
X83033Y761017D01*
X83367Y761350D01*
G01X85933Y762267D02*
X87667D01*
G01X90633Y762683D02*
X91100Y763267D01*
X91500Y763600D01*
X92033Y763767D01*
X92500Y763600D01*
X92833Y763267D01*
X93100Y762767D01*
X93167Y762183D01*
X93100Y761683D01*
X92833Y761183D01*
X92433Y760767D01*
X91967Y760600D01*
X91433Y760767D01*
X90967Y761267D01*
X90700Y762017D01*
X90633Y762850D01*
X90767Y763933D01*
X90967Y764517D01*
X91300Y765100D01*
X91767Y765517D01*
X92233Y765600D01*
X92700Y765433D01*
X93033Y765017D01*
G01X97000Y765600D02*
X96467Y765433D01*
X96067Y765017D01*
X95800Y764517D01*
X95600Y763850D01*
X95533Y763100D01*
X95600Y762350D01*
X95800Y761683D01*
X96067Y761183D01*
X96467Y760767D01*
X97000Y760600D01*
X97533Y760767D01*
X97933Y761183D01*
X98200Y761683D01*
X98400Y762350D01*
X98467Y763100D01*
X98400Y763850D01*
X98200Y764517D01*
X97933Y765017D01*
X97533Y765433D01*
X97000Y765600D01*
G01X102100Y760600D02*
Y765600D01*
X101300Y764600D01*
G01Y760600D02*
X102900D01*
G01X105933Y762683D02*
X106400Y763267D01*
X106800Y763600D01*
X107333Y763767D01*
X107800Y763600D01*
X108133Y763267D01*
X108400Y762767D01*
X108467Y762183D01*
X108400Y761683D01*
X108133Y761183D01*
X107733Y760767D01*
X107267Y760600D01*
X106733Y760767D01*
X106267Y761267D01*
X106000Y762017D01*
X105933Y762850D01*
X106067Y763933D01*
X106267Y764517D01*
X106600Y765100D01*
X107067Y765517D01*
X107533Y765600D01*
X108000Y765433D01*
X108333Y765017D01*
G01X117400Y760600D02*
X116867Y760683D01*
X116400Y761017D01*
X116000Y761517D01*
X115733Y762100D01*
X115600Y762767D01*
Y763433D01*
X115733Y764100D01*
X116000Y764683D01*
X116400Y765183D01*
X116867Y765517D01*
X117400Y765600D01*
X117933Y765517D01*
X118400Y765183D01*
X118800Y764683D01*
X119067Y764100D01*
X119200Y763433D01*
Y762767D01*
X119067Y762100D01*
X118800Y761517D01*
X118400Y761017D01*
X117933Y760683D01*
X117400Y760600D01*
G01X117933Y761933D02*
X118733Y760600D01*
G01X121367Y763933D02*
Y761600D01*
X121633Y761017D01*
X122033Y760683D01*
X122500Y760600D01*
X122967Y760683D01*
X123367Y761017D01*
X123633Y761600D01*
G01Y760600D02*
Y763933D01*
G01X128800Y760600D02*
Y763933D01*
G01Y763350D02*
X128533Y763683D01*
X128133Y763850D01*
X127667Y763933D01*
X127200Y763767D01*
X126800Y763433D01*
X126533Y762933D01*
X126400Y762267D01*
X126533Y761600D01*
X126800Y761100D01*
X127200Y760767D01*
X127667Y760600D01*
X128133Y760683D01*
X128533Y760933D01*
X128800Y761267D01*
G01X132700Y760600D02*
Y765600D01*
G01X137800Y763933D02*
Y760600D01*
G01Y765267D02*
X137667Y765350D01*
Y765517D01*
X137800Y765600D01*
X137933Y765517D01*
Y765350D01*
X137800Y765267D01*
G01X142500Y760600D02*
Y764850D01*
X142633Y765267D01*
X142900Y765517D01*
X143300Y765600D01*
X143700Y765433D01*
X143900Y765017D01*
G01X143100Y763600D02*
X141767D01*
G01X148000Y763933D02*
Y760600D01*
G01Y765267D02*
X147867Y765350D01*
Y765517D01*
X148000Y765600D01*
X148133Y765517D01*
Y765350D01*
X148000Y765267D01*
G01X154167Y763517D02*
X153700Y763850D01*
X153300Y763933D01*
X152767Y763767D01*
X152367Y763433D01*
X152100Y762850D01*
X152033Y762267D01*
X152100Y761683D01*
X152367Y761183D01*
X152767Y760767D01*
X153300Y760600D01*
X153767Y760767D01*
X154167Y761100D01*
G01X159400Y760600D02*
Y763933D01*
G01Y763350D02*
X159133Y763683D01*
X158733Y763850D01*
X158267Y763933D01*
X157800Y763767D01*
X157400Y763433D01*
X157133Y762933D01*
X157000Y762267D01*
X157133Y761600D01*
X157400Y761100D01*
X157800Y760767D01*
X158267Y760600D01*
X158733Y760683D01*
X159133Y760933D01*
X159400Y761267D01*
G01X163300Y765600D02*
Y760600D01*
G01X162367Y763933D02*
X164233D01*
G01X168400D02*
Y760600D01*
G01Y765267D02*
X168267Y765350D01*
Y765517D01*
X168400Y765600D01*
X168533Y765517D01*
Y765350D01*
X168400Y765267D01*
G01X173500Y760600D02*
X173100Y760683D01*
X172700Y761017D01*
X172433Y761600D01*
X172300Y762267D01*
X172433Y762933D01*
X172700Y763517D01*
X173100Y763850D01*
X173500Y763933D01*
X173900Y763850D01*
X174300Y763517D01*
X174567Y762933D01*
X174633Y762267D01*
X174567Y761600D01*
X174300Y761017D01*
X173900Y760683D01*
X173500Y760600D01*
G01X177467D02*
Y763933D01*
G01Y763100D02*
X177733Y763517D01*
X178133Y763850D01*
X178667Y763933D01*
X179133Y763850D01*
X179533Y763517D01*
X179733Y762933D01*
Y760600D01*
G01X190800Y758933D02*
X187467Y763933D01*
Y764767D01*
X188133Y765600D01*
X188800D01*
X189467Y764767D01*
Y763933D01*
X188800Y763100D01*
X187467Y762267D01*
X186800Y761433D01*
Y759767D01*
X187467Y758933D01*
X189467D01*
X190800Y760600D01*
G01X197667D02*
Y765600D01*
X199267D01*
X199800Y765350D01*
X200200Y764767D01*
X200333Y764100D01*
X200200Y763433D01*
X199867Y762933D01*
X199267Y762683D01*
X197667D01*
G01X203100Y762850D02*
X205233D01*
X205033Y763433D01*
X204700Y763767D01*
X204233Y763933D01*
X203767Y763850D01*
X203367Y763600D01*
X203100Y763017D01*
X202967Y762517D01*
Y762017D01*
X203100Y761517D01*
X203433Y761017D01*
X203833Y760683D01*
X204300Y760600D01*
X204767Y760767D01*
X205233Y761267D01*
G01X208267Y760600D02*
Y763933D01*
G01Y763267D02*
X208600Y763600D01*
X208933Y763850D01*
X209400Y763933D01*
X209733Y763850D01*
X210133Y763600D01*
G01X213900Y760600D02*
Y764850D01*
X214033Y765267D01*
X214300Y765517D01*
X214700Y765600D01*
X215100Y765433D01*
X215300Y765017D01*
G01X214500Y763600D02*
X213167D01*
G01X219400Y760600D02*
X219000Y760683D01*
X218600Y761017D01*
X218333Y761600D01*
X218200Y762267D01*
X218333Y762933D01*
X218600Y763517D01*
X219000Y763850D01*
X219400Y763933D01*
X219800Y763850D01*
X220200Y763517D01*
X220467Y762933D01*
X220533Y762267D01*
X220467Y761600D01*
X220200Y761017D01*
X219800Y760683D01*
X219400Y760600D01*
G01X223567D02*
Y763933D01*
G01Y763267D02*
X223900Y763600D01*
X224233Y763850D01*
X224700Y763933D01*
X225033Y763850D01*
X225433Y763600D01*
G01X227600Y760600D02*
Y763933D01*
G01Y763017D02*
X227800Y763433D01*
X228133Y763767D01*
X228600Y763933D01*
X229067Y763767D01*
X229400Y763433D01*
X229600Y763017D01*
Y760600D01*
G01Y763017D02*
X229800Y763433D01*
X230133Y763767D01*
X230600Y763933D01*
X231067Y763767D01*
X231400Y763433D01*
X231600Y762933D01*
Y760600D01*
G01X235900D02*
Y763933D01*
G01Y763350D02*
X235633Y763683D01*
X235233Y763850D01*
X234767Y763933D01*
X234300Y763767D01*
X233900Y763433D01*
X233633Y762933D01*
X233500Y762267D01*
X233633Y761600D01*
X233900Y761100D01*
X234300Y760767D01*
X234767Y760600D01*
X235233Y760683D01*
X235633Y760933D01*
X235900Y761267D01*
G01X238667Y760600D02*
Y763933D01*
G01Y763100D02*
X238933Y763517D01*
X239333Y763850D01*
X239867Y763933D01*
X240333Y763850D01*
X240733Y763517D01*
X240933Y762933D01*
Y760600D01*
G01X245967Y763517D02*
X245500Y763850D01*
X245100Y763933D01*
X244567Y763767D01*
X244167Y763433D01*
X243900Y762850D01*
X243833Y762267D01*
X243900Y761683D01*
X244167Y761183D01*
X244567Y760767D01*
X245100Y760600D01*
X245567Y760767D01*
X245967Y761100D01*
G01X249000Y762850D02*
X251133D01*
X250933Y763433D01*
X250600Y763767D01*
X250133Y763933D01*
X249667Y763850D01*
X249267Y763600D01*
X249000Y763017D01*
X248867Y762517D01*
Y762017D01*
X249000Y761517D01*
X249333Y761017D01*
X249733Y760683D01*
X250200Y760600D01*
X250667Y760767D01*
X251133Y761267D01*
G01X258800D02*
X259333Y760850D01*
X259933Y760600D01*
X260467D01*
X261000Y760850D01*
X261400Y761267D01*
X261600Y761850D01*
X261467Y762433D01*
X261133Y762933D01*
X260533Y763267D01*
X259733Y763433D01*
X259267Y763767D01*
X259067Y764350D01*
X259200Y764933D01*
X259533Y765350D01*
X260000Y765600D01*
X260467D01*
X260933Y765433D01*
X261333Y765017D01*
G01X264100Y758933D02*
Y763933D01*
G01Y763183D02*
X264433Y763600D01*
X264767Y763850D01*
X265300Y763933D01*
X265767Y763850D01*
X266233Y763433D01*
X266433Y762850D01*
X266500Y762267D01*
X266433Y761683D01*
X266233Y761100D01*
X265833Y760767D01*
X265300Y760600D01*
X264833Y760683D01*
X264367Y760933D01*
X264100Y761267D01*
G01X269400Y762850D02*
X271533D01*
X271333Y763433D01*
X271000Y763767D01*
X270533Y763933D01*
X270067Y763850D01*
X269667Y763600D01*
X269400Y763017D01*
X269267Y762517D01*
Y762017D01*
X269400Y761517D01*
X269733Y761017D01*
X270133Y760683D01*
X270600Y760600D01*
X271067Y760767D01*
X271533Y761267D01*
G01X276567Y763517D02*
X276100Y763850D01*
X275700Y763933D01*
X275167Y763767D01*
X274767Y763433D01*
X274500Y762850D01*
X274433Y762267D01*
X274500Y761683D01*
X274767Y761183D01*
X275167Y760767D01*
X275700Y760600D01*
X276167Y760767D01*
X276567Y761100D01*
G01X280600Y763933D02*
Y760600D01*
G01Y765267D02*
X280467Y765350D01*
Y765517D01*
X280600Y765600D01*
X280733Y765517D01*
Y765350D01*
X280600Y765267D01*
G01X285300Y760600D02*
Y764850D01*
X285433Y765267D01*
X285700Y765517D01*
X286100Y765600D01*
X286500Y765433D01*
X286700Y765017D01*
G01X285900Y763600D02*
X284567D01*
G01X290800Y763933D02*
Y760600D01*
G01Y765267D02*
X290667Y765350D01*
Y765517D01*
X290800Y765600D01*
X290933Y765517D01*
Y765350D01*
X290800Y765267D01*
G01X296967Y763517D02*
X296500Y763850D01*
X296100Y763933D01*
X295567Y763767D01*
X295167Y763433D01*
X294900Y762850D01*
X294833Y762267D01*
X294900Y761683D01*
X295167Y761183D01*
X295567Y760767D01*
X296100Y760600D01*
X296567Y760767D01*
X296967Y761100D01*
G01X302200Y760600D02*
Y763933D01*
G01Y763350D02*
X301933Y763683D01*
X301533Y763850D01*
X301067Y763933D01*
X300600Y763767D01*
X300200Y763433D01*
X299933Y762933D01*
X299800Y762267D01*
X299933Y761600D01*
X300200Y761100D01*
X300600Y760767D01*
X301067Y760600D01*
X301533Y760683D01*
X301933Y760933D01*
X302200Y761267D01*
G01X306100Y765600D02*
Y760600D01*
G01X305167Y763933D02*
X307033D01*
G01X311200D02*
Y760600D01*
G01Y765267D02*
X311067Y765350D01*
Y765517D01*
X311200Y765600D01*
X311333Y765517D01*
Y765350D01*
X311200Y765267D01*
G01X316300Y760600D02*
X315900Y760683D01*
X315500Y761017D01*
X315233Y761600D01*
X315100Y762267D01*
X315233Y762933D01*
X315500Y763517D01*
X315900Y763850D01*
X316300Y763933D01*
X316700Y763850D01*
X317100Y763517D01*
X317367Y762933D01*
X317433Y762267D01*
X317367Y761600D01*
X317100Y761017D01*
X316700Y760683D01*
X316300Y760600D01*
G01X320267D02*
Y763933D01*
G01Y763100D02*
X320533Y763517D01*
X320933Y763850D01*
X321467Y763933D01*
X321933Y763850D01*
X322333Y763517D01*
X322533Y762933D01*
Y760600D01*
G01X331200D02*
Y764850D01*
X331333Y765267D01*
X331600Y765517D01*
X332000Y765600D01*
X332400Y765433D01*
X332600Y765017D01*
G01X331800Y763600D02*
X330467D01*
G01X336700Y760600D02*
X336300Y760683D01*
X335900Y761017D01*
X335633Y761600D01*
X335500Y762267D01*
X335633Y762933D01*
X335900Y763517D01*
X336300Y763850D01*
X336700Y763933D01*
X337100Y763850D01*
X337500Y763517D01*
X337767Y762933D01*
X337833Y762267D01*
X337767Y761600D01*
X337500Y761017D01*
X337100Y760683D01*
X336700Y760600D01*
G01X340867D02*
Y763933D01*
G01Y763267D02*
X341200Y763600D01*
X341533Y763850D01*
X342000Y763933D01*
X342333Y763850D01*
X342733Y763600D01*
G01X350600Y760600D02*
Y765600D01*
G01X353400D02*
Y760600D01*
G01Y763100D02*
X350600D01*
G01X357100Y763933D02*
Y760600D01*
G01Y765267D02*
X356967Y765350D01*
Y765517D01*
X357100Y765600D01*
X357233Y765517D01*
Y765350D01*
X357100Y765267D01*
G01X361267Y759350D02*
X361733Y759017D01*
X362267Y758933D01*
X362733Y759017D01*
X363133Y759433D01*
X363400Y760017D01*
Y763933D01*
G01Y763267D02*
X363133Y763600D01*
X362733Y763850D01*
X362267Y763933D01*
X361733Y763767D01*
X361400Y763433D01*
X361133Y762850D01*
X361000Y762267D01*
X361067Y761767D01*
X361333Y761183D01*
X361733Y760767D01*
X362267Y760600D01*
X362667Y760683D01*
X363133Y761017D01*
X363400Y761350D01*
G01X366167Y760600D02*
Y765600D01*
G01Y763183D02*
X366500Y763600D01*
X366833Y763850D01*
X367367Y763933D01*
X367767Y763850D01*
X368233Y763517D01*
X368433Y763017D01*
Y760600D01*
G01X376033D02*
Y765600D01*
X377367D01*
X377900Y765350D01*
X378300Y765017D01*
X378633Y764517D01*
X378900Y763933D01*
X378967Y763100D01*
X378900Y762267D01*
X378633Y761683D01*
X378300Y761183D01*
X377900Y760850D01*
X377367Y760600D01*
X376033D01*
G01X381600Y762850D02*
X383733D01*
X383533Y763433D01*
X383200Y763767D01*
X382733Y763933D01*
X382267Y763850D01*
X381867Y763600D01*
X381600Y763017D01*
X381467Y762517D01*
Y762017D01*
X381600Y761517D01*
X381933Y761017D01*
X382333Y760683D01*
X382800Y760600D01*
X383267Y760767D01*
X383733Y761267D01*
G01X386567Y760600D02*
Y763933D01*
G01Y763100D02*
X386833Y763517D01*
X387233Y763850D01*
X387767Y763933D01*
X388233Y763850D01*
X388633Y763517D01*
X388833Y762933D01*
Y760600D01*
G01X391800Y761183D02*
X392133Y760850D01*
X392600Y760600D01*
X393000D01*
X393400Y760767D01*
X393667Y761017D01*
X393800Y761350D01*
X393733Y761850D01*
X393467Y762100D01*
X392267Y762600D01*
X392000Y763183D01*
X392133Y763600D01*
X392400Y763850D01*
X392800Y763933D01*
X393200Y763850D01*
X393600Y763600D01*
G01X397900Y763933D02*
Y760600D01*
G01Y765267D02*
X397767Y765350D01*
Y765517D01*
X397900Y765600D01*
X398033Y765517D01*
Y765350D01*
X397900Y765267D01*
G01X403000Y765600D02*
Y760600D01*
G01X402067Y763933D02*
X403933D01*
G01X406700Y759100D02*
X407100Y758933D01*
X407633Y759100D01*
X407967Y759433D01*
X408233Y759850D01*
X408633Y761183D01*
X409500Y763933D01*
G01X407367D02*
X408633Y761183D01*
G01X417500Y765600D02*
X419100D01*
G01X418300D02*
Y760600D01*
G01X417500D02*
X419100D01*
G01X422267D02*
Y763933D01*
G01Y763100D02*
X422533Y763517D01*
X422933Y763850D01*
X423467Y763933D01*
X423933Y763850D01*
X424333Y763517D01*
X424533Y762933D01*
Y760600D01*
G01X428500Y765600D02*
Y760600D01*
G01X427567Y763933D02*
X429433D01*
G01X432600Y762850D02*
X434733D01*
X434533Y763433D01*
X434200Y763767D01*
X433733Y763933D01*
X433267Y763850D01*
X432867Y763600D01*
X432600Y763017D01*
X432467Y762517D01*
Y762017D01*
X432600Y761517D01*
X432933Y761017D01*
X433333Y760683D01*
X433800Y760600D01*
X434267Y760767D01*
X434733Y761267D01*
G01X437767Y760600D02*
Y763933D01*
G01Y763267D02*
X438100Y763600D01*
X438433Y763850D01*
X438900Y763933D01*
X439233Y763850D01*
X439633Y763600D01*
G01X444867Y763517D02*
X444400Y763850D01*
X444000Y763933D01*
X443467Y763767D01*
X443067Y763433D01*
X442800Y762850D01*
X442733Y762267D01*
X442800Y761683D01*
X443067Y761183D01*
X443467Y760767D01*
X444000Y760600D01*
X444467Y760767D01*
X444867Y761100D01*
G01X448900Y760600D02*
X448500Y760683D01*
X448100Y761017D01*
X447833Y761600D01*
X447700Y762267D01*
X447833Y762933D01*
X448100Y763517D01*
X448500Y763850D01*
X448900Y763933D01*
X449300Y763850D01*
X449700Y763517D01*
X449967Y762933D01*
X450033Y762267D01*
X449967Y761600D01*
X449700Y761017D01*
X449300Y760683D01*
X448900Y760600D01*
G01X452867D02*
Y763933D01*
G01Y763100D02*
X453133Y763517D01*
X453533Y763850D01*
X454067Y763933D01*
X454533Y763850D01*
X454933Y763517D01*
X455133Y762933D01*
Y760600D01*
G01X457967D02*
Y763933D01*
G01Y763100D02*
X458233Y763517D01*
X458633Y763850D01*
X459167Y763933D01*
X459633Y763850D01*
X460033Y763517D01*
X460233Y762933D01*
Y760600D01*
G01X463200Y762850D02*
X465333D01*
X465133Y763433D01*
X464800Y763767D01*
X464333Y763933D01*
X463867Y763850D01*
X463467Y763600D01*
X463200Y763017D01*
X463067Y762517D01*
Y762017D01*
X463200Y761517D01*
X463533Y761017D01*
X463933Y760683D01*
X464400Y760600D01*
X464867Y760767D01*
X465333Y761267D01*
G01X470367Y763517D02*
X469900Y763850D01*
X469500Y763933D01*
X468967Y763767D01*
X468567Y763433D01*
X468300Y762850D01*
X468233Y762267D01*
X468300Y761683D01*
X468567Y761183D01*
X468967Y760767D01*
X469500Y760600D01*
X469967Y760767D01*
X470367Y761100D01*
G01X474400Y765600D02*
Y760600D01*
G01X473467Y763933D02*
X475333D01*
G01X479167Y758933D02*
X478500Y759767D01*
X478167Y760600D01*
Y763933D01*
X478500Y764767D01*
X479167Y765600D01*
G01X483200Y760600D02*
Y765600D01*
G01X486000D02*
Y760600D01*
G01Y763100D02*
X483200D01*
G01X488233Y760600D02*
Y765600D01*
X489567D01*
X490100Y765350D01*
X490500Y765017D01*
X490833Y764517D01*
X491100Y763933D01*
X491167Y763100D01*
X491100Y762267D01*
X490833Y761683D01*
X490500Y761183D01*
X490100Y760850D01*
X489567Y760600D01*
X488233D01*
G01X494000Y765600D02*
X495600D01*
G01X494800D02*
Y760600D01*
G01X494000D02*
X495600D01*
G01X500233Y758933D02*
X500900Y759767D01*
X501233Y760600D01*
Y763933D01*
X500900Y764767D01*
X500233Y765600D01*
G01X508767D02*
Y760600D01*
X511433D01*
G01X516400D02*
Y763933D01*
G01Y763350D02*
X516133Y763683D01*
X515733Y763850D01*
X515267Y763933D01*
X514800Y763767D01*
X514400Y763433D01*
X514133Y762933D01*
X514000Y762267D01*
X514133Y761600D01*
X514400Y761100D01*
X514800Y760767D01*
X515267Y760600D01*
X515733Y760683D01*
X516133Y760933D01*
X516400Y761267D01*
G01X518900Y759100D02*
X519300Y758933D01*
X519833Y759100D01*
X520167Y759433D01*
X520433Y759850D01*
X520833Y761183D01*
X521700Y763933D01*
G01X519567D02*
X520833Y761183D01*
G01X524400Y762850D02*
X526533D01*
X526333Y763433D01*
X526000Y763767D01*
X525533Y763933D01*
X525067Y763850D01*
X524667Y763600D01*
X524400Y763017D01*
X524267Y762517D01*
Y762017D01*
X524400Y761517D01*
X524733Y761017D01*
X525133Y760683D01*
X525600Y760600D01*
X526067Y760767D01*
X526533Y761267D01*
G01X529567Y760600D02*
Y763933D01*
G01Y763267D02*
X529900Y763600D01*
X530233Y763850D01*
X530700Y763933D01*
X531033Y763850D01*
X531433Y763600D01*
G01X534600Y761183D02*
X534933Y760850D01*
X535400Y760600D01*
X535800D01*
X536200Y760767D01*
X536467Y761017D01*
X536600Y761350D01*
X536533Y761850D01*
X536267Y762100D01*
X535067Y762600D01*
X534800Y763183D01*
X534933Y763600D01*
X535200Y763850D01*
X535600Y763933D01*
X536000Y763850D01*
X536400Y763600D01*
G01X545800Y760600D02*
X545400Y760683D01*
X545000Y761017D01*
X544733Y761600D01*
X544600Y762267D01*
X544733Y762933D01*
X545000Y763517D01*
X545400Y763850D01*
X545800Y763933D01*
X546200Y763850D01*
X546600Y763517D01*
X546867Y762933D01*
X546933Y762267D01*
X546867Y761600D01*
X546600Y761017D01*
X546200Y760683D01*
X545800Y760600D01*
G01X549967D02*
Y763933D01*
G01Y763267D02*
X550300Y763600D01*
X550633Y763850D01*
X551100Y763933D01*
X551433Y763850D01*
X551833Y763600D01*
G01X561633Y763267D02*
X561900Y763517D01*
X562100Y763933D01*
X562233Y764517D01*
X562100Y765017D01*
X561833Y765350D01*
X561367Y765600D01*
X559567D01*
Y760600D01*
X561767D01*
X562233Y760933D01*
X562500Y761433D01*
X562633Y762017D01*
X562500Y762600D01*
X562100Y763100D01*
X561633Y763267D01*
X559567D01*
G01X566200Y760600D02*
X565800Y760683D01*
X565400Y761017D01*
X565133Y761600D01*
X565000Y762267D01*
X565133Y762933D01*
X565400Y763517D01*
X565800Y763850D01*
X566200Y763933D01*
X566600Y763850D01*
X567000Y763517D01*
X567267Y762933D01*
X567333Y762267D01*
X567267Y761600D01*
X567000Y761017D01*
X566600Y760683D01*
X566200Y760600D01*
G01X572500D02*
Y763933D01*
G01Y763350D02*
X572233Y763683D01*
X571833Y763850D01*
X571367Y763933D01*
X570900Y763767D01*
X570500Y763433D01*
X570233Y762933D01*
X570100Y762267D01*
X570233Y761600D01*
X570500Y761100D01*
X570900Y760767D01*
X571367Y760600D01*
X571833Y760683D01*
X572233Y760933D01*
X572500Y761267D01*
G01X575467Y760600D02*
Y763933D01*
G01Y763267D02*
X575800Y763600D01*
X576133Y763850D01*
X576600Y763933D01*
X576933Y763850D01*
X577333Y763600D01*
G01X582700Y765600D02*
Y760600D01*
G01Y761350D02*
X582433Y760933D01*
X582033Y760683D01*
X581567Y760600D01*
X581033Y760767D01*
X580633Y761183D01*
X580367Y761683D01*
X580300Y762267D01*
X580367Y762850D01*
X580633Y763350D01*
X581033Y763767D01*
X581567Y763933D01*
X582033Y763850D01*
X582367Y763683D01*
X582700Y763350D01*
G01X585600Y761183D02*
X585933Y760850D01*
X586400Y760600D01*
X586800D01*
X587200Y760767D01*
X587467Y761017D01*
X587600Y761350D01*
X587533Y761850D01*
X587267Y762100D01*
X586067Y762600D01*
X585800Y763183D01*
X585933Y763600D01*
X586200Y763850D01*
X586600Y763933D01*
X587000Y763850D01*
X587400Y763600D01*
G01X592033Y758933D02*
X592700Y759767D01*
X593033Y760600D01*
Y763933D01*
X592700Y764767D01*
X592033Y765600D01*
G01X70700Y774600D02*
X72300D01*
G01X71500D02*
Y769600D01*
G01X70700D02*
X72300D01*
G01X75267D02*
Y774600D01*
X76867D01*
X77400Y774350D01*
X77800Y773767D01*
X77933Y773100D01*
X77800Y772433D01*
X77467Y771933D01*
X76867Y771683D01*
X75267D01*
G01X83167Y774183D02*
X82767Y774433D01*
X82300Y774600D01*
X81767D01*
X81167Y774350D01*
X80700Y773933D01*
X80367Y773433D01*
X80100Y772600D01*
X80033Y771850D01*
X80167Y771100D01*
X80367Y770600D01*
X80767Y770100D01*
X81233Y769767D01*
X81700Y769600D01*
X82167D01*
X82633Y769767D01*
X83033Y770017D01*
X83367Y770350D01*
G01X85933Y771267D02*
X87667D01*
G01X90633Y771683D02*
X91100Y772267D01*
X91500Y772600D01*
X92033Y772767D01*
X92500Y772600D01*
X92833Y772267D01*
X93100Y771767D01*
X93167Y771183D01*
X93100Y770683D01*
X92833Y770183D01*
X92433Y769767D01*
X91967Y769600D01*
X91433Y769767D01*
X90967Y770267D01*
X90700Y771017D01*
X90633Y771850D01*
X90767Y772933D01*
X90967Y773517D01*
X91300Y774100D01*
X91767Y774517D01*
X92233Y774600D01*
X92700Y774433D01*
X93033Y774017D01*
G01X97000Y774600D02*
X96467Y774433D01*
X96067Y774017D01*
X95800Y773517D01*
X95600Y772850D01*
X95533Y772100D01*
X95600Y771350D01*
X95800Y770683D01*
X96067Y770183D01*
X96467Y769767D01*
X97000Y769600D01*
X97533Y769767D01*
X97933Y770183D01*
X98200Y770683D01*
X98400Y771350D01*
X98467Y772100D01*
X98400Y772850D01*
X98200Y773517D01*
X97933Y774017D01*
X97533Y774433D01*
X97000Y774600D01*
G01X102100Y769600D02*
Y774600D01*
X101300Y773600D01*
G01Y769600D02*
X102900D01*
G01X105933Y773767D02*
X106333Y774267D01*
X106800Y774517D01*
X107333Y774600D01*
X108000Y774433D01*
X108467Y774017D01*
X108600Y773517D01*
X108533Y773017D01*
X108267Y772600D01*
X106933Y771767D01*
X106333Y771183D01*
X105933Y770350D01*
X105800Y769600D01*
X108600D01*
G01X117400D02*
X116867Y769683D01*
X116400Y770017D01*
X116000Y770517D01*
X115733Y771100D01*
X115600Y771767D01*
Y772433D01*
X115733Y773100D01*
X116000Y773683D01*
X116400Y774183D01*
X116867Y774517D01*
X117400Y774600D01*
X117933Y774517D01*
X118400Y774183D01*
X118800Y773683D01*
X119067Y773100D01*
X119200Y772433D01*
Y771767D01*
X119067Y771100D01*
X118800Y770517D01*
X118400Y770017D01*
X117933Y769683D01*
X117400Y769600D01*
G01X117933Y770933D02*
X118733Y769600D01*
G01X121367Y772933D02*
Y770600D01*
X121633Y770017D01*
X122033Y769683D01*
X122500Y769600D01*
X122967Y769683D01*
X123367Y770017D01*
X123633Y770600D01*
G01Y769600D02*
Y772933D01*
G01X128800Y769600D02*
Y772933D01*
G01Y772350D02*
X128533Y772683D01*
X128133Y772850D01*
X127667Y772933D01*
X127200Y772767D01*
X126800Y772433D01*
X126533Y771933D01*
X126400Y771267D01*
X126533Y770600D01*
X126800Y770100D01*
X127200Y769767D01*
X127667Y769600D01*
X128133Y769683D01*
X128533Y769933D01*
X128800Y770267D01*
G01X132700Y769600D02*
Y774600D01*
G01X137800Y772933D02*
Y769600D01*
G01Y774267D02*
X137667Y774350D01*
Y774517D01*
X137800Y774600D01*
X137933Y774517D01*
Y774350D01*
X137800Y774267D01*
G01X142500Y769600D02*
Y773850D01*
X142633Y774267D01*
X142900Y774517D01*
X143300Y774600D01*
X143700Y774433D01*
X143900Y774017D01*
G01X143100Y772600D02*
X141767D01*
G01X148000Y772933D02*
Y769600D01*
G01Y774267D02*
X147867Y774350D01*
Y774517D01*
X148000Y774600D01*
X148133Y774517D01*
Y774350D01*
X148000Y774267D01*
G01X154167Y772517D02*
X153700Y772850D01*
X153300Y772933D01*
X152767Y772767D01*
X152367Y772433D01*
X152100Y771850D01*
X152033Y771267D01*
X152100Y770683D01*
X152367Y770183D01*
X152767Y769767D01*
X153300Y769600D01*
X153767Y769767D01*
X154167Y770100D01*
G01X159400Y769600D02*
Y772933D01*
G01Y772350D02*
X159133Y772683D01*
X158733Y772850D01*
X158267Y772933D01*
X157800Y772767D01*
X157400Y772433D01*
X157133Y771933D01*
X157000Y771267D01*
X157133Y770600D01*
X157400Y770100D01*
X157800Y769767D01*
X158267Y769600D01*
X158733Y769683D01*
X159133Y769933D01*
X159400Y770267D01*
G01X163300Y774600D02*
Y769600D01*
G01X162367Y772933D02*
X164233D01*
G01X168400D02*
Y769600D01*
G01Y774267D02*
X168267Y774350D01*
Y774517D01*
X168400Y774600D01*
X168533Y774517D01*
Y774350D01*
X168400Y774267D01*
G01X173500Y769600D02*
X173100Y769683D01*
X172700Y770017D01*
X172433Y770600D01*
X172300Y771267D01*
X172433Y771933D01*
X172700Y772517D01*
X173100Y772850D01*
X173500Y772933D01*
X173900Y772850D01*
X174300Y772517D01*
X174567Y771933D01*
X174633Y771267D01*
X174567Y770600D01*
X174300Y770017D01*
X173900Y769683D01*
X173500Y769600D01*
G01X177467D02*
Y772933D01*
G01Y772100D02*
X177733Y772517D01*
X178133Y772850D01*
X178667Y772933D01*
X179133Y772850D01*
X179533Y772517D01*
X179733Y771933D01*
Y769600D01*
G01X190000D02*
Y772933D01*
G01Y772350D02*
X189733Y772683D01*
X189333Y772850D01*
X188867Y772933D01*
X188400Y772767D01*
X188000Y772433D01*
X187733Y771933D01*
X187600Y771267D01*
X187733Y770600D01*
X188000Y770100D01*
X188400Y769767D01*
X188867Y769600D01*
X189333Y769683D01*
X189733Y769933D01*
X190000Y770267D01*
G01X192767Y769600D02*
Y772933D01*
G01Y772100D02*
X193033Y772517D01*
X193433Y772850D01*
X193967Y772933D01*
X194433Y772850D01*
X194833Y772517D01*
X195033Y771933D01*
Y769600D01*
G01X200200Y774600D02*
Y769600D01*
G01Y770350D02*
X199933Y769933D01*
X199533Y769683D01*
X199067Y769600D01*
X198533Y769767D01*
X198133Y770183D01*
X197867Y770683D01*
X197800Y771267D01*
X197867Y771850D01*
X198133Y772350D01*
X198533Y772767D01*
X199067Y772933D01*
X199533Y772850D01*
X199867Y772683D01*
X200200Y772350D01*
G01X207867Y769600D02*
Y774600D01*
X209467D01*
X210000Y774350D01*
X210400Y773767D01*
X210533Y773100D01*
X210400Y772433D01*
X210067Y771933D01*
X209467Y771683D01*
X207867D01*
G01X213300Y771850D02*
X215433D01*
X215233Y772433D01*
X214900Y772767D01*
X214433Y772933D01*
X213967Y772850D01*
X213567Y772600D01*
X213300Y772017D01*
X213167Y771517D01*
Y771017D01*
X213300Y770517D01*
X213633Y770017D01*
X214033Y769683D01*
X214500Y769600D01*
X214967Y769767D01*
X215433Y770267D01*
G01X218467Y769600D02*
Y772933D01*
G01Y772267D02*
X218800Y772600D01*
X219133Y772850D01*
X219600Y772933D01*
X219933Y772850D01*
X220333Y772600D01*
G01X224100Y769600D02*
Y773850D01*
X224233Y774267D01*
X224500Y774517D01*
X224900Y774600D01*
X225300Y774433D01*
X225500Y774017D01*
G01X224700Y772600D02*
X223367D01*
G01X229600Y769600D02*
X229200Y769683D01*
X228800Y770017D01*
X228533Y770600D01*
X228400Y771267D01*
X228533Y771933D01*
X228800Y772517D01*
X229200Y772850D01*
X229600Y772933D01*
X230000Y772850D01*
X230400Y772517D01*
X230667Y771933D01*
X230733Y771267D01*
X230667Y770600D01*
X230400Y770017D01*
X230000Y769683D01*
X229600Y769600D01*
G01X233767D02*
Y772933D01*
G01Y772267D02*
X234100Y772600D01*
X234433Y772850D01*
X234900Y772933D01*
X235233Y772850D01*
X235633Y772600D01*
G01X237800Y769600D02*
Y772933D01*
G01Y772017D02*
X238000Y772433D01*
X238333Y772767D01*
X238800Y772933D01*
X239267Y772767D01*
X239600Y772433D01*
X239800Y772017D01*
Y769600D01*
G01Y772017D02*
X240000Y772433D01*
X240333Y772767D01*
X240800Y772933D01*
X241267Y772767D01*
X241600Y772433D01*
X241800Y771933D01*
Y769600D01*
G01X246100D02*
Y772933D01*
G01Y772350D02*
X245833Y772683D01*
X245433Y772850D01*
X244967Y772933D01*
X244500Y772767D01*
X244100Y772433D01*
X243833Y771933D01*
X243700Y771267D01*
X243833Y770600D01*
X244100Y770100D01*
X244500Y769767D01*
X244967Y769600D01*
X245433Y769683D01*
X245833Y769933D01*
X246100Y770267D01*
G01X248867Y769600D02*
Y772933D01*
G01Y772100D02*
X249133Y772517D01*
X249533Y772850D01*
X250067Y772933D01*
X250533Y772850D01*
X250933Y772517D01*
X251133Y771933D01*
Y769600D01*
G01X256167Y772517D02*
X255700Y772850D01*
X255300Y772933D01*
X254767Y772767D01*
X254367Y772433D01*
X254100Y771850D01*
X254033Y771267D01*
X254100Y770683D01*
X254367Y770183D01*
X254767Y769767D01*
X255300Y769600D01*
X255767Y769767D01*
X256167Y770100D01*
G01X259200Y771850D02*
X261333D01*
X261133Y772433D01*
X260800Y772767D01*
X260333Y772933D01*
X259867Y772850D01*
X259467Y772600D01*
X259200Y772017D01*
X259067Y771517D01*
Y771017D01*
X259200Y770517D01*
X259533Y770017D01*
X259933Y769683D01*
X260400Y769600D01*
X260867Y769767D01*
X261333Y770267D01*
G01X269000D02*
X269533Y769850D01*
X270133Y769600D01*
X270667D01*
X271200Y769850D01*
X271600Y770267D01*
X271800Y770850D01*
X271667Y771433D01*
X271333Y771933D01*
X270733Y772267D01*
X269933Y772433D01*
X269467Y772767D01*
X269267Y773350D01*
X269400Y773933D01*
X269733Y774350D01*
X270200Y774600D01*
X270667D01*
X271133Y774433D01*
X271533Y774017D01*
G01X274300Y767933D02*
Y772933D01*
G01Y772183D02*
X274633Y772600D01*
X274967Y772850D01*
X275500Y772933D01*
X275967Y772850D01*
X276433Y772433D01*
X276633Y771850D01*
X276700Y771267D01*
X276633Y770683D01*
X276433Y770100D01*
X276033Y769767D01*
X275500Y769600D01*
X275033Y769683D01*
X274567Y769933D01*
X274300Y770267D01*
G01X279600Y771850D02*
X281733D01*
X281533Y772433D01*
X281200Y772767D01*
X280733Y772933D01*
X280267Y772850D01*
X279867Y772600D01*
X279600Y772017D01*
X279467Y771517D01*
Y771017D01*
X279600Y770517D01*
X279933Y770017D01*
X280333Y769683D01*
X280800Y769600D01*
X281267Y769767D01*
X281733Y770267D01*
G01X286767Y772517D02*
X286300Y772850D01*
X285900Y772933D01*
X285367Y772767D01*
X284967Y772433D01*
X284700Y771850D01*
X284633Y771267D01*
X284700Y770683D01*
X284967Y770183D01*
X285367Y769767D01*
X285900Y769600D01*
X286367Y769767D01*
X286767Y770100D01*
G01X290800Y772933D02*
Y769600D01*
G01Y774267D02*
X290667Y774350D01*
Y774517D01*
X290800Y774600D01*
X290933Y774517D01*
Y774350D01*
X290800Y774267D01*
G01X295500Y769600D02*
Y773850D01*
X295633Y774267D01*
X295900Y774517D01*
X296300Y774600D01*
X296700Y774433D01*
X296900Y774017D01*
G01X296100Y772600D02*
X294767D01*
G01X301000Y772933D02*
Y769600D01*
G01Y774267D02*
X300867Y774350D01*
Y774517D01*
X301000Y774600D01*
X301133Y774517D01*
Y774350D01*
X301000Y774267D01*
G01X307167Y772517D02*
X306700Y772850D01*
X306300Y772933D01*
X305767Y772767D01*
X305367Y772433D01*
X305100Y771850D01*
X305033Y771267D01*
X305100Y770683D01*
X305367Y770183D01*
X305767Y769767D01*
X306300Y769600D01*
X306767Y769767D01*
X307167Y770100D01*
G01X312400Y769600D02*
Y772933D01*
G01Y772350D02*
X312133Y772683D01*
X311733Y772850D01*
X311267Y772933D01*
X310800Y772767D01*
X310400Y772433D01*
X310133Y771933D01*
X310000Y771267D01*
X310133Y770600D01*
X310400Y770100D01*
X310800Y769767D01*
X311267Y769600D01*
X311733Y769683D01*
X312133Y769933D01*
X312400Y770267D01*
G01X316300Y774600D02*
Y769600D01*
G01X315367Y772933D02*
X317233D01*
G01X321400D02*
Y769600D01*
G01Y774267D02*
X321267Y774350D01*
Y774517D01*
X321400Y774600D01*
X321533Y774517D01*
Y774350D01*
X321400Y774267D01*
G01X326500Y769600D02*
X326100Y769683D01*
X325700Y770017D01*
X325433Y770600D01*
X325300Y771267D01*
X325433Y771933D01*
X325700Y772517D01*
X326100Y772850D01*
X326500Y772933D01*
X326900Y772850D01*
X327300Y772517D01*
X327567Y771933D01*
X327633Y771267D01*
X327567Y770600D01*
X327300Y770017D01*
X326900Y769683D01*
X326500Y769600D01*
G01X330467D02*
Y772933D01*
G01Y772100D02*
X330733Y772517D01*
X331133Y772850D01*
X331667Y772933D01*
X332133Y772850D01*
X332533Y772517D01*
X332733Y771933D01*
Y769600D01*
G01X341400D02*
Y773850D01*
X341533Y774267D01*
X341800Y774517D01*
X342200Y774600D01*
X342600Y774433D01*
X342800Y774017D01*
G01X342000Y772600D02*
X340667D01*
G01X346900Y769600D02*
X346500Y769683D01*
X346100Y770017D01*
X345833Y770600D01*
X345700Y771267D01*
X345833Y771933D01*
X346100Y772517D01*
X346500Y772850D01*
X346900Y772933D01*
X347300Y772850D01*
X347700Y772517D01*
X347967Y771933D01*
X348033Y771267D01*
X347967Y770600D01*
X347700Y770017D01*
X347300Y769683D01*
X346900Y769600D01*
G01X351067D02*
Y772933D01*
G01Y772267D02*
X351400Y772600D01*
X351733Y772850D01*
X352200Y772933D01*
X352533Y772850D01*
X352933Y772600D01*
G01X360867Y769600D02*
Y774600D01*
X362533D01*
X363067Y774350D01*
X363400Y774017D01*
X363533Y773350D01*
X363400Y772683D01*
X363000Y772267D01*
X362533Y772017D01*
X360867D01*
G01X362533D02*
X363533Y769600D01*
G01X367300Y772933D02*
Y769600D01*
G01Y774267D02*
X367167Y774350D01*
Y774517D01*
X367300Y774600D01*
X367433Y774517D01*
Y774350D01*
X367300Y774267D01*
G01X371467Y768350D02*
X371933Y768017D01*
X372467Y767933D01*
X372933Y768017D01*
X373333Y768433D01*
X373600Y769017D01*
Y772933D01*
G01Y772267D02*
X373333Y772600D01*
X372933Y772850D01*
X372467Y772933D01*
X371933Y772767D01*
X371600Y772433D01*
X371333Y771850D01*
X371200Y771267D01*
X371267Y770767D01*
X371533Y770183D01*
X371933Y769767D01*
X372467Y769600D01*
X372867Y769683D01*
X373333Y770017D01*
X373600Y770350D01*
G01X377500Y772933D02*
Y769600D01*
G01Y774267D02*
X377367Y774350D01*
Y774517D01*
X377500Y774600D01*
X377633Y774517D01*
Y774350D01*
X377500Y774267D01*
G01X383800Y774600D02*
Y769600D01*
G01Y770350D02*
X383533Y769933D01*
X383133Y769683D01*
X382667Y769600D01*
X382133Y769767D01*
X381733Y770183D01*
X381467Y770683D01*
X381400Y771267D01*
X381467Y771850D01*
X381733Y772350D01*
X382133Y772767D01*
X382667Y772933D01*
X383133Y772850D01*
X383467Y772683D01*
X383800Y772350D01*
G01X391467Y769600D02*
Y774600D01*
X393067D01*
X393600Y774350D01*
X394000Y773767D01*
X394133Y773100D01*
X394000Y772433D01*
X393667Y771933D01*
X393067Y771683D01*
X391467D01*
G01X396967Y769600D02*
Y772933D01*
G01Y772267D02*
X397300Y772600D01*
X397633Y772850D01*
X398100Y772933D01*
X398433Y772850D01*
X398833Y772600D01*
G01X403000Y772933D02*
Y769600D01*
G01Y774267D02*
X402867Y774350D01*
Y774517D01*
X403000Y774600D01*
X403133Y774517D01*
Y774350D01*
X403000Y774267D01*
G01X406967Y769600D02*
Y772933D01*
G01Y772100D02*
X407233Y772517D01*
X407633Y772850D01*
X408167Y772933D01*
X408633Y772850D01*
X409033Y772517D01*
X409233Y771933D01*
Y769600D01*
G01X413200Y774600D02*
Y769600D01*
G01X412267Y772933D02*
X414133D01*
G01X417300Y771850D02*
X419433D01*
X419233Y772433D01*
X418900Y772767D01*
X418433Y772933D01*
X417967Y772850D01*
X417567Y772600D01*
X417300Y772017D01*
X417167Y771517D01*
Y771017D01*
X417300Y770517D01*
X417633Y770017D01*
X418033Y769683D01*
X418500Y769600D01*
X418967Y769767D01*
X419433Y770267D01*
G01X424600Y774600D02*
Y769600D01*
G01Y770350D02*
X424333Y769933D01*
X423933Y769683D01*
X423467Y769600D01*
X422933Y769767D01*
X422533Y770183D01*
X422267Y770683D01*
X422200Y771267D01*
X422267Y771850D01*
X422533Y772350D01*
X422933Y772767D01*
X423467Y772933D01*
X423933Y772850D01*
X424267Y772683D01*
X424600Y772350D01*
G01X434133Y772267D02*
X434400Y772517D01*
X434600Y772933D01*
X434733Y773517D01*
X434600Y774017D01*
X434333Y774350D01*
X433867Y774600D01*
X432067D01*
Y769600D01*
X434267D01*
X434733Y769933D01*
X435000Y770433D01*
X435133Y771017D01*
X435000Y771600D01*
X434600Y772100D01*
X434133Y772267D01*
X432067D01*
G01X438700Y769600D02*
X438300Y769683D01*
X437900Y770017D01*
X437633Y770600D01*
X437500Y771267D01*
X437633Y771933D01*
X437900Y772517D01*
X438300Y772850D01*
X438700Y772933D01*
X439100Y772850D01*
X439500Y772517D01*
X439767Y771933D01*
X439833Y771267D01*
X439767Y770600D01*
X439500Y770017D01*
X439100Y769683D01*
X438700Y769600D01*
G01X445000D02*
Y772933D01*
G01Y772350D02*
X444733Y772683D01*
X444333Y772850D01*
X443867Y772933D01*
X443400Y772767D01*
X443000Y772433D01*
X442733Y771933D01*
X442600Y771267D01*
X442733Y770600D01*
X443000Y770100D01*
X443400Y769767D01*
X443867Y769600D01*
X444333Y769683D01*
X444733Y769933D01*
X445000Y770267D01*
G01X447967Y769600D02*
Y772933D01*
G01Y772267D02*
X448300Y772600D01*
X448633Y772850D01*
X449100Y772933D01*
X449433Y772850D01*
X449833Y772600D01*
G01X455200Y774600D02*
Y769600D01*
G01Y770350D02*
X454933Y769933D01*
X454533Y769683D01*
X454067Y769600D01*
X453533Y769767D01*
X453133Y770183D01*
X452867Y770683D01*
X452800Y771267D01*
X452867Y771850D01*
X453133Y772350D01*
X453533Y772767D01*
X454067Y772933D01*
X454533Y772850D01*
X454867Y772683D01*
X455200Y772350D01*
G01X458100Y770183D02*
X458433Y769850D01*
X458900Y769600D01*
X459300D01*
X459700Y769767D01*
X459967Y770017D01*
X460100Y770350D01*
X460033Y770850D01*
X459767Y771100D01*
X458567Y771600D01*
X458300Y772183D01*
X458433Y772600D01*
X458700Y772850D01*
X459100Y772933D01*
X459500Y772850D01*
X459900Y772600D01*
G01X56700Y802500D02*
X58300D01*
G01X57500D02*
Y797500D01*
G01X56700D02*
X58300D01*
G01X62200D02*
Y801750D01*
X62333Y802167D01*
X62600Y802417D01*
X63000Y802500D01*
X63400Y802333D01*
X63600Y801917D01*
G01X62800Y800500D02*
X61467D01*
G01X72800Y802500D02*
Y797500D01*
G01X71867Y800833D02*
X73733D01*
G01X76767Y797500D02*
Y802500D01*
G01Y800083D02*
X77100Y800500D01*
X77433Y800750D01*
X77967Y800833D01*
X78367Y800750D01*
X78833Y800417D01*
X79033Y799917D01*
Y797500D01*
G01X82000Y799750D02*
X84133D01*
X83933Y800333D01*
X83600Y800667D01*
X83133Y800833D01*
X82667Y800750D01*
X82267Y800500D01*
X82000Y799917D01*
X81867Y799417D01*
Y798917D01*
X82000Y798417D01*
X82333Y797917D01*
X82733Y797583D01*
X83200Y797500D01*
X83667Y797667D01*
X84133Y798167D01*
G01X94267Y800417D02*
X93800Y800750D01*
X93400Y800833D01*
X92867Y800667D01*
X92467Y800333D01*
X92200Y799750D01*
X92133Y799167D01*
X92200Y798583D01*
X92467Y798083D01*
X92867Y797667D01*
X93400Y797500D01*
X93867Y797667D01*
X94267Y798000D01*
G01X97367Y797500D02*
Y800833D01*
G01Y800167D02*
X97700Y800500D01*
X98033Y800750D01*
X98500Y800833D01*
X98833Y800750D01*
X99233Y800500D01*
G01X103400Y800833D02*
Y797500D01*
G01Y802167D02*
X103267Y802250D01*
Y802417D01*
X103400Y802500D01*
X103533Y802417D01*
Y802250D01*
X103400Y802167D01*
G01X108500Y802500D02*
Y797500D01*
G01X107567Y800833D02*
X109433D01*
G01X112600Y799750D02*
X114733D01*
X114533Y800333D01*
X114200Y800667D01*
X113733Y800833D01*
X113267Y800750D01*
X112867Y800500D01*
X112600Y799917D01*
X112467Y799417D01*
Y798917D01*
X112600Y798417D01*
X112933Y797917D01*
X113333Y797583D01*
X113800Y797500D01*
X114267Y797667D01*
X114733Y798167D01*
G01X117767Y797500D02*
Y800833D01*
G01Y800167D02*
X118100Y800500D01*
X118433Y800750D01*
X118900Y800833D01*
X119233Y800750D01*
X119633Y800500D01*
G01X123800Y800833D02*
Y797500D01*
G01Y802167D02*
X123667Y802250D01*
Y802417D01*
X123800Y802500D01*
X123933Y802417D01*
Y802250D01*
X123800Y802167D01*
G01X130100Y797500D02*
Y800833D01*
G01Y800250D02*
X129833Y800583D01*
X129433Y800750D01*
X128967Y800833D01*
X128500Y800667D01*
X128100Y800333D01*
X127833Y799833D01*
X127700Y799167D01*
X127833Y798500D01*
X128100Y798000D01*
X128500Y797667D01*
X128967Y797500D01*
X129433Y797583D01*
X129833Y797833D01*
X130100Y798167D01*
G01X139100Y800833D02*
Y797500D01*
G01Y802167D02*
X138967Y802250D01*
Y802417D01*
X139100Y802500D01*
X139233Y802417D01*
Y802250D01*
X139100Y802167D01*
G01X143200Y798083D02*
X143533Y797750D01*
X144000Y797500D01*
X144400D01*
X144800Y797667D01*
X145067Y797917D01*
X145200Y798250D01*
X145133Y798750D01*
X144867Y799000D01*
X143667Y799500D01*
X143400Y800083D01*
X143533Y800500D01*
X143800Y800750D01*
X144200Y800833D01*
X144600Y800750D01*
X145000Y800500D01*
G01X153267Y797500D02*
Y800833D01*
G01Y800000D02*
X153533Y800417D01*
X153933Y800750D01*
X154467Y800833D01*
X154933Y800750D01*
X155333Y800417D01*
X155533Y799833D01*
Y797500D01*
G01X159500D02*
X159100Y797583D01*
X158700Y797917D01*
X158433Y798500D01*
X158300Y799167D01*
X158433Y799833D01*
X158700Y800417D01*
X159100Y800750D01*
X159500Y800833D01*
X159900Y800750D01*
X160300Y800417D01*
X160567Y799833D01*
X160633Y799167D01*
X160567Y798500D01*
X160300Y797917D01*
X159900Y797583D01*
X159500Y797500D01*
G01X164600Y802500D02*
Y797500D01*
G01X163667Y800833D02*
X165533D01*
G01X173800Y798083D02*
X174133Y797750D01*
X174600Y797500D01*
X175000D01*
X175400Y797667D01*
X175667Y797917D01*
X175800Y798250D01*
X175733Y798750D01*
X175467Y799000D01*
X174267Y799500D01*
X174000Y800083D01*
X174133Y800500D01*
X174400Y800750D01*
X174800Y800833D01*
X175200Y800750D01*
X175600Y800500D01*
G01X178700Y795833D02*
Y800833D01*
G01Y800083D02*
X179033Y800500D01*
X179367Y800750D01*
X179900Y800833D01*
X180367Y800750D01*
X180833Y800333D01*
X181033Y799750D01*
X181100Y799167D01*
X181033Y798583D01*
X180833Y798000D01*
X180433Y797667D01*
X179900Y797500D01*
X179433Y797583D01*
X178967Y797833D01*
X178700Y798167D01*
G01X184000Y799750D02*
X186133D01*
X185933Y800333D01*
X185600Y800667D01*
X185133Y800833D01*
X184667Y800750D01*
X184267Y800500D01*
X184000Y799917D01*
X183867Y799417D01*
Y798917D01*
X184000Y798417D01*
X184333Y797917D01*
X184733Y797583D01*
X185200Y797500D01*
X185667Y797667D01*
X186133Y798167D01*
G01X191167Y800417D02*
X190700Y800750D01*
X190300Y800833D01*
X189767Y800667D01*
X189367Y800333D01*
X189100Y799750D01*
X189033Y799167D01*
X189100Y798583D01*
X189367Y798083D01*
X189767Y797667D01*
X190300Y797500D01*
X190767Y797667D01*
X191167Y798000D01*
G01X195200Y800833D02*
Y797500D01*
G01Y802167D02*
X195067Y802250D01*
Y802417D01*
X195200Y802500D01*
X195333Y802417D01*
Y802250D01*
X195200Y802167D01*
G01X199900Y797500D02*
Y801750D01*
X200033Y802167D01*
X200300Y802417D01*
X200700Y802500D01*
X201100Y802333D01*
X201300Y801917D01*
G01X200500Y800500D02*
X199167D01*
G01X205400Y800833D02*
Y797500D01*
G01Y802167D02*
X205267Y802250D01*
Y802417D01*
X205400Y802500D01*
X205533Y802417D01*
Y802250D01*
X205400Y802167D01*
G01X209500Y799750D02*
X211633D01*
X211433Y800333D01*
X211100Y800667D01*
X210633Y800833D01*
X210167Y800750D01*
X209767Y800500D01*
X209500Y799917D01*
X209367Y799417D01*
Y798917D01*
X209500Y798417D01*
X209833Y797917D01*
X210233Y797583D01*
X210700Y797500D01*
X211167Y797667D01*
X211633Y798167D01*
G01X216800Y802500D02*
Y797500D01*
G01Y798250D02*
X216533Y797833D01*
X216133Y797583D01*
X215667Y797500D01*
X215133Y797667D01*
X214733Y798083D01*
X214467Y798583D01*
X214400Y799167D01*
X214467Y799750D01*
X214733Y800250D01*
X215133Y800667D01*
X215667Y800833D01*
X216133Y800750D01*
X216467Y800583D01*
X216800Y800250D01*
G01X225800Y800833D02*
Y797500D01*
G01Y802167D02*
X225667Y802250D01*
Y802417D01*
X225800Y802500D01*
X225933Y802417D01*
Y802250D01*
X225800Y802167D01*
G01X229767Y797500D02*
Y800833D01*
G01Y800000D02*
X230033Y800417D01*
X230433Y800750D01*
X230967Y800833D01*
X231433Y800750D01*
X231833Y800417D01*
X232033Y799833D01*
Y797500D01*
G01X241100Y802500D02*
Y797500D01*
G01X240167Y800833D02*
X242033D01*
G01X245067Y797500D02*
Y802500D01*
G01Y800083D02*
X245400Y800500D01*
X245733Y800750D01*
X246267Y800833D01*
X246667Y800750D01*
X247133Y800417D01*
X247333Y799917D01*
Y797500D01*
G01X250300Y799750D02*
X252433D01*
X252233Y800333D01*
X251900Y800667D01*
X251433Y800833D01*
X250967Y800750D01*
X250567Y800500D01*
X250300Y799917D01*
X250167Y799417D01*
Y798917D01*
X250300Y798417D01*
X250633Y797917D01*
X251033Y797583D01*
X251500Y797500D01*
X251967Y797667D01*
X252433Y798167D01*
G01X261500Y802500D02*
Y797500D01*
G01X260567Y800833D02*
X262433D01*
G01X267800Y797500D02*
Y800833D01*
G01Y800250D02*
X267533Y800583D01*
X267133Y800750D01*
X266667Y800833D01*
X266200Y800667D01*
X265800Y800333D01*
X265533Y799833D01*
X265400Y799167D01*
X265533Y798500D01*
X265800Y798000D01*
X266200Y797667D01*
X266667Y797500D01*
X267133Y797583D01*
X267533Y797833D01*
X267800Y798167D01*
G01X270500Y797500D02*
Y802500D01*
G01Y800000D02*
X270833Y800500D01*
X271233Y800750D01*
X271633Y800833D01*
X272233Y800667D01*
X272633Y800333D01*
X272900Y799750D01*
Y799083D01*
X272767Y798417D01*
X272500Y797917D01*
X272033Y797583D01*
X271633Y797500D01*
X271233Y797583D01*
X270833Y797833D01*
X270500Y798250D01*
G01X276800Y797500D02*
Y802500D01*
G01X280900Y799750D02*
X283033D01*
X282833Y800333D01*
X282500Y800667D01*
X282033Y800833D01*
X281567Y800750D01*
X281167Y800500D01*
X280900Y799917D01*
X280767Y799417D01*
Y798917D01*
X280900Y798417D01*
X281233Y797917D01*
X281633Y797583D01*
X282100Y797500D01*
X282567Y797667D01*
X283033Y798167D01*
G01X287000Y797333D02*
X286867Y797417D01*
Y797583D01*
X287000Y797667D01*
X287133Y797583D01*
Y797417D01*
X287000Y797333D01*
G01Y799583D02*
X286867Y799667D01*
Y799833D01*
X287000Y799917D01*
X287133Y799833D01*
Y799667D01*
X287000Y799583D01*
G01X66500Y779433D02*
X66367Y779517D01*
Y779683D01*
X66500Y779767D01*
X66633Y779683D01*
Y779517D01*
X66500Y779433D01*
G01Y786333D02*
X66367Y786417D01*
Y786583D01*
X66500Y786667D01*
X66633Y786583D01*
Y786417D01*
X66500Y786333D01*
G01X70700Y783600D02*
X72300D01*
G01X71500D02*
Y778600D01*
G01X70700D02*
X72300D01*
G01X75267D02*
Y783600D01*
X76867D01*
X77400Y783350D01*
X77800Y782767D01*
X77933Y782100D01*
X77800Y781433D01*
X77467Y780933D01*
X76867Y780683D01*
X75267D01*
G01X83167Y783183D02*
X82767Y783433D01*
X82300Y783600D01*
X81767D01*
X81167Y783350D01*
X80700Y782933D01*
X80367Y782433D01*
X80100Y781600D01*
X80033Y780850D01*
X80167Y780100D01*
X80367Y779600D01*
X80767Y779100D01*
X81233Y778767D01*
X81700Y778600D01*
X82167D01*
X82633Y778767D01*
X83033Y779017D01*
X83367Y779350D01*
G01X85933Y780267D02*
X87667D01*
G01X90633Y780683D02*
X91100Y781267D01*
X91500Y781600D01*
X92033Y781767D01*
X92500Y781600D01*
X92833Y781267D01*
X93100Y780767D01*
X93167Y780183D01*
X93100Y779683D01*
X92833Y779183D01*
X92433Y778767D01*
X91967Y778600D01*
X91433Y778767D01*
X90967Y779267D01*
X90700Y780017D01*
X90633Y780850D01*
X90767Y781933D01*
X90967Y782517D01*
X91300Y783100D01*
X91767Y783517D01*
X92233Y783600D01*
X92700Y783433D01*
X93033Y783017D01*
G01X97000Y783600D02*
X96467Y783433D01*
X96067Y783017D01*
X95800Y782517D01*
X95600Y781850D01*
X95533Y781100D01*
X95600Y780350D01*
X95800Y779683D01*
X96067Y779183D01*
X96467Y778767D01*
X97000Y778600D01*
X97533Y778767D01*
X97933Y779183D01*
X98200Y779683D01*
X98400Y780350D01*
X98467Y781100D01*
X98400Y781850D01*
X98200Y782517D01*
X97933Y783017D01*
X97533Y783433D01*
X97000Y783600D01*
G01X102100Y778600D02*
Y783600D01*
X101300Y782600D01*
G01Y778600D02*
X102900D01*
G01X107200D02*
Y783600D01*
X106400Y782600D01*
G01Y778600D02*
X108000D01*
G01X117800Y781100D02*
X119133D01*
Y779600D01*
X118733Y779100D01*
X118267Y778767D01*
X117600Y778600D01*
X116933Y778767D01*
X116467Y779100D01*
X116067Y779600D01*
X115800Y780183D01*
X115667Y780850D01*
Y781433D01*
X115800Y781933D01*
X116067Y782517D01*
X116467Y783017D01*
X116867Y783350D01*
X117400Y783600D01*
X117867D01*
X118400Y783433D01*
X118800Y783100D01*
G01X121500Y780850D02*
X123633D01*
X123433Y781433D01*
X123100Y781767D01*
X122633Y781933D01*
X122167Y781850D01*
X121767Y781600D01*
X121500Y781017D01*
X121367Y780517D01*
Y780017D01*
X121500Y779517D01*
X121833Y779017D01*
X122233Y778683D01*
X122700Y778600D01*
X123167Y778767D01*
X123633Y779267D01*
G01X126467Y778600D02*
Y781933D01*
G01Y781100D02*
X126733Y781517D01*
X127133Y781850D01*
X127667Y781933D01*
X128133Y781850D01*
X128533Y781517D01*
X128733Y780933D01*
Y778600D01*
G01X131700Y780850D02*
X133833D01*
X133633Y781433D01*
X133300Y781767D01*
X132833Y781933D01*
X132367Y781850D01*
X131967Y781600D01*
X131700Y781017D01*
X131567Y780517D01*
Y780017D01*
X131700Y779517D01*
X132033Y779017D01*
X132433Y778683D01*
X132900Y778600D01*
X133367Y778767D01*
X133833Y779267D01*
G01X136867Y778600D02*
Y781933D01*
G01Y781267D02*
X137200Y781600D01*
X137533Y781850D01*
X138000Y781933D01*
X138333Y781850D01*
X138733Y781600D01*
G01X142900Y781933D02*
Y778600D01*
G01Y783267D02*
X142767Y783350D01*
Y783517D01*
X142900Y783600D01*
X143033Y783517D01*
Y783350D01*
X142900Y783267D01*
G01X149067Y781517D02*
X148600Y781850D01*
X148200Y781933D01*
X147667Y781767D01*
X147267Y781433D01*
X147000Y780850D01*
X146933Y780267D01*
X147000Y779683D01*
X147267Y779183D01*
X147667Y778767D01*
X148200Y778600D01*
X148667Y778767D01*
X149067Y779100D01*
G01X156867Y778600D02*
Y783600D01*
X158467D01*
X159000Y783350D01*
X159400Y782767D01*
X159533Y782100D01*
X159400Y781433D01*
X159067Y780933D01*
X158467Y780683D01*
X156867D01*
G01X162300Y780850D02*
X164433D01*
X164233Y781433D01*
X163900Y781767D01*
X163433Y781933D01*
X162967Y781850D01*
X162567Y781600D01*
X162300Y781017D01*
X162167Y780517D01*
Y780017D01*
X162300Y779517D01*
X162633Y779017D01*
X163033Y778683D01*
X163500Y778600D01*
X163967Y778767D01*
X164433Y779267D01*
G01X167467Y778600D02*
Y781933D01*
G01Y781267D02*
X167800Y781600D01*
X168133Y781850D01*
X168600Y781933D01*
X168933Y781850D01*
X169333Y781600D01*
G01X173100Y778600D02*
Y782850D01*
X173233Y783267D01*
X173500Y783517D01*
X173900Y783600D01*
X174300Y783433D01*
X174500Y783017D01*
G01X173700Y781600D02*
X172367D01*
G01X178600Y778600D02*
X178200Y778683D01*
X177800Y779017D01*
X177533Y779600D01*
X177400Y780267D01*
X177533Y780933D01*
X177800Y781517D01*
X178200Y781850D01*
X178600Y781933D01*
X179000Y781850D01*
X179400Y781517D01*
X179667Y780933D01*
X179733Y780267D01*
X179667Y779600D01*
X179400Y779017D01*
X179000Y778683D01*
X178600Y778600D01*
G01X182767D02*
Y781933D01*
G01Y781267D02*
X183100Y781600D01*
X183433Y781850D01*
X183900Y781933D01*
X184233Y781850D01*
X184633Y781600D01*
G01X186800Y778600D02*
Y781933D01*
G01Y781017D02*
X187000Y781433D01*
X187333Y781767D01*
X187800Y781933D01*
X188267Y781767D01*
X188600Y781433D01*
X188800Y781017D01*
Y778600D01*
G01Y781017D02*
X189000Y781433D01*
X189333Y781767D01*
X189800Y781933D01*
X190267Y781767D01*
X190600Y781433D01*
X190800Y780933D01*
Y778600D01*
G01X195100D02*
Y781933D01*
G01Y781350D02*
X194833Y781683D01*
X194433Y781850D01*
X193967Y781933D01*
X193500Y781767D01*
X193100Y781433D01*
X192833Y780933D01*
X192700Y780267D01*
X192833Y779600D01*
X193100Y779100D01*
X193500Y778767D01*
X193967Y778600D01*
X194433Y778683D01*
X194833Y778933D01*
X195100Y779267D01*
G01X197867Y778600D02*
Y781933D01*
G01Y781100D02*
X198133Y781517D01*
X198533Y781850D01*
X199067Y781933D01*
X199533Y781850D01*
X199933Y781517D01*
X200133Y780933D01*
Y778600D01*
G01X205167Y781517D02*
X204700Y781850D01*
X204300Y781933D01*
X203767Y781767D01*
X203367Y781433D01*
X203100Y780850D01*
X203033Y780267D01*
X203100Y779683D01*
X203367Y779183D01*
X203767Y778767D01*
X204300Y778600D01*
X204767Y778767D01*
X205167Y779100D01*
G01X208200Y780850D02*
X210333D01*
X210133Y781433D01*
X209800Y781767D01*
X209333Y781933D01*
X208867Y781850D01*
X208467Y781600D01*
X208200Y781017D01*
X208067Y780517D01*
Y780017D01*
X208200Y779517D01*
X208533Y779017D01*
X208933Y778683D01*
X209400Y778600D01*
X209867Y778767D01*
X210333Y779267D01*
G01X218000D02*
X218533Y778850D01*
X219133Y778600D01*
X219667D01*
X220200Y778850D01*
X220600Y779267D01*
X220800Y779850D01*
X220667Y780433D01*
X220333Y780933D01*
X219733Y781267D01*
X218933Y781433D01*
X218467Y781767D01*
X218267Y782350D01*
X218400Y782933D01*
X218733Y783350D01*
X219200Y783600D01*
X219667D01*
X220133Y783433D01*
X220533Y783017D01*
G01X223300Y776933D02*
Y781933D01*
G01Y781183D02*
X223633Y781600D01*
X223967Y781850D01*
X224500Y781933D01*
X224967Y781850D01*
X225433Y781433D01*
X225633Y780850D01*
X225700Y780267D01*
X225633Y779683D01*
X225433Y779100D01*
X225033Y778767D01*
X224500Y778600D01*
X224033Y778683D01*
X223567Y778933D01*
X223300Y779267D01*
G01X228600Y780850D02*
X230733D01*
X230533Y781433D01*
X230200Y781767D01*
X229733Y781933D01*
X229267Y781850D01*
X228867Y781600D01*
X228600Y781017D01*
X228467Y780517D01*
Y780017D01*
X228600Y779517D01*
X228933Y779017D01*
X229333Y778683D01*
X229800Y778600D01*
X230267Y778767D01*
X230733Y779267D01*
G01X235767Y781517D02*
X235300Y781850D01*
X234900Y781933D01*
X234367Y781767D01*
X233967Y781433D01*
X233700Y780850D01*
X233633Y780267D01*
X233700Y779683D01*
X233967Y779183D01*
X234367Y778767D01*
X234900Y778600D01*
X235367Y778767D01*
X235767Y779100D01*
G01X239800Y781933D02*
Y778600D01*
G01Y783267D02*
X239667Y783350D01*
Y783517D01*
X239800Y783600D01*
X239933Y783517D01*
Y783350D01*
X239800Y783267D01*
G01X244500Y778600D02*
Y782850D01*
X244633Y783267D01*
X244900Y783517D01*
X245300Y783600D01*
X245700Y783433D01*
X245900Y783017D01*
G01X245100Y781600D02*
X243767D01*
G01X250000Y781933D02*
Y778600D01*
G01Y783267D02*
X249867Y783350D01*
Y783517D01*
X250000Y783600D01*
X250133Y783517D01*
Y783350D01*
X250000Y783267D01*
G01X256167Y781517D02*
X255700Y781850D01*
X255300Y781933D01*
X254767Y781767D01*
X254367Y781433D01*
X254100Y780850D01*
X254033Y780267D01*
X254100Y779683D01*
X254367Y779183D01*
X254767Y778767D01*
X255300Y778600D01*
X255767Y778767D01*
X256167Y779100D01*
G01X261400Y778600D02*
Y781933D01*
G01Y781350D02*
X261133Y781683D01*
X260733Y781850D01*
X260267Y781933D01*
X259800Y781767D01*
X259400Y781433D01*
X259133Y780933D01*
X259000Y780267D01*
X259133Y779600D01*
X259400Y779100D01*
X259800Y778767D01*
X260267Y778600D01*
X260733Y778683D01*
X261133Y778933D01*
X261400Y779267D01*
G01X265300Y783600D02*
Y778600D01*
G01X264367Y781933D02*
X266233D01*
G01X270400D02*
Y778600D01*
G01Y783267D02*
X270267Y783350D01*
Y783517D01*
X270400Y783600D01*
X270533Y783517D01*
Y783350D01*
X270400Y783267D01*
G01X275500Y778600D02*
X275100Y778683D01*
X274700Y779017D01*
X274433Y779600D01*
X274300Y780267D01*
X274433Y780933D01*
X274700Y781517D01*
X275100Y781850D01*
X275500Y781933D01*
X275900Y781850D01*
X276300Y781517D01*
X276567Y780933D01*
X276633Y780267D01*
X276567Y779600D01*
X276300Y779017D01*
X275900Y778683D01*
X275500Y778600D01*
G01X279467D02*
Y781933D01*
G01Y781100D02*
X279733Y781517D01*
X280133Y781850D01*
X280667Y781933D01*
X281133Y781850D01*
X281533Y781517D01*
X281733Y780933D01*
Y778600D01*
G01X290400D02*
Y782850D01*
X290533Y783267D01*
X290800Y783517D01*
X291200Y783600D01*
X291600Y783433D01*
X291800Y783017D01*
G01X291000Y781600D02*
X289667D01*
G01X295900Y778600D02*
X295500Y778683D01*
X295100Y779017D01*
X294833Y779600D01*
X294700Y780267D01*
X294833Y780933D01*
X295100Y781517D01*
X295500Y781850D01*
X295900Y781933D01*
X296300Y781850D01*
X296700Y781517D01*
X296967Y780933D01*
X297033Y780267D01*
X296967Y779600D01*
X296700Y779017D01*
X296300Y778683D01*
X295900Y778600D01*
G01X300067D02*
Y781933D01*
G01Y781267D02*
X300400Y781600D01*
X300733Y781850D01*
X301200Y781933D01*
X301533Y781850D01*
X301933Y781600D01*
G01X309867Y778600D02*
Y783600D01*
X311467D01*
X312000Y783350D01*
X312400Y782767D01*
X312533Y782100D01*
X312400Y781433D01*
X312067Y780933D01*
X311467Y780683D01*
X309867D01*
G01X315367Y778600D02*
Y781933D01*
G01Y781267D02*
X315700Y781600D01*
X316033Y781850D01*
X316500Y781933D01*
X316833Y781850D01*
X317233Y781600D01*
G01X321400Y781933D02*
Y778600D01*
G01Y783267D02*
X321267Y783350D01*
Y783517D01*
X321400Y783600D01*
X321533Y783517D01*
Y783350D01*
X321400Y783267D01*
G01X325367Y778600D02*
Y781933D01*
G01Y781100D02*
X325633Y781517D01*
X326033Y781850D01*
X326567Y781933D01*
X327033Y781850D01*
X327433Y781517D01*
X327633Y780933D01*
Y778600D01*
G01X331600Y783600D02*
Y778600D01*
G01X330667Y781933D02*
X332533D01*
G01X335700Y780850D02*
X337833D01*
X337633Y781433D01*
X337300Y781767D01*
X336833Y781933D01*
X336367Y781850D01*
X335967Y781600D01*
X335700Y781017D01*
X335567Y780517D01*
Y780017D01*
X335700Y779517D01*
X336033Y779017D01*
X336433Y778683D01*
X336900Y778600D01*
X337367Y778767D01*
X337833Y779267D01*
G01X343000Y783600D02*
Y778600D01*
G01Y779350D02*
X342733Y778933D01*
X342333Y778683D01*
X341867Y778600D01*
X341333Y778767D01*
X340933Y779183D01*
X340667Y779683D01*
X340600Y780267D01*
X340667Y780850D01*
X340933Y781350D01*
X341333Y781767D01*
X341867Y781933D01*
X342333Y781850D01*
X342667Y781683D01*
X343000Y781350D01*
G01X352533Y781267D02*
X352800Y781517D01*
X353000Y781933D01*
X353133Y782517D01*
X353000Y783017D01*
X352733Y783350D01*
X352267Y783600D01*
X350467D01*
Y778600D01*
X352667D01*
X353133Y778933D01*
X353400Y779433D01*
X353533Y780017D01*
X353400Y780600D01*
X353000Y781100D01*
X352533Y781267D01*
X350467D01*
G01X357100Y778600D02*
X356700Y778683D01*
X356300Y779017D01*
X356033Y779600D01*
X355900Y780267D01*
X356033Y780933D01*
X356300Y781517D01*
X356700Y781850D01*
X357100Y781933D01*
X357500Y781850D01*
X357900Y781517D01*
X358167Y780933D01*
X358233Y780267D01*
X358167Y779600D01*
X357900Y779017D01*
X357500Y778683D01*
X357100Y778600D01*
G01X363400D02*
Y781933D01*
G01Y781350D02*
X363133Y781683D01*
X362733Y781850D01*
X362267Y781933D01*
X361800Y781767D01*
X361400Y781433D01*
X361133Y780933D01*
X361000Y780267D01*
X361133Y779600D01*
X361400Y779100D01*
X361800Y778767D01*
X362267Y778600D01*
X362733Y778683D01*
X363133Y778933D01*
X363400Y779267D01*
G01X366367Y778600D02*
Y781933D01*
G01Y781267D02*
X366700Y781600D01*
X367033Y781850D01*
X367500Y781933D01*
X367833Y781850D01*
X368233Y781600D01*
G01X373600Y783600D02*
Y778600D01*
G01Y779350D02*
X373333Y778933D01*
X372933Y778683D01*
X372467Y778600D01*
X371933Y778767D01*
X371533Y779183D01*
X371267Y779683D01*
X371200Y780267D01*
X371267Y780850D01*
X371533Y781350D01*
X371933Y781767D01*
X372467Y781933D01*
X372933Y781850D01*
X373267Y781683D01*
X373600Y781350D01*
G01X376500Y779183D02*
X376833Y778850D01*
X377300Y778600D01*
X377700D01*
X378100Y778767D01*
X378367Y779017D01*
X378500Y779350D01*
X378433Y779850D01*
X378167Y780100D01*
X376967Y780600D01*
X376700Y781183D01*
X376833Y781600D01*
X377100Y781850D01*
X377500Y781933D01*
X377900Y781850D01*
X378300Y781600D01*
G01X70700Y791500D02*
X72300D01*
G01X71500D02*
Y786500D01*
G01X70700D02*
X72300D01*
G01X75267D02*
Y791500D01*
X76867D01*
X77400Y791250D01*
X77800Y790667D01*
X77933Y790000D01*
X77800Y789333D01*
X77467Y788833D01*
X76867Y788583D01*
X75267D01*
G01X83167Y791083D02*
X82767Y791333D01*
X82300Y791500D01*
X81767D01*
X81167Y791250D01*
X80700Y790833D01*
X80367Y790333D01*
X80100Y789500D01*
X80033Y788750D01*
X80167Y788000D01*
X80367Y787500D01*
X80767Y787000D01*
X81233Y786667D01*
X81700Y786500D01*
X82167D01*
X82633Y786667D01*
X83033Y786917D01*
X83367Y787250D01*
G01X85933Y788167D02*
X87667D01*
G01X90233Y786500D02*
X91900Y791500D01*
X93567Y786500D01*
G01X92967Y788250D02*
X90833D01*
G01X96133Y788167D02*
X97867D01*
G01X100833Y788583D02*
X101300Y789167D01*
X101700Y789500D01*
X102233Y789667D01*
X102700Y789500D01*
X103033Y789167D01*
X103300Y788667D01*
X103367Y788083D01*
X103300Y787583D01*
X103033Y787083D01*
X102633Y786667D01*
X102167Y786500D01*
X101633Y786667D01*
X101167Y787167D01*
X100900Y787917D01*
X100833Y788750D01*
X100967Y789833D01*
X101167Y790417D01*
X101500Y791000D01*
X101967Y791417D01*
X102433Y791500D01*
X102900Y791333D01*
X103233Y790917D01*
G01X107200Y791500D02*
X106667Y791333D01*
X106267Y790917D01*
X106000Y790417D01*
X105800Y789750D01*
X105733Y789000D01*
X105800Y788250D01*
X106000Y787583D01*
X106267Y787083D01*
X106667Y786667D01*
X107200Y786500D01*
X107733Y786667D01*
X108133Y787083D01*
X108400Y787583D01*
X108600Y788250D01*
X108667Y789000D01*
X108600Y789750D01*
X108400Y790417D01*
X108133Y790917D01*
X107733Y791333D01*
X107200Y791500D01*
G01X112300D02*
X111767Y791333D01*
X111367Y790917D01*
X111100Y790417D01*
X110900Y789750D01*
X110833Y789000D01*
X110900Y788250D01*
X111100Y787583D01*
X111367Y787083D01*
X111767Y786667D01*
X112300Y786500D01*
X112833Y786667D01*
X113233Y787083D01*
X113500Y787583D01*
X113700Y788250D01*
X113767Y789000D01*
X113700Y789750D01*
X113500Y790417D01*
X113233Y790917D01*
X112833Y791333D01*
X112300Y791500D01*
G01X120833Y786500D02*
X122500Y791500D01*
X124167Y786500D01*
G01X123567Y788250D02*
X121433D01*
G01X128667Y789417D02*
X128200Y789750D01*
X127800Y789833D01*
X127267Y789667D01*
X126867Y789333D01*
X126600Y788750D01*
X126533Y788167D01*
X126600Y787583D01*
X126867Y787083D01*
X127267Y786667D01*
X127800Y786500D01*
X128267Y786667D01*
X128667Y787000D01*
G01X133767Y789417D02*
X133300Y789750D01*
X132900Y789833D01*
X132367Y789667D01*
X131967Y789333D01*
X131700Y788750D01*
X131633Y788167D01*
X131700Y787583D01*
X131967Y787083D01*
X132367Y786667D01*
X132900Y786500D01*
X133367Y786667D01*
X133767Y787000D01*
G01X136800Y788750D02*
X138933D01*
X138733Y789333D01*
X138400Y789667D01*
X137933Y789833D01*
X137467Y789750D01*
X137067Y789500D01*
X136800Y788917D01*
X136667Y788417D01*
Y787917D01*
X136800Y787417D01*
X137133Y786917D01*
X137533Y786583D01*
X138000Y786500D01*
X138467Y786667D01*
X138933Y787167D01*
G01X141700Y784833D02*
Y789833D01*
G01Y789083D02*
X142033Y789500D01*
X142367Y789750D01*
X142900Y789833D01*
X143367Y789750D01*
X143833Y789333D01*
X144033Y788750D01*
X144100Y788167D01*
X144033Y787583D01*
X143833Y787000D01*
X143433Y786667D01*
X142900Y786500D01*
X142433Y786583D01*
X141967Y786833D01*
X141700Y787167D01*
G01X148000Y791500D02*
Y786500D01*
G01X147067Y789833D02*
X148933D01*
G01X154300Y786500D02*
Y789833D01*
G01Y789250D02*
X154033Y789583D01*
X153633Y789750D01*
X153167Y789833D01*
X152700Y789667D01*
X152300Y789333D01*
X152033Y788833D01*
X151900Y788167D01*
X152033Y787500D01*
X152300Y787000D01*
X152700Y786667D01*
X153167Y786500D01*
X153633Y786583D01*
X154033Y786833D01*
X154300Y787167D01*
G01X157000Y786500D02*
Y791500D01*
G01Y789000D02*
X157333Y789500D01*
X157733Y789750D01*
X158133Y789833D01*
X158733Y789667D01*
X159133Y789333D01*
X159400Y788750D01*
Y788083D01*
X159267Y787417D01*
X159000Y786917D01*
X158533Y786583D01*
X158133Y786500D01*
X157733Y786583D01*
X157333Y786833D01*
X157000Y787250D01*
G01X163300Y789833D02*
Y786500D01*
G01Y791167D02*
X163167Y791250D01*
Y791417D01*
X163300Y791500D01*
X163433Y791417D01*
Y791250D01*
X163300Y791167D01*
G01X168400Y786500D02*
Y791500D01*
G01X173500Y789833D02*
Y786500D01*
G01Y791167D02*
X173367Y791250D01*
Y791417D01*
X173500Y791500D01*
X173633Y791417D01*
Y791250D01*
X173500Y791167D01*
G01X178600Y791500D02*
Y786500D01*
G01X177667Y789833D02*
X179533D01*
G01X182300Y785000D02*
X182700Y784833D01*
X183233Y785000D01*
X183567Y785333D01*
X183833Y785750D01*
X184233Y787083D01*
X185100Y789833D01*
G01X182967D02*
X184233Y787083D01*
G01X193900Y786500D02*
X193500Y786583D01*
X193100Y786917D01*
X192833Y787500D01*
X192700Y788167D01*
X192833Y788833D01*
X193100Y789417D01*
X193500Y789750D01*
X193900Y789833D01*
X194300Y789750D01*
X194700Y789417D01*
X194967Y788833D01*
X195033Y788167D01*
X194967Y787500D01*
X194700Y786917D01*
X194300Y786583D01*
X193900Y786500D01*
G01X198600D02*
Y790750D01*
X198733Y791167D01*
X199000Y791417D01*
X199400Y791500D01*
X199800Y791333D01*
X200000Y790917D01*
G01X199200Y789500D02*
X197867D01*
G01X207867Y786500D02*
Y791500D01*
X209467D01*
X210000Y791250D01*
X210400Y790667D01*
X210533Y790000D01*
X210400Y789333D01*
X210067Y788833D01*
X209467Y788583D01*
X207867D01*
G01X213367Y786500D02*
Y789833D01*
G01Y789167D02*
X213700Y789500D01*
X214033Y789750D01*
X214500Y789833D01*
X214833Y789750D01*
X215233Y789500D01*
G01X219400Y789833D02*
Y786500D01*
G01Y791167D02*
X219267Y791250D01*
Y791417D01*
X219400Y791500D01*
X219533Y791417D01*
Y791250D01*
X219400Y791167D01*
G01X223367Y786500D02*
Y789833D01*
G01Y789000D02*
X223633Y789417D01*
X224033Y789750D01*
X224567Y789833D01*
X225033Y789750D01*
X225433Y789417D01*
X225633Y788833D01*
Y786500D01*
G01X229600Y791500D02*
Y786500D01*
G01X228667Y789833D02*
X230533D01*
G01X233700Y788750D02*
X235833D01*
X235633Y789333D01*
X235300Y789667D01*
X234833Y789833D01*
X234367Y789750D01*
X233967Y789500D01*
X233700Y788917D01*
X233567Y788417D01*
Y787917D01*
X233700Y787417D01*
X234033Y786917D01*
X234433Y786583D01*
X234900Y786500D01*
X235367Y786667D01*
X235833Y787167D01*
G01X241000Y791500D02*
Y786500D01*
G01Y787250D02*
X240733Y786833D01*
X240333Y786583D01*
X239867Y786500D01*
X239333Y786667D01*
X238933Y787083D01*
X238667Y787583D01*
X238600Y788167D01*
X238667Y788750D01*
X238933Y789250D01*
X239333Y789667D01*
X239867Y789833D01*
X240333Y789750D01*
X240667Y789583D01*
X241000Y789250D01*
G01X250533Y789167D02*
X250800Y789417D01*
X251000Y789833D01*
X251133Y790417D01*
X251000Y790917D01*
X250733Y791250D01*
X250267Y791500D01*
X248467D01*
Y786500D01*
X250667D01*
X251133Y786833D01*
X251400Y787333D01*
X251533Y787917D01*
X251400Y788500D01*
X251000Y789000D01*
X250533Y789167D01*
X248467D01*
G01X255100Y786500D02*
X254700Y786583D01*
X254300Y786917D01*
X254033Y787500D01*
X253900Y788167D01*
X254033Y788833D01*
X254300Y789417D01*
X254700Y789750D01*
X255100Y789833D01*
X255500Y789750D01*
X255900Y789417D01*
X256167Y788833D01*
X256233Y788167D01*
X256167Y787500D01*
X255900Y786917D01*
X255500Y786583D01*
X255100Y786500D01*
G01X261400D02*
Y789833D01*
G01Y789250D02*
X261133Y789583D01*
X260733Y789750D01*
X260267Y789833D01*
X259800Y789667D01*
X259400Y789333D01*
X259133Y788833D01*
X259000Y788167D01*
X259133Y787500D01*
X259400Y787000D01*
X259800Y786667D01*
X260267Y786500D01*
X260733Y786583D01*
X261133Y786833D01*
X261400Y787167D01*
G01X264367Y786500D02*
Y789833D01*
G01Y789167D02*
X264700Y789500D01*
X265033Y789750D01*
X265500Y789833D01*
X265833Y789750D01*
X266233Y789500D01*
G01X271600Y791500D02*
Y786500D01*
G01Y787250D02*
X271333Y786833D01*
X270933Y786583D01*
X270467Y786500D01*
X269933Y786667D01*
X269533Y787083D01*
X269267Y787583D01*
X269200Y788167D01*
X269267Y788750D01*
X269533Y789250D01*
X269933Y789667D01*
X270467Y789833D01*
X270933Y789750D01*
X271267Y789583D01*
X271600Y789250D01*
G01X274500Y787083D02*
X274833Y786750D01*
X275300Y786500D01*
X275700D01*
X276100Y786667D01*
X276367Y786917D01*
X276500Y787250D01*
X276433Y787750D01*
X276167Y788000D01*
X274967Y788500D01*
X274700Y789083D01*
X274833Y789500D01*
X275100Y789750D01*
X275500Y789833D01*
X275900Y789750D01*
X276300Y789500D01*
G01X57667Y806500D02*
Y811500D01*
X59267D01*
X59800Y811250D01*
X60200Y810667D01*
X60333Y810000D01*
X60200Y809333D01*
X59867Y808833D01*
X59267Y808583D01*
X57667D01*
G01X64100Y806500D02*
Y811500D01*
G01X68200Y808750D02*
X70333D01*
X70133Y809333D01*
X69800Y809667D01*
X69333Y809833D01*
X68867Y809750D01*
X68467Y809500D01*
X68200Y808917D01*
X68067Y808417D01*
Y807917D01*
X68200Y807417D01*
X68533Y806917D01*
X68933Y806583D01*
X69400Y806500D01*
X69867Y806667D01*
X70333Y807167D01*
G01X75500Y806500D02*
Y809833D01*
G01Y809250D02*
X75233Y809583D01*
X74833Y809750D01*
X74367Y809833D01*
X73900Y809667D01*
X73500Y809333D01*
X73233Y808833D01*
X73100Y808167D01*
X73233Y807500D01*
X73500Y807000D01*
X73900Y806667D01*
X74367Y806500D01*
X74833Y806583D01*
X75233Y806833D01*
X75500Y807167D01*
G01X78400Y807083D02*
X78733Y806750D01*
X79200Y806500D01*
X79600D01*
X80000Y806667D01*
X80267Y806917D01*
X80400Y807250D01*
X80333Y807750D01*
X80067Y808000D01*
X78867Y808500D01*
X78600Y809083D01*
X78733Y809500D01*
X79000Y809750D01*
X79400Y809833D01*
X79800Y809750D01*
X80200Y809500D01*
G01X83500Y808750D02*
X85633D01*
X85433Y809333D01*
X85100Y809667D01*
X84633Y809833D01*
X84167Y809750D01*
X83767Y809500D01*
X83500Y808917D01*
X83367Y808417D01*
Y807917D01*
X83500Y807417D01*
X83833Y806917D01*
X84233Y806583D01*
X84700Y806500D01*
X85167Y806667D01*
X85633Y807167D01*
G01X94300Y806500D02*
Y810750D01*
X94433Y811167D01*
X94700Y811417D01*
X95100Y811500D01*
X95500Y811333D01*
X95700Y810917D01*
G01X94900Y809500D02*
X93567D01*
G01X99800Y806500D02*
X99400Y806583D01*
X99000Y806917D01*
X98733Y807500D01*
X98600Y808167D01*
X98733Y808833D01*
X99000Y809417D01*
X99400Y809750D01*
X99800Y809833D01*
X100200Y809750D01*
X100600Y809417D01*
X100867Y808833D01*
X100933Y808167D01*
X100867Y807500D01*
X100600Y806917D01*
X100200Y806583D01*
X99800Y806500D01*
G01X104900D02*
Y811500D01*
G01X110000Y806500D02*
Y811500D01*
G01X115100Y806500D02*
X114700Y806583D01*
X114300Y806917D01*
X114033Y807500D01*
X113900Y808167D01*
X114033Y808833D01*
X114300Y809417D01*
X114700Y809750D01*
X115100Y809833D01*
X115500Y809750D01*
X115900Y809417D01*
X116167Y808833D01*
X116233Y808167D01*
X116167Y807500D01*
X115900Y806917D01*
X115500Y806583D01*
X115100Y806500D01*
G01X118533Y809833D02*
X119333Y806500D01*
X120200Y809833D01*
X121067Y806500D01*
X121867Y809833D01*
G01X130400Y811500D02*
Y806500D01*
G01X129467Y809833D02*
X131333D01*
G01X134367Y806500D02*
Y811500D01*
G01Y809083D02*
X134700Y809500D01*
X135033Y809750D01*
X135567Y809833D01*
X135967Y809750D01*
X136433Y809417D01*
X136633Y808917D01*
Y806500D01*
G01X139600Y808750D02*
X141733D01*
X141533Y809333D01*
X141200Y809667D01*
X140733Y809833D01*
X140267Y809750D01*
X139867Y809500D01*
X139600Y808917D01*
X139467Y808417D01*
Y807917D01*
X139600Y807417D01*
X139933Y806917D01*
X140333Y806583D01*
X140800Y806500D01*
X141267Y806667D01*
X141733Y807167D01*
G01X149800Y807083D02*
X150133Y806750D01*
X150600Y806500D01*
X151000D01*
X151400Y806667D01*
X151667Y806917D01*
X151800Y807250D01*
X151733Y807750D01*
X151467Y808000D01*
X150267Y808500D01*
X150000Y809083D01*
X150133Y809500D01*
X150400Y809750D01*
X150800Y809833D01*
X151200Y809750D01*
X151600Y809500D01*
G01X154700Y804833D02*
Y809833D01*
G01Y809083D02*
X155033Y809500D01*
X155367Y809750D01*
X155900Y809833D01*
X156367Y809750D01*
X156833Y809333D01*
X157033Y808750D01*
X157100Y808167D01*
X157033Y807583D01*
X156833Y807000D01*
X156433Y806667D01*
X155900Y806500D01*
X155433Y806583D01*
X154967Y806833D01*
X154700Y807167D01*
G01X160000Y808750D02*
X162133D01*
X161933Y809333D01*
X161600Y809667D01*
X161133Y809833D01*
X160667Y809750D01*
X160267Y809500D01*
X160000Y808917D01*
X159867Y808417D01*
Y807917D01*
X160000Y807417D01*
X160333Y806917D01*
X160733Y806583D01*
X161200Y806500D01*
X161667Y806667D01*
X162133Y807167D01*
G01X167167Y809417D02*
X166700Y809750D01*
X166300Y809833D01*
X165767Y809667D01*
X165367Y809333D01*
X165100Y808750D01*
X165033Y808167D01*
X165100Y807583D01*
X165367Y807083D01*
X165767Y806667D01*
X166300Y806500D01*
X166767Y806667D01*
X167167Y807000D01*
G01X171200Y809833D02*
Y806500D01*
G01Y811167D02*
X171067Y811250D01*
Y811417D01*
X171200Y811500D01*
X171333Y811417D01*
Y811250D01*
X171200Y811167D01*
G01X175900Y806500D02*
Y810750D01*
X176033Y811167D01*
X176300Y811417D01*
X176700Y811500D01*
X177100Y811333D01*
X177300Y810917D01*
G01X176500Y809500D02*
X175167D01*
G01X181400Y809833D02*
Y806500D01*
G01Y811167D02*
X181267Y811250D01*
Y811417D01*
X181400Y811500D01*
X181533Y811417D01*
Y811250D01*
X181400Y811167D01*
G01X187567Y809417D02*
X187100Y809750D01*
X186700Y809833D01*
X186167Y809667D01*
X185767Y809333D01*
X185500Y808750D01*
X185433Y808167D01*
X185500Y807583D01*
X185767Y807083D01*
X186167Y806667D01*
X186700Y806500D01*
X187167Y806667D01*
X187567Y807000D01*
G01X192800Y806500D02*
Y809833D01*
G01Y809250D02*
X192533Y809583D01*
X192133Y809750D01*
X191667Y809833D01*
X191200Y809667D01*
X190800Y809333D01*
X190533Y808833D01*
X190400Y808167D01*
X190533Y807500D01*
X190800Y807000D01*
X191200Y806667D01*
X191667Y806500D01*
X192133Y806583D01*
X192533Y806833D01*
X192800Y807167D01*
G01X196700Y811500D02*
Y806500D01*
G01X195767Y809833D02*
X197633D01*
G01X201800D02*
Y806500D01*
G01Y811167D02*
X201667Y811250D01*
Y811417D01*
X201800Y811500D01*
X201933Y811417D01*
Y811250D01*
X201800Y811167D01*
G01X206900Y806500D02*
X206500Y806583D01*
X206100Y806917D01*
X205833Y807500D01*
X205700Y808167D01*
X205833Y808833D01*
X206100Y809417D01*
X206500Y809750D01*
X206900Y809833D01*
X207300Y809750D01*
X207700Y809417D01*
X207967Y808833D01*
X208033Y808167D01*
X207967Y807500D01*
X207700Y806917D01*
X207300Y806583D01*
X206900Y806500D01*
G01X210867D02*
Y809833D01*
G01Y809000D02*
X211133Y809417D01*
X211533Y809750D01*
X212067Y809833D01*
X212533Y809750D01*
X212933Y809417D01*
X213133Y808833D01*
Y806500D01*
G01X223400Y811500D02*
Y806500D01*
G01Y807250D02*
X223133Y806833D01*
X222733Y806583D01*
X222267Y806500D01*
X221733Y806667D01*
X221333Y807083D01*
X221067Y807583D01*
X221000Y808167D01*
X221067Y808750D01*
X221333Y809250D01*
X221733Y809667D01*
X222267Y809833D01*
X222733Y809750D01*
X223067Y809583D01*
X223400Y809250D01*
G01X227300Y806500D02*
X226900Y806583D01*
X226500Y806917D01*
X226233Y807500D01*
X226100Y808167D01*
X226233Y808833D01*
X226500Y809417D01*
X226900Y809750D01*
X227300Y809833D01*
X227700Y809750D01*
X228100Y809417D01*
X228367Y808833D01*
X228433Y808167D01*
X228367Y807500D01*
X228100Y806917D01*
X227700Y806583D01*
X227300Y806500D01*
G01X233467Y809417D02*
X233000Y809750D01*
X232600Y809833D01*
X232067Y809667D01*
X231667Y809333D01*
X231400Y808750D01*
X231333Y808167D01*
X231400Y807583D01*
X231667Y807083D01*
X232067Y806667D01*
X232600Y806500D01*
X233067Y806667D01*
X233467Y807000D01*
G01X236367Y809833D02*
Y807500D01*
X236633Y806917D01*
X237033Y806583D01*
X237500Y806500D01*
X237967Y806583D01*
X238367Y806917D01*
X238633Y807500D01*
G01Y806500D02*
Y809833D01*
G01X240600Y806500D02*
Y809833D01*
G01Y808917D02*
X240800Y809333D01*
X241133Y809667D01*
X241600Y809833D01*
X242067Y809667D01*
X242400Y809333D01*
X242600Y808917D01*
Y806500D01*
G01Y808917D02*
X242800Y809333D01*
X243133Y809667D01*
X243600Y809833D01*
X244067Y809667D01*
X244400Y809333D01*
X244600Y808833D01*
Y806500D01*
G01X246700Y808750D02*
X248833D01*
X248633Y809333D01*
X248300Y809667D01*
X247833Y809833D01*
X247367Y809750D01*
X246967Y809500D01*
X246700Y808917D01*
X246567Y808417D01*
Y807917D01*
X246700Y807417D01*
X247033Y806917D01*
X247433Y806583D01*
X247900Y806500D01*
X248367Y806667D01*
X248833Y807167D01*
G01X251667Y806500D02*
Y809833D01*
G01Y809000D02*
X251933Y809417D01*
X252333Y809750D01*
X252867Y809833D01*
X253333Y809750D01*
X253733Y809417D01*
X253933Y808833D01*
Y806500D01*
G01X257900Y811500D02*
Y806500D01*
G01X256967Y809833D02*
X258833D01*
G01X262000Y807083D02*
X262333Y806750D01*
X262800Y806500D01*
X263200D01*
X263600Y806667D01*
X263867Y806917D01*
X264000Y807250D01*
X263933Y807750D01*
X263667Y808000D01*
X262467Y808500D01*
X262200Y809083D01*
X262333Y809500D01*
X262600Y809750D01*
X263000Y809833D01*
X263400Y809750D01*
X263800Y809500D01*
G01X273200Y809833D02*
Y806500D01*
G01Y811167D02*
X273067Y811250D01*
Y811417D01*
X273200Y811500D01*
X273333Y811417D01*
Y811250D01*
X273200Y811167D01*
G01X277167Y806500D02*
Y809833D01*
G01Y809000D02*
X277433Y809417D01*
X277833Y809750D01*
X278367Y809833D01*
X278833Y809750D01*
X279233Y809417D01*
X279433Y808833D01*
Y806500D01*
G01X289567Y809417D02*
X289100Y809750D01*
X288700Y809833D01*
X288167Y809667D01*
X287767Y809333D01*
X287500Y808750D01*
X287433Y808167D01*
X287500Y807583D01*
X287767Y807083D01*
X288167Y806667D01*
X288700Y806500D01*
X289167Y806667D01*
X289567Y807000D01*
G01X293600Y806500D02*
Y811500D01*
G01X299900Y806500D02*
Y809833D01*
G01Y809250D02*
X299633Y809583D01*
X299233Y809750D01*
X298767Y809833D01*
X298300Y809667D01*
X297900Y809333D01*
X297633Y808833D01*
X297500Y808167D01*
X297633Y807500D01*
X297900Y807000D01*
X298300Y806667D01*
X298767Y806500D01*
X299233Y806583D01*
X299633Y806833D01*
X299900Y807167D01*
G01X302800Y807083D02*
X303133Y806750D01*
X303600Y806500D01*
X304000D01*
X304400Y806667D01*
X304667Y806917D01*
X304800Y807250D01*
X304733Y807750D01*
X304467Y808000D01*
X303267Y808500D01*
X303000Y809083D01*
X303133Y809500D01*
X303400Y809750D01*
X303800Y809833D01*
X304200Y809750D01*
X304600Y809500D01*
G01X307900Y807083D02*
X308233Y806750D01*
X308700Y806500D01*
X309100D01*
X309500Y806667D01*
X309767Y806917D01*
X309900Y807250D01*
X309833Y807750D01*
X309567Y808000D01*
X308367Y808500D01*
X308100Y809083D01*
X308233Y809500D01*
X308500Y809750D01*
X308900Y809833D01*
X309300Y809750D01*
X309700Y809500D01*
G01X317833Y810667D02*
X318233Y811167D01*
X318700Y811417D01*
X319233Y811500D01*
X319900Y811333D01*
X320367Y810917D01*
X320500Y810417D01*
X320433Y809917D01*
X320167Y809500D01*
X318833Y808667D01*
X318233Y808083D01*
X317833Y807250D01*
X317700Y806500D01*
X320500D01*
G01X330500D02*
Y809833D01*
G01Y809250D02*
X330233Y809583D01*
X329833Y809750D01*
X329367Y809833D01*
X328900Y809667D01*
X328500Y809333D01*
X328233Y808833D01*
X328100Y808167D01*
X328233Y807500D01*
X328500Y807000D01*
X328900Y806667D01*
X329367Y806500D01*
X329833Y806583D01*
X330233Y806833D01*
X330500Y807167D01*
G01X333267Y806500D02*
Y809833D01*
G01Y809000D02*
X333533Y809417D01*
X333933Y809750D01*
X334467Y809833D01*
X334933Y809750D01*
X335333Y809417D01*
X335533Y808833D01*
Y806500D01*
G01X340700Y811500D02*
Y806500D01*
G01Y807250D02*
X340433Y806833D01*
X340033Y806583D01*
X339567Y806500D01*
X339033Y806667D01*
X338633Y807083D01*
X338367Y807583D01*
X338300Y808167D01*
X338367Y808750D01*
X338633Y809250D01*
X339033Y809667D01*
X339567Y809833D01*
X340033Y809750D01*
X340367Y809583D01*
X340700Y809250D01*
G01X349700Y811500D02*
Y806500D01*
G01X348767Y809833D02*
X350633D01*
G01X353667Y806500D02*
Y811500D01*
G01Y809083D02*
X354000Y809500D01*
X354333Y809750D01*
X354867Y809833D01*
X355267Y809750D01*
X355733Y809417D01*
X355933Y808917D01*
Y806500D01*
G01X358900Y808750D02*
X361033D01*
X360833Y809333D01*
X360500Y809667D01*
X360033Y809833D01*
X359567Y809750D01*
X359167Y809500D01*
X358900Y808917D01*
X358767Y808417D01*
Y807917D01*
X358900Y807417D01*
X359233Y806917D01*
X359633Y806583D01*
X360100Y806500D01*
X360567Y806667D01*
X361033Y807167D01*
G01X370100Y806500D02*
Y811500D01*
G01X376400Y806500D02*
Y809833D01*
G01Y809250D02*
X376133Y809583D01*
X375733Y809750D01*
X375267Y809833D01*
X374800Y809667D01*
X374400Y809333D01*
X374133Y808833D01*
X374000Y808167D01*
X374133Y807500D01*
X374400Y807000D01*
X374800Y806667D01*
X375267Y806500D01*
X375733Y806583D01*
X376133Y806833D01*
X376400Y807167D01*
G01X380300Y811500D02*
Y806500D01*
G01X379367Y809833D02*
X381233D01*
G01X384400Y808750D02*
X386533D01*
X386333Y809333D01*
X386000Y809667D01*
X385533Y809833D01*
X385067Y809750D01*
X384667Y809500D01*
X384400Y808917D01*
X384267Y808417D01*
Y807917D01*
X384400Y807417D01*
X384733Y806917D01*
X385133Y806583D01*
X385600Y806500D01*
X386067Y806667D01*
X386533Y807167D01*
G01X389500Y807083D02*
X389833Y806750D01*
X390300Y806500D01*
X390700D01*
X391100Y806667D01*
X391367Y806917D01*
X391500Y807250D01*
X391433Y807750D01*
X391167Y808000D01*
X389967Y808500D01*
X389700Y809083D01*
X389833Y809500D01*
X390100Y809750D01*
X390500Y809833D01*
X390900Y809750D01*
X391300Y809500D01*
G01X395600Y811500D02*
Y806500D01*
G01X394667Y809833D02*
X396533D01*
G01X404600D02*
X405800Y806500D01*
X407000Y809833D01*
G01X409900Y808750D02*
X412033D01*
X411833Y809333D01*
X411500Y809667D01*
X411033Y809833D01*
X410567Y809750D01*
X410167Y809500D01*
X409900Y808917D01*
X409767Y808417D01*
Y807917D01*
X409900Y807417D01*
X410233Y806917D01*
X410633Y806583D01*
X411100Y806500D01*
X411567Y806667D01*
X412033Y807167D01*
G01X415067Y806500D02*
Y809833D01*
G01Y809167D02*
X415400Y809500D01*
X415733Y809750D01*
X416200Y809833D01*
X416533Y809750D01*
X416933Y809500D01*
G01X420100Y807083D02*
X420433Y806750D01*
X420900Y806500D01*
X421300D01*
X421700Y806667D01*
X421967Y806917D01*
X422100Y807250D01*
X422033Y807750D01*
X421767Y808000D01*
X420567Y808500D01*
X420300Y809083D01*
X420433Y809500D01*
X420700Y809750D01*
X421100Y809833D01*
X421500Y809750D01*
X421900Y809500D01*
G01X426200Y809833D02*
Y806500D01*
G01Y811167D02*
X426067Y811250D01*
Y811417D01*
X426200Y811500D01*
X426333Y811417D01*
Y811250D01*
X426200Y811167D01*
G01X431300Y806500D02*
X430900Y806583D01*
X430500Y806917D01*
X430233Y807500D01*
X430100Y808167D01*
X430233Y808833D01*
X430500Y809417D01*
X430900Y809750D01*
X431300Y809833D01*
X431700Y809750D01*
X432100Y809417D01*
X432367Y808833D01*
X432433Y808167D01*
X432367Y807500D01*
X432100Y806917D01*
X431700Y806583D01*
X431300Y806500D01*
G01X435267D02*
Y809833D01*
G01Y809000D02*
X435533Y809417D01*
X435933Y809750D01*
X436467Y809833D01*
X436933Y809750D01*
X437333Y809417D01*
X437533Y808833D01*
Y806500D01*
G01X446600Y809833D02*
Y806500D01*
G01Y811167D02*
X446467Y811250D01*
Y811417D01*
X446600Y811500D01*
X446733Y811417D01*
Y811250D01*
X446600Y811167D01*
G01X450700Y807083D02*
X451033Y806750D01*
X451500Y806500D01*
X451900D01*
X452300Y806667D01*
X452567Y806917D01*
X452700Y807250D01*
X452633Y807750D01*
X452367Y808000D01*
X451167Y808500D01*
X450900Y809083D01*
X451033Y809500D01*
X451300Y809750D01*
X451700Y809833D01*
X452100Y809750D01*
X452500Y809500D01*
G01X460967Y806500D02*
Y809833D01*
G01Y809167D02*
X461300Y809500D01*
X461633Y809750D01*
X462100Y809833D01*
X462433Y809750D01*
X462833Y809500D01*
G01X466000Y808750D02*
X468133D01*
X467933Y809333D01*
X467600Y809667D01*
X467133Y809833D01*
X466667Y809750D01*
X466267Y809500D01*
X466000Y808917D01*
X465867Y808417D01*
Y807917D01*
X466000Y807417D01*
X466333Y806917D01*
X466733Y806583D01*
X467200Y806500D01*
X467667Y806667D01*
X468133Y807167D01*
G01X473300Y804833D02*
Y809833D01*
G01Y809083D02*
X472967Y809500D01*
X472567Y809750D01*
X472100Y809833D01*
X471700Y809750D01*
X471233Y809333D01*
X470967Y808750D01*
X470900Y808167D01*
X470967Y807583D01*
X471233Y807000D01*
X471700Y806583D01*
X472100Y806500D01*
X472567Y806583D01*
X472967Y806833D01*
X473300Y807250D01*
G01X476067Y809833D02*
Y807500D01*
X476333Y806917D01*
X476733Y806583D01*
X477200Y806500D01*
X477667Y806583D01*
X478067Y806917D01*
X478333Y807500D01*
G01Y806500D02*
Y809833D01*
G01X482300D02*
Y806500D01*
G01Y811167D02*
X482167Y811250D01*
Y811417D01*
X482300Y811500D01*
X482433Y811417D01*
Y811250D01*
X482300Y811167D01*
G01X486467Y806500D02*
Y809833D01*
G01Y809167D02*
X486800Y809500D01*
X487133Y809750D01*
X487600Y809833D01*
X487933Y809750D01*
X488333Y809500D01*
G01X491500Y808750D02*
X493633D01*
X493433Y809333D01*
X493100Y809667D01*
X492633Y809833D01*
X492167Y809750D01*
X491767Y809500D01*
X491500Y808917D01*
X491367Y808417D01*
Y807917D01*
X491500Y807417D01*
X491833Y806917D01*
X492233Y806583D01*
X492700Y806500D01*
X493167Y806667D01*
X493633Y807167D01*
G01X498800Y811500D02*
Y806500D01*
G01Y807250D02*
X498533Y806833D01*
X498133Y806583D01*
X497667Y806500D01*
X497133Y806667D01*
X496733Y807083D01*
X496467Y807583D01*
X496400Y808167D01*
X496467Y808750D01*
X496733Y809250D01*
X497133Y809667D01*
X497667Y809833D01*
X498133Y809750D01*
X498467Y809583D01*
X498800Y809250D01*
G01X502567Y805583D02*
X502833Y806667D01*
G01X112167Y-60000D02*
Y-65000D01*
X114833D01*
G01X118600D02*
X118200Y-64917D01*
X117800Y-64583D01*
X117533Y-64000D01*
X117400Y-63333D01*
X117533Y-62667D01*
X117800Y-62083D01*
X118200Y-61750D01*
X118600Y-61667D01*
X119000Y-61750D01*
X119400Y-62083D01*
X119667Y-62667D01*
X119733Y-63333D01*
X119667Y-64000D01*
X119400Y-64583D01*
X119000Y-64917D01*
X118600Y-65000D01*
G01X122767Y-66250D02*
X123233Y-66583D01*
X123767Y-66667D01*
X124233Y-66583D01*
X124633Y-66167D01*
X124900Y-65583D01*
Y-61667D01*
G01Y-62333D02*
X124633Y-62000D01*
X124233Y-61750D01*
X123767Y-61667D01*
X123233Y-61833D01*
X122900Y-62167D01*
X122633Y-62750D01*
X122500Y-63333D01*
X122567Y-63833D01*
X122833Y-64417D01*
X123233Y-64833D01*
X123767Y-65000D01*
X124167Y-64917D01*
X124633Y-64583D01*
X124900Y-64250D01*
G01X128800Y-65000D02*
X128400Y-64917D01*
X128000Y-64583D01*
X127733Y-64000D01*
X127600Y-63333D01*
X127733Y-62667D01*
X128000Y-62083D01*
X128400Y-61750D01*
X128800Y-61667D01*
X129200Y-61750D01*
X129600Y-62083D01*
X129867Y-62667D01*
X129933Y-63333D01*
X129867Y-64000D01*
X129600Y-64583D01*
X129200Y-64917D01*
X128800Y-65000D01*
G01X113500Y-36000D02*
Y-41000D01*
G01X112567Y-37667D02*
X114433D01*
G01X117467Y-41000D02*
Y-36000D01*
G01Y-38417D02*
X117800Y-38000D01*
X118133Y-37750D01*
X118667Y-37667D01*
X119067Y-37750D01*
X119533Y-38083D01*
X119733Y-38583D01*
Y-41000D01*
G01X123700Y-37667D02*
Y-41000D01*
G01Y-36333D02*
X123567Y-36250D01*
Y-36083D01*
X123700Y-36000D01*
X123833Y-36083D01*
Y-36250D01*
X123700Y-36333D01*
G01X129867Y-38083D02*
X129400Y-37750D01*
X129000Y-37667D01*
X128467Y-37833D01*
X128067Y-38167D01*
X127800Y-38750D01*
X127733Y-39333D01*
X127800Y-39917D01*
X128067Y-40417D01*
X128467Y-40833D01*
X129000Y-41000D01*
X129467Y-40833D01*
X129867Y-40500D01*
G01X132767Y-41000D02*
Y-36000D01*
G01X134900Y-37667D02*
X132767Y-39583D01*
G01X133633Y-38833D02*
X135033Y-41000D01*
G01X137867D02*
Y-37667D01*
G01Y-38500D02*
X138133Y-38083D01*
X138533Y-37750D01*
X139067Y-37667D01*
X139533Y-37750D01*
X139933Y-38083D01*
X140133Y-38667D01*
Y-41000D01*
G01X143100Y-38750D02*
X145233D01*
X145033Y-38167D01*
X144700Y-37833D01*
X144233Y-37667D01*
X143767Y-37750D01*
X143367Y-38000D01*
X143100Y-38583D01*
X142967Y-39083D01*
Y-39583D01*
X143100Y-40083D01*
X143433Y-40583D01*
X143833Y-40917D01*
X144300Y-41000D01*
X144767Y-40833D01*
X145233Y-40333D01*
G01X148200Y-40417D02*
X148533Y-40750D01*
X149000Y-41000D01*
X149400D01*
X149800Y-40833D01*
X150067Y-40583D01*
X150200Y-40250D01*
X150133Y-39750D01*
X149867Y-39500D01*
X148667Y-39000D01*
X148400Y-38417D01*
X148533Y-38000D01*
X148800Y-37750D01*
X149200Y-37667D01*
X149600Y-37750D01*
X150000Y-38000D01*
G01X153300Y-40417D02*
X153633Y-40750D01*
X154100Y-41000D01*
X154500D01*
X154900Y-40833D01*
X155167Y-40583D01*
X155300Y-40250D01*
X155233Y-39750D01*
X154967Y-39500D01*
X153767Y-39000D01*
X153500Y-38417D01*
X153633Y-38000D01*
X153900Y-37750D01*
X154300Y-37667D01*
X154700Y-37750D01*
X155100Y-38000D01*
G01X112417Y24700D02*
Y29700D01*
X114150Y25533D01*
X115883Y29700D01*
Y24700D01*
G01X120450D02*
Y28033D01*
G01Y27450D02*
X120183Y27783D01*
X119783Y27950D01*
X119317Y28033D01*
X118850Y27867D01*
X118450Y27533D01*
X118183Y27033D01*
X118050Y26367D01*
X118183Y25700D01*
X118450Y25200D01*
X118850Y24867D01*
X119317Y24700D01*
X119783Y24783D01*
X120183Y25033D01*
X120450Y25367D01*
G01X123417Y24700D02*
Y28033D01*
G01Y27367D02*
X123750Y27700D01*
X124083Y27950D01*
X124550Y28033D01*
X124883Y27950D01*
X125283Y27700D01*
G01X128317Y24700D02*
Y29700D01*
G01X130450Y28033D02*
X128317Y26117D01*
G01X129183Y26867D02*
X130583Y24700D01*
G01X134883Y23033D02*
X135550Y23867D01*
X135883Y24700D01*
Y28033D01*
X135550Y28867D01*
X134883Y29700D01*
G01X112470Y36130D02*
X113803D01*
Y34630D01*
X113403Y34130D01*
X112937Y33797D01*
X112270Y33630D01*
X111603Y33797D01*
X111137Y34130D01*
X110737Y34630D01*
X110470Y35213D01*
X110337Y35880D01*
Y36463D01*
X110470Y36963D01*
X110737Y37547D01*
X111137Y38047D01*
X111537Y38380D01*
X112070Y38630D01*
X112537D01*
X113070Y38463D01*
X113470Y38130D01*
G01X117170Y33630D02*
X116770Y33713D01*
X116370Y34047D01*
X116103Y34630D01*
X115970Y35297D01*
X116103Y35963D01*
X116370Y36547D01*
X116770Y36880D01*
X117170Y36963D01*
X117570Y36880D01*
X117970Y36547D01*
X118237Y35963D01*
X118303Y35297D01*
X118237Y34630D01*
X117970Y34047D01*
X117570Y33713D01*
X117170Y33630D01*
G01X122270D02*
Y38630D01*
G01X128570D02*
Y33630D01*
G01Y34380D02*
X128303Y33963D01*
X127903Y33713D01*
X127437Y33630D01*
X126903Y33797D01*
X126503Y34213D01*
X126237Y34713D01*
X126170Y35297D01*
X126237Y35880D01*
X126503Y36380D01*
X126903Y36797D01*
X127437Y36963D01*
X127903Y36880D01*
X128237Y36713D01*
X128570Y36380D01*
G01X131470Y35880D02*
X133603D01*
X133403Y36463D01*
X133070Y36797D01*
X132603Y36963D01*
X132137Y36880D01*
X131737Y36630D01*
X131470Y36047D01*
X131337Y35547D01*
Y35047D01*
X131470Y34547D01*
X131803Y34047D01*
X132203Y33713D01*
X132670Y33630D01*
X133137Y33797D01*
X133603Y34297D01*
G01X136437Y33630D02*
Y36963D01*
G01Y36130D02*
X136703Y36547D01*
X137103Y36880D01*
X137637Y36963D01*
X138103Y36880D01*
X138503Y36547D01*
X138703Y35963D01*
Y33630D01*
G01X147370D02*
Y37880D01*
X147503Y38297D01*
X147770Y38547D01*
X148170Y38630D01*
X148570Y38463D01*
X148770Y38047D01*
G01X147970Y36630D02*
X146637D01*
G01X152870Y36963D02*
Y33630D01*
G01Y38297D02*
X152737Y38380D01*
Y38547D01*
X152870Y38630D01*
X153003Y38547D01*
Y38380D01*
X152870Y38297D01*
G01X156837Y33630D02*
Y36963D01*
G01Y36130D02*
X157103Y36547D01*
X157503Y36880D01*
X158037Y36963D01*
X158503Y36880D01*
X158903Y36547D01*
X159103Y35963D01*
Y33630D01*
G01X162137Y32380D02*
X162603Y32047D01*
X163137Y31963D01*
X163603Y32047D01*
X164003Y32463D01*
X164270Y33047D01*
Y36963D01*
G01Y36297D02*
X164003Y36630D01*
X163603Y36880D01*
X163137Y36963D01*
X162603Y36797D01*
X162270Y36463D01*
X162003Y35880D01*
X161870Y35297D01*
X161937Y34797D01*
X162203Y34213D01*
X162603Y33797D01*
X163137Y33630D01*
X163537Y33713D01*
X164003Y34047D01*
X164270Y34380D01*
G01X167170Y35880D02*
X169303D01*
X169103Y36463D01*
X168770Y36797D01*
X168303Y36963D01*
X167837Y36880D01*
X167437Y36630D01*
X167170Y36047D01*
X167037Y35547D01*
Y35047D01*
X167170Y34547D01*
X167503Y34047D01*
X167903Y33713D01*
X168370Y33630D01*
X168837Y33797D01*
X169303Y34297D01*
G01X172337Y33630D02*
Y36963D01*
G01Y36297D02*
X172670Y36630D01*
X173003Y36880D01*
X173470Y36963D01*
X173803Y36880D01*
X174203Y36630D01*
G01X182137Y33630D02*
Y38630D01*
X183737D01*
X184270Y38380D01*
X184670Y37797D01*
X184803Y37130D01*
X184670Y36463D01*
X184337Y35963D01*
X183737Y35713D01*
X182137D01*
G01X186903Y33630D02*
X188570Y38630D01*
X190237Y33630D01*
G01X189637Y35380D02*
X187503D01*
G01X192203Y33630D02*
Y38630D01*
X193537D01*
X194070Y38380D01*
X194470Y38047D01*
X194803Y37547D01*
X195070Y36963D01*
X195137Y36130D01*
X195070Y35297D01*
X194803Y34713D01*
X194470Y34213D01*
X194070Y33880D01*
X193537Y33630D01*
X192203D01*
G01X202670Y33463D02*
X205070Y38630D01*
G01X207703Y33630D02*
Y38630D01*
X210237D01*
G01X209303Y36213D02*
X207703D01*
G01X214070Y36963D02*
Y33630D01*
G01Y38297D02*
X213937Y38380D01*
Y38547D01*
X214070Y38630D01*
X214203Y38547D01*
Y38380D01*
X214070Y38297D01*
G01X220370Y38630D02*
Y33630D01*
G01Y34380D02*
X220103Y33963D01*
X219703Y33713D01*
X219237Y33630D01*
X218703Y33797D01*
X218303Y34213D01*
X218037Y34713D01*
X217970Y35297D01*
X218037Y35880D01*
X218303Y36380D01*
X218703Y36797D01*
X219237Y36963D01*
X219703Y36880D01*
X220037Y36713D01*
X220370Y36380D01*
G01X223137Y36963D02*
Y34630D01*
X223403Y34047D01*
X223803Y33713D01*
X224270Y33630D01*
X224737Y33713D01*
X225137Y34047D01*
X225403Y34630D01*
G01Y33630D02*
Y36963D01*
G01X230437Y36547D02*
X229970Y36880D01*
X229570Y36963D01*
X229037Y36797D01*
X228637Y36463D01*
X228370Y35880D01*
X228303Y35297D01*
X228370Y34713D01*
X228637Y34213D01*
X229037Y33797D01*
X229570Y33630D01*
X230037Y33797D01*
X230437Y34130D01*
G01X234470Y36963D02*
Y33630D01*
G01Y38297D02*
X234337Y38380D01*
Y38547D01*
X234470Y38630D01*
X234603Y38547D01*
Y38380D01*
X234470Y38297D01*
G01X240770Y33630D02*
Y36963D01*
G01Y36380D02*
X240503Y36713D01*
X240103Y36880D01*
X239637Y36963D01*
X239170Y36797D01*
X238770Y36463D01*
X238503Y35963D01*
X238370Y35297D01*
X238503Y34630D01*
X238770Y34130D01*
X239170Y33797D01*
X239637Y33630D01*
X240103Y33713D01*
X240503Y33963D01*
X240770Y34297D01*
G01X244670Y33630D02*
Y38630D01*
G01X113500Y-15000D02*
Y-20000D01*
G01X112567Y-16667D02*
X114433D01*
G01X117467Y-20000D02*
Y-15000D01*
G01Y-17417D02*
X117800Y-17000D01*
X118133Y-16750D01*
X118667Y-16667D01*
X119067Y-16750D01*
X119533Y-17083D01*
X119733Y-17583D01*
Y-20000D01*
G01X123700Y-16667D02*
Y-20000D01*
G01Y-15333D02*
X123567Y-15250D01*
Y-15083D01*
X123700Y-15000D01*
X123833Y-15083D01*
Y-15250D01*
X123700Y-15333D01*
G01X129867Y-17083D02*
X129400Y-16750D01*
X129000Y-16667D01*
X128467Y-16833D01*
X128067Y-17167D01*
X127800Y-17750D01*
X127733Y-18333D01*
X127800Y-18917D01*
X128067Y-19417D01*
X128467Y-19833D01*
X129000Y-20000D01*
X129467Y-19833D01*
X129867Y-19500D01*
G01X132767Y-20000D02*
Y-15000D01*
G01X134900Y-16667D02*
X132767Y-18583D01*
G01X133633Y-17833D02*
X135033Y-20000D01*
G01X137867D02*
Y-16667D01*
G01Y-17500D02*
X138133Y-17083D01*
X138533Y-16750D01*
X139067Y-16667D01*
X139533Y-16750D01*
X139933Y-17083D01*
X140133Y-17667D01*
Y-20000D01*
G01X143100Y-17750D02*
X145233D01*
X145033Y-17167D01*
X144700Y-16833D01*
X144233Y-16667D01*
X143767Y-16750D01*
X143367Y-17000D01*
X143100Y-17583D01*
X142967Y-18083D01*
Y-18583D01*
X143100Y-19083D01*
X143433Y-19583D01*
X143833Y-19917D01*
X144300Y-20000D01*
X144767Y-19833D01*
X145233Y-19333D01*
G01X148200Y-19417D02*
X148533Y-19750D01*
X149000Y-20000D01*
X149400D01*
X149800Y-19833D01*
X150067Y-19583D01*
X150200Y-19250D01*
X150133Y-18750D01*
X149867Y-18500D01*
X148667Y-18000D01*
X148400Y-17417D01*
X148533Y-17000D01*
X148800Y-16750D01*
X149200Y-16667D01*
X149600Y-16750D01*
X150000Y-17000D01*
G01X153300Y-19417D02*
X153633Y-19750D01*
X154100Y-20000D01*
X154500D01*
X154900Y-19833D01*
X155167Y-19583D01*
X155300Y-19250D01*
X155233Y-18750D01*
X154967Y-18500D01*
X153767Y-18000D01*
X153500Y-17417D01*
X153633Y-17000D01*
X153900Y-16750D01*
X154300Y-16667D01*
X154700Y-16750D01*
X155100Y-17000D01*
G01X118267Y-2167D02*
X117600Y-1333D01*
X117267Y-500D01*
Y2833D01*
X117600Y3667D01*
X118267Y4500D01*
G01X122300Y167D02*
X122833Y-250D01*
X123433Y-500D01*
X123967D01*
X124500Y-250D01*
X124900Y167D01*
X125100Y750D01*
X124967Y1333D01*
X124633Y1833D01*
X124033Y2167D01*
X123233Y2333D01*
X122767Y2667D01*
X122567Y3250D01*
X122700Y3833D01*
X123033Y4250D01*
X123500Y4500D01*
X123967D01*
X124433Y4333D01*
X124833Y3917D01*
G01X127067Y-500D02*
Y4500D01*
X128800Y333D01*
X130533Y4500D01*
Y-500D01*
G01X132433D02*
Y4500D01*
X133767D01*
X134300Y4250D01*
X134700Y3917D01*
X135033Y3417D01*
X135300Y2833D01*
X135367Y2000D01*
X135300Y1167D01*
X135033Y583D01*
X134700Y83D01*
X134300Y-250D01*
X133767Y-500D01*
X132433D01*
G01X139333Y-2167D02*
X140000Y-1333D01*
X140333Y-500D01*
Y2833D01*
X140000Y3667D01*
X139333Y4500D01*
G01X112100Y12167D02*
X112633Y11750D01*
X113233Y11500D01*
X113767D01*
X114300Y11750D01*
X114700Y12167D01*
X114900Y12750D01*
X114767Y13333D01*
X114433Y13833D01*
X113833Y14167D01*
X113033Y14333D01*
X112567Y14667D01*
X112367Y15250D01*
X112500Y15833D01*
X112833Y16250D01*
X113300Y16500D01*
X113767D01*
X114233Y16333D01*
X114633Y15917D01*
G01X118600Y11500D02*
X118200Y11583D01*
X117800Y11917D01*
X117533Y12500D01*
X117400Y13167D01*
X117533Y13833D01*
X117800Y14417D01*
X118200Y14750D01*
X118600Y14833D01*
X119000Y14750D01*
X119400Y14417D01*
X119667Y13833D01*
X119733Y13167D01*
X119667Y12500D01*
X119400Y11917D01*
X119000Y11583D01*
X118600Y11500D01*
G01X123700D02*
Y16500D01*
G01X130000D02*
Y11500D01*
G01Y12250D02*
X129733Y11833D01*
X129333Y11583D01*
X128867Y11500D01*
X128333Y11667D01*
X127933Y12083D01*
X127667Y12583D01*
X127600Y13167D01*
X127667Y13750D01*
X127933Y14250D01*
X128333Y14667D01*
X128867Y14833D01*
X129333Y14750D01*
X129667Y14583D01*
X130000Y14250D01*
G01X132900Y13750D02*
X135033D01*
X134833Y14333D01*
X134500Y14667D01*
X134033Y14833D01*
X133567Y14750D01*
X133167Y14500D01*
X132900Y13917D01*
X132767Y13417D01*
Y12917D01*
X132900Y12417D01*
X133233Y11917D01*
X133633Y11583D01*
X134100Y11500D01*
X134567Y11667D01*
X135033Y12167D01*
G01X138067Y11500D02*
Y14833D01*
G01Y14167D02*
X138400Y14500D01*
X138733Y14750D01*
X139200Y14833D01*
X139533Y14750D01*
X139933Y14500D01*
G01X147200Y11500D02*
Y14833D01*
G01Y13917D02*
X147400Y14333D01*
X147733Y14667D01*
X148200Y14833D01*
X148667Y14667D01*
X149000Y14333D01*
X149200Y13917D01*
Y11500D01*
G01Y13917D02*
X149400Y14333D01*
X149733Y14667D01*
X150200Y14833D01*
X150667Y14667D01*
X151000Y14333D01*
X151200Y13833D01*
Y11500D01*
G01X155500D02*
Y14833D01*
G01Y14250D02*
X155233Y14583D01*
X154833Y14750D01*
X154367Y14833D01*
X153900Y14667D01*
X153500Y14333D01*
X153233Y13833D01*
X153100Y13167D01*
X153233Y12500D01*
X153500Y12000D01*
X153900Y11667D01*
X154367Y11500D01*
X154833Y11583D01*
X155233Y11833D01*
X155500Y12167D01*
G01X158400Y12083D02*
X158733Y11750D01*
X159200Y11500D01*
X159600D01*
X160000Y11667D01*
X160267Y11917D01*
X160400Y12250D01*
X160333Y12750D01*
X160067Y13000D01*
X158867Y13500D01*
X158600Y14083D01*
X158733Y14500D01*
X159000Y14750D01*
X159400Y14833D01*
X159800Y14750D01*
X160200Y14500D01*
G01X163367Y11500D02*
Y16500D01*
G01X165500Y14833D02*
X163367Y12917D01*
G01X164233Y13667D02*
X165633Y11500D01*
G01X175900Y16500D02*
Y11500D01*
G01Y12250D02*
X175633Y11833D01*
X175233Y11583D01*
X174767Y11500D01*
X174233Y11667D01*
X173833Y12083D01*
X173567Y12583D01*
X173500Y13167D01*
X173567Y13750D01*
X173833Y14250D01*
X174233Y14667D01*
X174767Y14833D01*
X175233Y14750D01*
X175567Y14583D01*
X175900Y14250D01*
G01X178800Y13750D02*
X180933D01*
X180733Y14333D01*
X180400Y14667D01*
X179933Y14833D01*
X179467Y14750D01*
X179067Y14500D01*
X178800Y13917D01*
X178667Y13417D01*
Y12917D01*
X178800Y12417D01*
X179133Y11917D01*
X179533Y11583D01*
X180000Y11500D01*
X180467Y11667D01*
X180933Y12167D01*
G01X184500Y11500D02*
Y15750D01*
X184633Y16167D01*
X184900Y16417D01*
X185300Y16500D01*
X185700Y16333D01*
X185900Y15917D01*
G01X185100Y14500D02*
X183767D01*
G01X190000Y14833D02*
Y11500D01*
G01Y16167D02*
X189867Y16250D01*
Y16417D01*
X190000Y16500D01*
X190133Y16417D01*
Y16250D01*
X190000Y16167D01*
G01X193967Y11500D02*
Y14833D01*
G01Y14000D02*
X194233Y14417D01*
X194633Y14750D01*
X195167Y14833D01*
X195633Y14750D01*
X196033Y14417D01*
X196233Y13833D01*
Y11500D01*
G01X199200Y13750D02*
X201333D01*
X201133Y14333D01*
X200800Y14667D01*
X200333Y14833D01*
X199867Y14750D01*
X199467Y14500D01*
X199200Y13917D01*
X199067Y13417D01*
Y12917D01*
X199200Y12417D01*
X199533Y11917D01*
X199933Y11583D01*
X200400Y11500D01*
X200867Y11667D01*
X201333Y12167D01*
G01X209200Y9833D02*
Y14833D01*
G01Y14083D02*
X209533Y14500D01*
X209867Y14750D01*
X210400Y14833D01*
X210867Y14750D01*
X211333Y14333D01*
X211533Y13750D01*
X211600Y13167D01*
X211533Y12583D01*
X211333Y12000D01*
X210933Y11667D01*
X210400Y11500D01*
X209933Y11583D01*
X209467Y11833D01*
X209200Y12167D01*
G01X216700Y11500D02*
Y14833D01*
G01Y14250D02*
X216433Y14583D01*
X216033Y14750D01*
X215567Y14833D01*
X215100Y14667D01*
X214700Y14333D01*
X214433Y13833D01*
X214300Y13167D01*
X214433Y12500D01*
X214700Y12000D01*
X215100Y11667D01*
X215567Y11500D01*
X216033Y11583D01*
X216433Y11833D01*
X216700Y12167D01*
G01X221800Y16500D02*
Y11500D01*
G01Y12250D02*
X221533Y11833D01*
X221133Y11583D01*
X220667Y11500D01*
X220133Y11667D01*
X219733Y12083D01*
X219467Y12583D01*
X219400Y13167D01*
X219467Y13750D01*
X219733Y14250D01*
X220133Y14667D01*
X220667Y14833D01*
X221133Y14750D01*
X221467Y14583D01*
X221800Y14250D01*
G01X112327Y42673D02*
X111660Y43507D01*
X111327Y44340D01*
Y47673D01*
X111660Y48507D01*
X112327Y49340D01*
G01X115760Y44340D02*
Y47673D01*
G01Y46757D02*
X115960Y47173D01*
X116293Y47507D01*
X116760Y47673D01*
X117227Y47507D01*
X117560Y47173D01*
X117760Y46757D01*
Y44340D01*
G01Y46757D02*
X117960Y47173D01*
X118293Y47507D01*
X118760Y47673D01*
X119227Y47507D01*
X119560Y47173D01*
X119760Y46673D01*
Y44340D01*
G01X121860Y46590D02*
X123993D01*
X123793Y47173D01*
X123460Y47507D01*
X122993Y47673D01*
X122527Y47590D01*
X122127Y47340D01*
X121860Y46757D01*
X121727Y46257D01*
Y45757D01*
X121860Y45257D01*
X122193Y44757D01*
X122593Y44423D01*
X123060Y44340D01*
X123527Y44507D01*
X123993Y45007D01*
G01X129160Y44340D02*
Y47673D01*
G01Y47090D02*
X128893Y47423D01*
X128493Y47590D01*
X128027Y47673D01*
X127560Y47507D01*
X127160Y47173D01*
X126893Y46673D01*
X126760Y46007D01*
X126893Y45340D01*
X127160Y44840D01*
X127560Y44507D01*
X128027Y44340D01*
X128493Y44423D01*
X128893Y44673D01*
X129160Y45007D01*
G01X132060Y44923D02*
X132393Y44590D01*
X132860Y44340D01*
X133260D01*
X133660Y44507D01*
X133927Y44757D01*
X134060Y45090D01*
X133993Y45590D01*
X133727Y45840D01*
X132527Y46340D01*
X132260Y46923D01*
X132393Y47340D01*
X132660Y47590D01*
X133060Y47673D01*
X133460Y47590D01*
X133860Y47340D01*
G01X137027Y47673D02*
Y45340D01*
X137293Y44757D01*
X137693Y44423D01*
X138160Y44340D01*
X138627Y44423D01*
X139027Y44757D01*
X139293Y45340D01*
G01Y44340D02*
Y47673D01*
G01X142327Y44340D02*
Y47673D01*
G01Y47007D02*
X142660Y47340D01*
X142993Y47590D01*
X143460Y47673D01*
X143793Y47590D01*
X144193Y47340D01*
G01X147360Y46590D02*
X149493D01*
X149293Y47173D01*
X148960Y47507D01*
X148493Y47673D01*
X148027Y47590D01*
X147627Y47340D01*
X147360Y46757D01*
X147227Y46257D01*
Y45757D01*
X147360Y45257D01*
X147693Y44757D01*
X148093Y44423D01*
X148560Y44340D01*
X149027Y44507D01*
X149493Y45007D01*
G01X158560Y49340D02*
Y44340D01*
G01X157627Y47673D02*
X159493D01*
G01X163660Y44340D02*
X163260Y44423D01*
X162860Y44757D01*
X162593Y45340D01*
X162460Y46007D01*
X162593Y46673D01*
X162860Y47257D01*
X163260Y47590D01*
X163660Y47673D01*
X164060Y47590D01*
X164460Y47257D01*
X164727Y46673D01*
X164793Y46007D01*
X164727Y45340D01*
X164460Y44757D01*
X164060Y44423D01*
X163660Y44340D01*
G01X167560Y42673D02*
Y47673D01*
G01Y46923D02*
X167893Y47340D01*
X168227Y47590D01*
X168760Y47673D01*
X169227Y47590D01*
X169693Y47173D01*
X169893Y46590D01*
X169960Y46007D01*
X169893Y45423D01*
X169693Y44840D01*
X169293Y44507D01*
X168760Y44340D01*
X168293Y44423D01*
X167827Y44673D01*
X167560Y45007D01*
G01X177960Y44923D02*
X178293Y44590D01*
X178760Y44340D01*
X179160D01*
X179560Y44507D01*
X179827Y44757D01*
X179960Y45090D01*
X179893Y45590D01*
X179627Y45840D01*
X178427Y46340D01*
X178160Y46923D01*
X178293Y47340D01*
X178560Y47590D01*
X178960Y47673D01*
X179360Y47590D01*
X179760Y47340D01*
G01X184060Y47673D02*
Y44340D01*
G01Y49007D02*
X183927Y49090D01*
Y49257D01*
X184060Y49340D01*
X184193Y49257D01*
Y49090D01*
X184060Y49007D01*
G01X188160Y47673D02*
X190160D01*
X188160Y44340D01*
X190160D01*
G01X193260Y46590D02*
X195393D01*
X195193Y47173D01*
X194860Y47507D01*
X194393Y47673D01*
X193927Y47590D01*
X193527Y47340D01*
X193260Y46757D01*
X193127Y46257D01*
Y45757D01*
X193260Y45257D01*
X193593Y44757D01*
X193993Y44423D01*
X194460Y44340D01*
X194927Y44507D01*
X195393Y45007D01*
G01X204460Y44340D02*
X204060Y44423D01*
X203660Y44757D01*
X203393Y45340D01*
X203260Y46007D01*
X203393Y46673D01*
X203660Y47257D01*
X204060Y47590D01*
X204460Y47673D01*
X204860Y47590D01*
X205260Y47257D01*
X205527Y46673D01*
X205593Y46007D01*
X205527Y45340D01*
X205260Y44757D01*
X204860Y44423D01*
X204460Y44340D01*
G01X209160D02*
Y48590D01*
X209293Y49007D01*
X209560Y49257D01*
X209960Y49340D01*
X210360Y49173D01*
X210560Y48757D01*
G01X209760Y47340D02*
X208427D01*
G01X218427Y44340D02*
Y49340D01*
X220027D01*
X220560Y49090D01*
X220960Y48507D01*
X221093Y47840D01*
X220960Y47173D01*
X220627Y46673D01*
X220027Y46423D01*
X218427D01*
G01X223193Y44340D02*
X224860Y49340D01*
X226527Y44340D01*
G01X225927Y46090D02*
X223793D01*
G01X228493Y44340D02*
Y49340D01*
X229827D01*
X230360Y49090D01*
X230760Y48757D01*
X231093Y48257D01*
X231360Y47673D01*
X231427Y46840D01*
X231360Y46007D01*
X231093Y45423D01*
X230760Y44923D01*
X230360Y44590D01*
X229827Y44340D01*
X228493D01*
G01X238960Y44173D02*
X241360Y49340D01*
G01X112167Y51500D02*
Y56500D01*
X113767D01*
X114300Y56250D01*
X114700Y55667D01*
X114833Y55000D01*
X114700Y54333D01*
X114367Y53833D01*
X113767Y53583D01*
X112167D01*
G01X116933Y51500D02*
X118600Y56500D01*
X120267Y51500D01*
G01X119667Y53250D02*
X117533D01*
G01X122233Y51500D02*
Y56500D01*
X123567D01*
X124100Y56250D01*
X124500Y55917D01*
X124833Y55417D01*
X125100Y54833D01*
X125167Y54000D01*
X125100Y53167D01*
X124833Y52583D01*
X124500Y52083D01*
X124100Y51750D01*
X123567Y51500D01*
X122233D01*
G01X132900Y52083D02*
X133233Y51750D01*
X133700Y51500D01*
X134100D01*
X134500Y51667D01*
X134767Y51917D01*
X134900Y52250D01*
X134833Y52750D01*
X134567Y53000D01*
X133367Y53500D01*
X133100Y54083D01*
X133233Y54500D01*
X133500Y54750D01*
X133900Y54833D01*
X134300Y54750D01*
X134700Y54500D01*
G01X139000Y54833D02*
Y51500D01*
G01Y56167D02*
X138867Y56250D01*
Y56417D01*
X139000Y56500D01*
X139133Y56417D01*
Y56250D01*
X139000Y56167D01*
G01X143100Y54833D02*
X145100D01*
X143100Y51500D01*
X145100D01*
G01X148200Y53750D02*
X150333D01*
X150133Y54333D01*
X149800Y54667D01*
X149333Y54833D01*
X148867Y54750D01*
X148467Y54500D01*
X148200Y53917D01*
X148067Y53417D01*
Y52917D01*
X148200Y52417D01*
X148533Y51917D01*
X148933Y51583D01*
X149400Y51500D01*
X149867Y51667D01*
X150333Y52167D01*
G01X113500Y85000D02*
Y80000D01*
G01X111967Y85000D02*
X115033D01*
G01X117667Y80000D02*
Y83333D01*
G01Y82667D02*
X118000Y83000D01*
X118333Y83250D01*
X118800Y83333D01*
X119133Y83250D01*
X119533Y83000D01*
G01X124900Y80000D02*
Y83333D01*
G01Y82750D02*
X124633Y83083D01*
X124233Y83250D01*
X123767Y83333D01*
X123300Y83167D01*
X122900Y82833D01*
X122633Y82333D01*
X122500Y81667D01*
X122633Y81000D01*
X122900Y80500D01*
X123300Y80167D01*
X123767Y80000D01*
X124233Y80083D01*
X124633Y80333D01*
X124900Y80667D01*
G01X129867Y82917D02*
X129400Y83250D01*
X129000Y83333D01*
X128467Y83167D01*
X128067Y82833D01*
X127800Y82250D01*
X127733Y81667D01*
X127800Y81083D01*
X128067Y80583D01*
X128467Y80167D01*
X129000Y80000D01*
X129467Y80167D01*
X129867Y80500D01*
G01X132900Y82250D02*
X135033D01*
X134833Y82833D01*
X134500Y83167D01*
X134033Y83333D01*
X133567Y83250D01*
X133167Y83000D01*
X132900Y82417D01*
X132767Y81917D01*
Y81417D01*
X132900Y80917D01*
X133233Y80417D01*
X133633Y80083D01*
X134100Y80000D01*
X134567Y80167D01*
X135033Y80667D01*
G01X142433Y83333D02*
X143233Y80000D01*
X144100Y83333D01*
X144967Y80000D01*
X145767Y83333D01*
G01X149200D02*
Y80000D01*
G01Y84667D02*
X149067Y84750D01*
Y84917D01*
X149200Y85000D01*
X149333Y84917D01*
Y84750D01*
X149200Y84667D01*
G01X155500Y85000D02*
Y80000D01*
G01Y80750D02*
X155233Y80333D01*
X154833Y80083D01*
X154367Y80000D01*
X153833Y80167D01*
X153433Y80583D01*
X153167Y81083D01*
X153100Y81667D01*
X153167Y82250D01*
X153433Y82750D01*
X153833Y83167D01*
X154367Y83333D01*
X154833Y83250D01*
X155167Y83083D01*
X155500Y82750D01*
G01X159400Y85000D02*
Y80000D01*
G01X158467Y83333D02*
X160333D01*
G01X163367Y80000D02*
Y85000D01*
G01Y82583D02*
X163700Y83000D01*
X164033Y83250D01*
X164567Y83333D01*
X164967Y83250D01*
X165433Y82917D01*
X165633Y82417D01*
Y80000D01*
G01X112167Y111500D02*
Y116500D01*
X113833D01*
X114367Y116250D01*
X114700Y115917D01*
X114833Y115250D01*
X114700Y114583D01*
X114300Y114167D01*
X113833Y113917D01*
X112167D01*
G01X113833D02*
X114833Y111500D01*
G01X117600Y113750D02*
X119733D01*
X119533Y114333D01*
X119200Y114667D01*
X118733Y114833D01*
X118267Y114750D01*
X117867Y114500D01*
X117600Y113917D01*
X117467Y113417D01*
Y112917D01*
X117600Y112417D01*
X117933Y111917D01*
X118333Y111583D01*
X118800Y111500D01*
X119267Y111667D01*
X119733Y112167D01*
G01X123700Y111500D02*
Y116500D01*
G01X130000Y111500D02*
Y114833D01*
G01Y114250D02*
X129733Y114583D01*
X129333Y114750D01*
X128867Y114833D01*
X128400Y114667D01*
X128000Y114333D01*
X127733Y113833D01*
X127600Y113167D01*
X127733Y112500D01*
X128000Y112000D01*
X128400Y111667D01*
X128867Y111500D01*
X129333Y111583D01*
X129733Y111833D01*
X130000Y112167D01*
G01X133900Y116500D02*
Y111500D01*
G01X132967Y114833D02*
X134833D01*
G01X139000D02*
Y111500D01*
G01Y116167D02*
X138867Y116250D01*
Y116417D01*
X139000Y116500D01*
X139133Y116417D01*
Y116250D01*
X139000Y116167D01*
G01X142900Y114833D02*
X144100Y111500D01*
X145300Y114833D01*
G01X148200Y113750D02*
X150333D01*
X150133Y114333D01*
X149800Y114667D01*
X149333Y114833D01*
X148867Y114750D01*
X148467Y114500D01*
X148200Y113917D01*
X148067Y113417D01*
Y112917D01*
X148200Y112417D01*
X148533Y111917D01*
X148933Y111583D01*
X149400Y111500D01*
X149867Y111667D01*
X150333Y112167D01*
G01X158200Y109833D02*
Y114833D01*
G01Y114083D02*
X158533Y114500D01*
X158867Y114750D01*
X159400Y114833D01*
X159867Y114750D01*
X160333Y114333D01*
X160533Y113750D01*
X160600Y113167D01*
X160533Y112583D01*
X160333Y112000D01*
X159933Y111667D01*
X159400Y111500D01*
X158933Y111583D01*
X158467Y111833D01*
X158200Y112167D01*
G01X164500Y111500D02*
X164100Y111583D01*
X163700Y111917D01*
X163433Y112500D01*
X163300Y113167D01*
X163433Y113833D01*
X163700Y114417D01*
X164100Y114750D01*
X164500Y114833D01*
X164900Y114750D01*
X165300Y114417D01*
X165567Y113833D01*
X165633Y113167D01*
X165567Y112500D01*
X165300Y111917D01*
X164900Y111583D01*
X164500Y111500D01*
G01X168600Y112083D02*
X168933Y111750D01*
X169400Y111500D01*
X169800D01*
X170200Y111667D01*
X170467Y111917D01*
X170600Y112250D01*
X170533Y112750D01*
X170267Y113000D01*
X169067Y113500D01*
X168800Y114083D01*
X168933Y114500D01*
X169200Y114750D01*
X169600Y114833D01*
X170000Y114750D01*
X170400Y114500D01*
G01X174700Y114833D02*
Y111500D01*
G01Y116167D02*
X174567Y116250D01*
Y116417D01*
X174700Y116500D01*
X174833Y116417D01*
Y116250D01*
X174700Y116167D01*
G01X179800Y116500D02*
Y111500D01*
G01X178867Y114833D02*
X180733D01*
G01X184900D02*
Y111500D01*
G01Y116167D02*
X184767Y116250D01*
Y116417D01*
X184900Y116500D01*
X185033Y116417D01*
Y116250D01*
X184900Y116167D01*
G01X190000Y111500D02*
X189600Y111583D01*
X189200Y111917D01*
X188933Y112500D01*
X188800Y113167D01*
X188933Y113833D01*
X189200Y114417D01*
X189600Y114750D01*
X190000Y114833D01*
X190400Y114750D01*
X190800Y114417D01*
X191067Y113833D01*
X191133Y113167D01*
X191067Y112500D01*
X190800Y111917D01*
X190400Y111583D01*
X190000Y111500D01*
G01X193967D02*
Y114833D01*
G01Y114000D02*
X194233Y114417D01*
X194633Y114750D01*
X195167Y114833D01*
X195633Y114750D01*
X196033Y114417D01*
X196233Y113833D01*
Y111500D01*
G01X113500Y143500D02*
Y138500D01*
G01X112567Y141833D02*
X114433D01*
G01X117467Y138500D02*
Y143500D01*
G01Y141083D02*
X117800Y141500D01*
X118133Y141750D01*
X118667Y141833D01*
X119067Y141750D01*
X119533Y141417D01*
X119733Y140917D01*
Y138500D01*
G01X123700Y141833D02*
Y138500D01*
G01Y143167D02*
X123567Y143250D01*
Y143417D01*
X123700Y143500D01*
X123833Y143417D01*
Y143250D01*
X123700Y143167D01*
G01X129867Y141417D02*
X129400Y141750D01*
X129000Y141833D01*
X128467Y141667D01*
X128067Y141333D01*
X127800Y140750D01*
X127733Y140167D01*
X127800Y139583D01*
X128067Y139083D01*
X128467Y138667D01*
X129000Y138500D01*
X129467Y138667D01*
X129867Y139000D01*
G01X132767Y138500D02*
Y143500D01*
G01X134900Y141833D02*
X132767Y139917D01*
G01X133633Y140667D02*
X135033Y138500D01*
G01X137867D02*
Y141833D01*
G01Y141000D02*
X138133Y141417D01*
X138533Y141750D01*
X139067Y141833D01*
X139533Y141750D01*
X139933Y141417D01*
X140133Y140833D01*
Y138500D01*
G01X143100Y140750D02*
X145233D01*
X145033Y141333D01*
X144700Y141667D01*
X144233Y141833D01*
X143767Y141750D01*
X143367Y141500D01*
X143100Y140917D01*
X142967Y140417D01*
Y139917D01*
X143100Y139417D01*
X143433Y138917D01*
X143833Y138583D01*
X144300Y138500D01*
X144767Y138667D01*
X145233Y139167D01*
G01X148200Y139083D02*
X148533Y138750D01*
X149000Y138500D01*
X149400D01*
X149800Y138667D01*
X150067Y138917D01*
X150200Y139250D01*
X150133Y139750D01*
X149867Y140000D01*
X148667Y140500D01*
X148400Y141083D01*
X148533Y141500D01*
X148800Y141750D01*
X149200Y141833D01*
X149600Y141750D01*
X150000Y141500D01*
G01X153300Y139083D02*
X153633Y138750D01*
X154100Y138500D01*
X154500D01*
X154900Y138667D01*
X155167Y138917D01*
X155300Y139250D01*
X155233Y139750D01*
X154967Y140000D01*
X153767Y140500D01*
X153500Y141083D01*
X153633Y141500D01*
X153900Y141750D01*
X154300Y141833D01*
X154700Y141750D01*
X155100Y141500D01*
G01X165700Y138500D02*
Y141833D01*
G01Y141250D02*
X165433Y141583D01*
X165033Y141750D01*
X164567Y141833D01*
X164100Y141667D01*
X163700Y141333D01*
X163433Y140833D01*
X163300Y140167D01*
X163433Y139500D01*
X163700Y139000D01*
X164100Y138667D01*
X164567Y138500D01*
X165033Y138583D01*
X165433Y138833D01*
X165700Y139167D01*
G01X169200Y138500D02*
Y142750D01*
X169333Y143167D01*
X169600Y143417D01*
X170000Y143500D01*
X170400Y143333D01*
X170600Y142917D01*
G01X169800Y141500D02*
X168467D01*
G01X174700Y143500D02*
Y138500D01*
G01X173767Y141833D02*
X175633D01*
G01X178800Y140750D02*
X180933D01*
X180733Y141333D01*
X180400Y141667D01*
X179933Y141833D01*
X179467Y141750D01*
X179067Y141500D01*
X178800Y140917D01*
X178667Y140417D01*
Y139917D01*
X178800Y139417D01*
X179133Y138917D01*
X179533Y138583D01*
X180000Y138500D01*
X180467Y138667D01*
X180933Y139167D01*
G01X183967Y138500D02*
Y141833D01*
G01Y141167D02*
X184300Y141500D01*
X184633Y141750D01*
X185100Y141833D01*
X185433Y141750D01*
X185833Y141500D01*
G01X193900Y136833D02*
Y141833D01*
G01Y141083D02*
X194233Y141500D01*
X194567Y141750D01*
X195100Y141833D01*
X195567Y141750D01*
X196033Y141333D01*
X196233Y140750D01*
X196300Y140167D01*
X196233Y139583D01*
X196033Y139000D01*
X195633Y138667D01*
X195100Y138500D01*
X194633Y138583D01*
X194167Y138833D01*
X193900Y139167D01*
G01X200200Y138500D02*
Y143500D01*
G01X206500Y138500D02*
Y141833D01*
G01Y141250D02*
X206233Y141583D01*
X205833Y141750D01*
X205367Y141833D01*
X204900Y141667D01*
X204500Y141333D01*
X204233Y140833D01*
X204100Y140167D01*
X204233Y139500D01*
X204500Y139000D01*
X204900Y138667D01*
X205367Y138500D01*
X205833Y138583D01*
X206233Y138833D01*
X206500Y139167D01*
G01X210400Y143500D02*
Y138500D01*
G01X209467Y141833D02*
X211333D01*
G01X215500D02*
Y138500D01*
G01Y143167D02*
X215367Y143250D01*
Y143417D01*
X215500Y143500D01*
X215633Y143417D01*
Y143250D01*
X215500Y143167D01*
G01X219467Y138500D02*
Y141833D01*
G01Y141000D02*
X219733Y141417D01*
X220133Y141750D01*
X220667Y141833D01*
X221133Y141750D01*
X221533Y141417D01*
X221733Y140833D01*
Y138500D01*
G01X224767Y137250D02*
X225233Y136917D01*
X225767Y136833D01*
X226233Y136917D01*
X226633Y137333D01*
X226900Y137917D01*
Y141833D01*
G01Y141167D02*
X226633Y141500D01*
X226233Y141750D01*
X225767Y141833D01*
X225233Y141667D01*
X224900Y141333D01*
X224633Y140750D01*
X224500Y140167D01*
X224567Y139667D01*
X224833Y139083D01*
X225233Y138667D01*
X225767Y138500D01*
X226167Y138583D01*
X226633Y138917D01*
X226900Y139250D01*
G01X114833Y148500D02*
X112167D01*
Y153500D01*
X114833D01*
G01X113767Y151083D02*
X112167D01*
G01X117600Y151833D02*
X119600Y148500D01*
G01Y151833D02*
X117600Y148500D01*
G01X123700Y153500D02*
Y148500D01*
G01X122767Y151833D02*
X124633D01*
G01X127800Y150750D02*
X129933D01*
X129733Y151333D01*
X129400Y151667D01*
X128933Y151833D01*
X128467Y151750D01*
X128067Y151500D01*
X127800Y150917D01*
X127667Y150417D01*
Y149917D01*
X127800Y149417D01*
X128133Y148917D01*
X128533Y148583D01*
X129000Y148500D01*
X129467Y148667D01*
X129933Y149167D01*
G01X132967Y148500D02*
Y151833D01*
G01Y151167D02*
X133300Y151500D01*
X133633Y151750D01*
X134100Y151833D01*
X134433Y151750D01*
X134833Y151500D01*
G01X137867Y148500D02*
Y151833D01*
G01Y151000D02*
X138133Y151417D01*
X138533Y151750D01*
X139067Y151833D01*
X139533Y151750D01*
X139933Y151417D01*
X140133Y150833D01*
Y148500D01*
G01X145300D02*
Y151833D01*
G01Y151250D02*
X145033Y151583D01*
X144633Y151750D01*
X144167Y151833D01*
X143700Y151667D01*
X143300Y151333D01*
X143033Y150833D01*
X142900Y150167D01*
X143033Y149500D01*
X143300Y149000D01*
X143700Y148667D01*
X144167Y148500D01*
X144633Y148583D01*
X145033Y148833D01*
X145300Y149167D01*
G01X149200Y148500D02*
Y153500D01*
G01X160467Y151417D02*
X160000Y151750D01*
X159600Y151833D01*
X159067Y151667D01*
X158667Y151333D01*
X158400Y150750D01*
X158333Y150167D01*
X158400Y149583D01*
X158667Y149083D01*
X159067Y148667D01*
X159600Y148500D01*
X160067Y148667D01*
X160467Y149000D01*
G01X164500Y148500D02*
X164100Y148583D01*
X163700Y148917D01*
X163433Y149500D01*
X163300Y150167D01*
X163433Y150833D01*
X163700Y151417D01*
X164100Y151750D01*
X164500Y151833D01*
X164900Y151750D01*
X165300Y151417D01*
X165567Y150833D01*
X165633Y150167D01*
X165567Y149500D01*
X165300Y148917D01*
X164900Y148583D01*
X164500Y148500D01*
G01X168467D02*
Y151833D01*
G01Y151000D02*
X168733Y151417D01*
X169133Y151750D01*
X169667Y151833D01*
X170133Y151750D01*
X170533Y151417D01*
X170733Y150833D01*
Y148500D01*
G01X175900Y153500D02*
Y148500D01*
G01Y149250D02*
X175633Y148833D01*
X175233Y148583D01*
X174767Y148500D01*
X174233Y148667D01*
X173833Y149083D01*
X173567Y149583D01*
X173500Y150167D01*
X173567Y150750D01*
X173833Y151250D01*
X174233Y151667D01*
X174767Y151833D01*
X175233Y151750D01*
X175567Y151583D01*
X175900Y151250D01*
G01X178667Y151833D02*
Y149500D01*
X178933Y148917D01*
X179333Y148583D01*
X179800Y148500D01*
X180267Y148583D01*
X180667Y148917D01*
X180933Y149500D01*
G01Y148500D02*
Y151833D01*
G01X185967Y151417D02*
X185500Y151750D01*
X185100Y151833D01*
X184567Y151667D01*
X184167Y151333D01*
X183900Y150750D01*
X183833Y150167D01*
X183900Y149583D01*
X184167Y149083D01*
X184567Y148667D01*
X185100Y148500D01*
X185567Y148667D01*
X185967Y149000D01*
G01X190000Y153500D02*
Y148500D01*
G01X189067Y151833D02*
X190933D01*
G01X195100Y148500D02*
X194700Y148583D01*
X194300Y148917D01*
X194033Y149500D01*
X193900Y150167D01*
X194033Y150833D01*
X194300Y151417D01*
X194700Y151750D01*
X195100Y151833D01*
X195500Y151750D01*
X195900Y151417D01*
X196167Y150833D01*
X196233Y150167D01*
X196167Y149500D01*
X195900Y148917D01*
X195500Y148583D01*
X195100Y148500D01*
G01X199267D02*
Y151833D01*
G01Y151167D02*
X199600Y151500D01*
X199933Y151750D01*
X200400Y151833D01*
X200733Y151750D01*
X201133Y151500D01*
G01X112167Y356500D02*
Y351500D01*
X114833D01*
G01X119800D02*
Y354833D01*
G01Y354250D02*
X119533Y354583D01*
X119133Y354750D01*
X118667Y354833D01*
X118200Y354667D01*
X117800Y354333D01*
X117533Y353833D01*
X117400Y353167D01*
X117533Y352500D01*
X117800Y352000D01*
X118200Y351667D01*
X118667Y351500D01*
X119133Y351583D01*
X119533Y351833D01*
X119800Y352167D01*
G01X122700Y352083D02*
X123033Y351750D01*
X123500Y351500D01*
X123900D01*
X124300Y351667D01*
X124567Y351917D01*
X124700Y352250D01*
X124633Y352750D01*
X124367Y353000D01*
X123167Y353500D01*
X122900Y354083D01*
X123033Y354500D01*
X123300Y354750D01*
X123700Y354833D01*
X124100Y354750D01*
X124500Y354500D01*
G01X127800Y353750D02*
X129933D01*
X129733Y354333D01*
X129400Y354667D01*
X128933Y354833D01*
X128467Y354750D01*
X128067Y354500D01*
X127800Y353917D01*
X127667Y353417D01*
Y352917D01*
X127800Y352417D01*
X128133Y351917D01*
X128533Y351583D01*
X129000Y351500D01*
X129467Y351667D01*
X129933Y352167D01*
G01X132967Y351500D02*
Y354833D01*
G01Y354167D02*
X133300Y354500D01*
X133633Y354750D01*
X134100Y354833D01*
X134433Y354750D01*
X134833Y354500D01*
G01X142900Y354833D02*
X144100Y351500D01*
X145300Y354833D01*
G01X149200D02*
Y351500D01*
G01Y356167D02*
X149067Y356250D01*
Y356417D01*
X149200Y356500D01*
X149333Y356417D01*
Y356250D01*
X149200Y356167D01*
G01X155500Y351500D02*
Y354833D01*
G01Y354250D02*
X155233Y354583D01*
X154833Y354750D01*
X154367Y354833D01*
X153900Y354667D01*
X153500Y354333D01*
X153233Y353833D01*
X153100Y353167D01*
X153233Y352500D01*
X153500Y352000D01*
X153900Y351667D01*
X154367Y351500D01*
X154833Y351583D01*
X155233Y351833D01*
X155500Y352167D01*
G01X163033Y351333D02*
X165967Y355000D01*
G01X164500Y355667D02*
Y350667D01*
G01X165967Y351333D02*
X163033Y355000D01*
G01X162500Y353167D02*
X166500D01*
G01X169267Y349833D02*
X168600Y350667D01*
X168267Y351500D01*
Y354833D01*
X168600Y355667D01*
X169267Y356500D01*
G01X173233Y352250D02*
X173633Y351833D01*
X174100Y351583D01*
X174700Y351500D01*
X175300Y351667D01*
X175767Y352000D01*
X176100Y352583D01*
X176167Y353250D01*
X176033Y353917D01*
X175700Y354333D01*
X175233Y354667D01*
X174767Y354750D01*
X174300Y354667D01*
X173700Y354333D01*
X173900Y356500D01*
X175700D01*
G01X179800Y351333D02*
X179667Y351417D01*
Y351583D01*
X179800Y351667D01*
X179933Y351583D01*
Y351417D01*
X179800Y351333D01*
G01X184900Y351500D02*
Y356500D01*
X184100Y355500D01*
G01Y351500D02*
X185700D01*
G01X190333Y349833D02*
X191000Y350667D01*
X191333Y351500D01*
Y354833D01*
X191000Y355667D01*
X190333Y356500D01*
G01X112167Y406500D02*
Y411500D01*
X113767D01*
X114300Y411250D01*
X114700Y410667D01*
X114833Y410000D01*
X114700Y409333D01*
X114367Y408833D01*
X113767Y408583D01*
X112167D01*
G01X118600Y411500D02*
Y406500D01*
G01X117067Y411500D02*
X120133D01*
G01X122300Y406500D02*
Y411500D01*
G01X125100D02*
Y406500D01*
G01Y409000D02*
X122300D01*
G01X132967Y406500D02*
Y409833D01*
G01Y409167D02*
X133300Y409500D01*
X133633Y409750D01*
X134100Y409833D01*
X134433Y409750D01*
X134833Y409500D01*
G01X138000Y408750D02*
X140133D01*
X139933Y409333D01*
X139600Y409667D01*
X139133Y409833D01*
X138667Y409750D01*
X138267Y409500D01*
X138000Y408917D01*
X137867Y408417D01*
Y407917D01*
X138000Y407417D01*
X138333Y406917D01*
X138733Y406583D01*
X139200Y406500D01*
X139667Y406667D01*
X140133Y407167D01*
G01X143167Y405250D02*
X143633Y404917D01*
X144167Y404833D01*
X144633Y404917D01*
X145033Y405333D01*
X145300Y405917D01*
Y409833D01*
G01Y409167D02*
X145033Y409500D01*
X144633Y409750D01*
X144167Y409833D01*
X143633Y409667D01*
X143300Y409333D01*
X143033Y408750D01*
X142900Y408167D01*
X142967Y407667D01*
X143233Y407083D01*
X143633Y406667D01*
X144167Y406500D01*
X144567Y406583D01*
X145033Y406917D01*
X145300Y407250D01*
G01X149200Y409833D02*
Y406500D01*
G01Y411167D02*
X149067Y411250D01*
Y411417D01*
X149200Y411500D01*
X149333Y411417D01*
Y411250D01*
X149200Y411167D01*
G01X153300Y407083D02*
X153633Y406750D01*
X154100Y406500D01*
X154500D01*
X154900Y406667D01*
X155167Y406917D01*
X155300Y407250D01*
X155233Y407750D01*
X154967Y408000D01*
X153767Y408500D01*
X153500Y409083D01*
X153633Y409500D01*
X153900Y409750D01*
X154300Y409833D01*
X154700Y409750D01*
X155100Y409500D01*
G01X159400Y411500D02*
Y406500D01*
G01X158467Y409833D02*
X160333D01*
G01X163567Y406500D02*
Y409833D01*
G01Y409167D02*
X163900Y409500D01*
X164233Y409750D01*
X164700Y409833D01*
X165033Y409750D01*
X165433Y409500D01*
G01X170800Y406500D02*
Y409833D01*
G01Y409250D02*
X170533Y409583D01*
X170133Y409750D01*
X169667Y409833D01*
X169200Y409667D01*
X168800Y409333D01*
X168533Y408833D01*
X168400Y408167D01*
X168533Y407500D01*
X168800Y407000D01*
X169200Y406667D01*
X169667Y406500D01*
X170133Y406583D01*
X170533Y406833D01*
X170800Y407167D01*
G01X174700Y411500D02*
Y406500D01*
G01X173767Y409833D02*
X175633D01*
G01X179800D02*
Y406500D01*
G01Y411167D02*
X179667Y411250D01*
Y411417D01*
X179800Y411500D01*
X179933Y411417D01*
Y411250D01*
X179800Y411167D01*
G01X184900Y406500D02*
X184500Y406583D01*
X184100Y406917D01*
X183833Y407500D01*
X183700Y408167D01*
X183833Y408833D01*
X184100Y409417D01*
X184500Y409750D01*
X184900Y409833D01*
X185300Y409750D01*
X185700Y409417D01*
X185967Y408833D01*
X186033Y408167D01*
X185967Y407500D01*
X185700Y406917D01*
X185300Y406583D01*
X184900Y406500D01*
G01X188867D02*
Y409833D01*
G01Y409000D02*
X189133Y409417D01*
X189533Y409750D01*
X190067Y409833D01*
X190533Y409750D01*
X190933Y409417D01*
X191133Y408833D01*
Y406500D01*
G01X112033Y433000D02*
Y438000D01*
X113367D01*
X113900Y437750D01*
X114300Y437417D01*
X114633Y436917D01*
X114900Y436333D01*
X114967Y435500D01*
X114900Y434667D01*
X114633Y434083D01*
X114300Y433583D01*
X113900Y433250D01*
X113367Y433000D01*
X112033D01*
G01X117600Y435250D02*
X119733D01*
X119533Y435833D01*
X119200Y436167D01*
X118733Y436333D01*
X118267Y436250D01*
X117867Y436000D01*
X117600Y435417D01*
X117467Y434917D01*
Y434417D01*
X117600Y433917D01*
X117933Y433417D01*
X118333Y433083D01*
X118800Y433000D01*
X119267Y433167D01*
X119733Y433667D01*
G01X122500Y431333D02*
Y436333D01*
G01Y435583D02*
X122833Y436000D01*
X123167Y436250D01*
X123700Y436333D01*
X124167Y436250D01*
X124633Y435833D01*
X124833Y435250D01*
X124900Y434667D01*
X124833Y434083D01*
X124633Y433500D01*
X124233Y433167D01*
X123700Y433000D01*
X123233Y433083D01*
X122767Y433333D01*
X122500Y433667D01*
G01X128800Y438000D02*
Y433000D01*
G01X127867Y436333D02*
X129733D01*
G01X132767Y433000D02*
Y438000D01*
G01Y435583D02*
X133100Y436000D01*
X133433Y436250D01*
X133967Y436333D01*
X134367Y436250D01*
X134833Y435917D01*
X135033Y435417D01*
Y433000D01*
G01X145167Y435917D02*
X144700Y436250D01*
X144300Y436333D01*
X143767Y436167D01*
X143367Y435833D01*
X143100Y435250D01*
X143033Y434667D01*
X143100Y434083D01*
X143367Y433583D01*
X143767Y433167D01*
X144300Y433000D01*
X144767Y433167D01*
X145167Y433500D01*
G01X149200Y433000D02*
X148800Y433083D01*
X148400Y433417D01*
X148133Y434000D01*
X148000Y434667D01*
X148133Y435333D01*
X148400Y435917D01*
X148800Y436250D01*
X149200Y436333D01*
X149600Y436250D01*
X150000Y435917D01*
X150267Y435333D01*
X150333Y434667D01*
X150267Y434000D01*
X150000Y433417D01*
X149600Y433083D01*
X149200Y433000D01*
G01X153167D02*
Y436333D01*
G01Y435500D02*
X153433Y435917D01*
X153833Y436250D01*
X154367Y436333D01*
X154833Y436250D01*
X155233Y435917D01*
X155433Y435333D01*
Y433000D01*
G01X159400Y438000D02*
Y433000D01*
G01X158467Y436333D02*
X160333D01*
G01X163567Y433000D02*
Y436333D01*
G01Y435667D02*
X163900Y436000D01*
X164233Y436250D01*
X164700Y436333D01*
X165033Y436250D01*
X165433Y436000D01*
G01X169600Y433000D02*
X169200Y433083D01*
X168800Y433417D01*
X168533Y434000D01*
X168400Y434667D01*
X168533Y435333D01*
X168800Y435917D01*
X169200Y436250D01*
X169600Y436333D01*
X170000Y436250D01*
X170400Y435917D01*
X170667Y435333D01*
X170733Y434667D01*
X170667Y434000D01*
X170400Y433417D01*
X170000Y433083D01*
X169600Y433000D01*
G01X174700D02*
Y438000D01*
G01X183767Y433000D02*
Y438000D01*
G01Y435583D02*
X184100Y436000D01*
X184433Y436250D01*
X184967Y436333D01*
X185367Y436250D01*
X185833Y435917D01*
X186033Y435417D01*
Y433000D01*
G01X190000D02*
X189600Y433083D01*
X189200Y433417D01*
X188933Y434000D01*
X188800Y434667D01*
X188933Y435333D01*
X189200Y435917D01*
X189600Y436250D01*
X190000Y436333D01*
X190400Y436250D01*
X190800Y435917D01*
X191067Y435333D01*
X191133Y434667D01*
X191067Y434000D01*
X190800Y433417D01*
X190400Y433083D01*
X190000Y433000D01*
G01X195100D02*
Y438000D01*
G01X199200Y435250D02*
X201333D01*
X201133Y435833D01*
X200800Y436167D01*
X200333Y436333D01*
X199867Y436250D01*
X199467Y436000D01*
X199200Y435417D01*
X199067Y434917D01*
Y434417D01*
X199200Y433917D01*
X199533Y433417D01*
X199933Y433083D01*
X200400Y433000D01*
X200867Y433167D01*
X201333Y433667D01*
G01X112167Y455000D02*
Y460000D01*
X113833D01*
X114367Y459750D01*
X114700Y459417D01*
X114833Y458750D01*
X114700Y458083D01*
X114300Y457667D01*
X113833Y457417D01*
X112167D01*
G01X113833D02*
X114833Y455000D01*
G01X118600D02*
X118200Y455083D01*
X117800Y455417D01*
X117533Y456000D01*
X117400Y456667D01*
X117533Y457333D01*
X117800Y457917D01*
X118200Y458250D01*
X118600Y458333D01*
X119000Y458250D01*
X119400Y457917D01*
X119667Y457333D01*
X119733Y456667D01*
X119667Y456000D01*
X119400Y455417D01*
X119000Y455083D01*
X118600Y455000D01*
G01X122567Y458333D02*
Y456000D01*
X122833Y455417D01*
X123233Y455083D01*
X123700Y455000D01*
X124167Y455083D01*
X124567Y455417D01*
X124833Y456000D01*
G01Y455000D02*
Y458333D01*
G01X127867Y453750D02*
X128333Y453417D01*
X128867Y453333D01*
X129333Y453417D01*
X129733Y453833D01*
X130000Y454417D01*
Y458333D01*
G01Y457667D02*
X129733Y458000D01*
X129333Y458250D01*
X128867Y458333D01*
X128333Y458167D01*
X128000Y457833D01*
X127733Y457250D01*
X127600Y456667D01*
X127667Y456167D01*
X127933Y455583D01*
X128333Y455167D01*
X128867Y455000D01*
X129267Y455083D01*
X129733Y455417D01*
X130000Y455750D01*
G01X132767Y455000D02*
Y460000D01*
G01Y457583D02*
X133100Y458000D01*
X133433Y458250D01*
X133967Y458333D01*
X134367Y458250D01*
X134833Y457917D01*
X135033Y457417D01*
Y455000D01*
G01X137867D02*
Y458333D01*
G01Y457500D02*
X138133Y457917D01*
X138533Y458250D01*
X139067Y458333D01*
X139533Y458250D01*
X139933Y457917D01*
X140133Y457333D01*
Y455000D01*
G01X143100Y457250D02*
X145233D01*
X145033Y457833D01*
X144700Y458167D01*
X144233Y458333D01*
X143767Y458250D01*
X143367Y458000D01*
X143100Y457417D01*
X142967Y456917D01*
Y456417D01*
X143100Y455917D01*
X143433Y455417D01*
X143833Y455083D01*
X144300Y455000D01*
X144767Y455167D01*
X145233Y455667D01*
G01X148200Y455583D02*
X148533Y455250D01*
X149000Y455000D01*
X149400D01*
X149800Y455167D01*
X150067Y455417D01*
X150200Y455750D01*
X150133Y456250D01*
X149867Y456500D01*
X148667Y457000D01*
X148400Y457583D01*
X148533Y458000D01*
X148800Y458250D01*
X149200Y458333D01*
X149600Y458250D01*
X150000Y458000D01*
G01X153300Y455583D02*
X153633Y455250D01*
X154100Y455000D01*
X154500D01*
X154900Y455167D01*
X155167Y455417D01*
X155300Y455750D01*
X155233Y456250D01*
X154967Y456500D01*
X153767Y457000D01*
X153500Y457583D01*
X153633Y458000D01*
X153900Y458250D01*
X154300Y458333D01*
X154700Y458250D01*
X155100Y458000D01*
G01X112100Y513500D02*
Y518500D01*
G01X114900D02*
Y513500D01*
G01Y516000D02*
X112100D01*
G01X118600Y513500D02*
X118200Y513583D01*
X117800Y513917D01*
X117533Y514500D01*
X117400Y515167D01*
X117533Y515833D01*
X117800Y516417D01*
X118200Y516750D01*
X118600Y516833D01*
X119000Y516750D01*
X119400Y516417D01*
X119667Y515833D01*
X119733Y515167D01*
X119667Y514500D01*
X119400Y513917D01*
X119000Y513583D01*
X118600Y513500D01*
G01X123700D02*
Y518500D01*
G01X127800Y515750D02*
X129933D01*
X129733Y516333D01*
X129400Y516667D01*
X128933Y516833D01*
X128467Y516750D01*
X128067Y516500D01*
X127800Y515917D01*
X127667Y515417D01*
Y514917D01*
X127800Y514417D01*
X128133Y513917D01*
X128533Y513583D01*
X129000Y513500D01*
X129467Y513667D01*
X129933Y514167D01*
G01X138000Y514083D02*
X138333Y513750D01*
X138800Y513500D01*
X139200D01*
X139600Y513667D01*
X139867Y513917D01*
X140000Y514250D01*
X139933Y514750D01*
X139667Y515000D01*
X138467Y515500D01*
X138200Y516083D01*
X138333Y516500D01*
X138600Y516750D01*
X139000Y516833D01*
X139400Y516750D01*
X139800Y516500D01*
G01X144100Y516833D02*
Y513500D01*
G01Y518167D02*
X143967Y518250D01*
Y518417D01*
X144100Y518500D01*
X144233Y518417D01*
Y518250D01*
X144100Y518167D01*
G01X148200Y516833D02*
X150200D01*
X148200Y513500D01*
X150200D01*
G01X153300Y515750D02*
X155433D01*
X155233Y516333D01*
X154900Y516667D01*
X154433Y516833D01*
X153967Y516750D01*
X153567Y516500D01*
X153300Y515917D01*
X153167Y515417D01*
Y514917D01*
X153300Y514417D01*
X153633Y513917D01*
X154033Y513583D01*
X154500Y513500D01*
X154967Y513667D01*
X155433Y514167D01*
G01X112100Y588500D02*
Y593500D01*
G01X114900D02*
Y588500D01*
G01Y591000D02*
X112100D01*
G01X118600Y588500D02*
X118200Y588583D01*
X117800Y588917D01*
X117533Y589500D01*
X117400Y590167D01*
X117533Y590833D01*
X117800Y591417D01*
X118200Y591750D01*
X118600Y591833D01*
X119000Y591750D01*
X119400Y591417D01*
X119667Y590833D01*
X119733Y590167D01*
X119667Y589500D01*
X119400Y588917D01*
X119000Y588583D01*
X118600Y588500D01*
G01X123700D02*
Y593500D01*
G01X127800Y590750D02*
X129933D01*
X129733Y591333D01*
X129400Y591667D01*
X128933Y591833D01*
X128467Y591750D01*
X128067Y591500D01*
X127800Y590917D01*
X127667Y590417D01*
Y589917D01*
X127800Y589417D01*
X128133Y588917D01*
X128533Y588583D01*
X129000Y588500D01*
X129467Y588667D01*
X129933Y589167D01*
G01X137800Y586833D02*
Y591833D01*
G01Y591083D02*
X138133Y591500D01*
X138467Y591750D01*
X139000Y591833D01*
X139467Y591750D01*
X139933Y591333D01*
X140133Y590750D01*
X140200Y590167D01*
X140133Y589583D01*
X139933Y589000D01*
X139533Y588667D01*
X139000Y588500D01*
X138533Y588583D01*
X138067Y588833D01*
X137800Y589167D01*
G01X144100Y588500D02*
X143700Y588583D01*
X143300Y588917D01*
X143033Y589500D01*
X142900Y590167D01*
X143033Y590833D01*
X143300Y591417D01*
X143700Y591750D01*
X144100Y591833D01*
X144500Y591750D01*
X144900Y591417D01*
X145167Y590833D01*
X145233Y590167D01*
X145167Y589500D01*
X144900Y588917D01*
X144500Y588583D01*
X144100Y588500D01*
G01X148200Y589083D02*
X148533Y588750D01*
X149000Y588500D01*
X149400D01*
X149800Y588667D01*
X150067Y588917D01*
X150200Y589250D01*
X150133Y589750D01*
X149867Y590000D01*
X148667Y590500D01*
X148400Y591083D01*
X148533Y591500D01*
X148800Y591750D01*
X149200Y591833D01*
X149600Y591750D01*
X150000Y591500D01*
G01X154300Y591833D02*
Y588500D01*
G01Y593167D02*
X154167Y593250D01*
Y593417D01*
X154300Y593500D01*
X154433Y593417D01*
Y593250D01*
X154300Y593167D01*
G01X159400Y593500D02*
Y588500D01*
G01X158467Y591833D02*
X160333D01*
G01X164500D02*
Y588500D01*
G01Y593167D02*
X164367Y593250D01*
Y593417D01*
X164500Y593500D01*
X164633Y593417D01*
Y593250D01*
X164500Y593167D01*
G01X169600Y588500D02*
X169200Y588583D01*
X168800Y588917D01*
X168533Y589500D01*
X168400Y590167D01*
X168533Y590833D01*
X168800Y591417D01*
X169200Y591750D01*
X169600Y591833D01*
X170000Y591750D01*
X170400Y591417D01*
X170667Y590833D01*
X170733Y590167D01*
X170667Y589500D01*
X170400Y588917D01*
X170000Y588583D01*
X169600Y588500D01*
G01X173567D02*
Y591833D01*
G01Y591000D02*
X173833Y591417D01*
X174233Y591750D01*
X174767Y591833D01*
X175233Y591750D01*
X175633Y591417D01*
X175833Y590833D01*
Y588500D01*
G01X184900Y593500D02*
Y588500D01*
G01X183967Y591833D02*
X185833D01*
G01X190000Y588500D02*
X189600Y588583D01*
X189200Y588917D01*
X188933Y589500D01*
X188800Y590167D01*
X188933Y590833D01*
X189200Y591417D01*
X189600Y591750D01*
X190000Y591833D01*
X190400Y591750D01*
X190800Y591417D01*
X191067Y590833D01*
X191133Y590167D01*
X191067Y589500D01*
X190800Y588917D01*
X190400Y588583D01*
X190000Y588500D01*
G01X195100D02*
Y593500D01*
G01X199200Y590750D02*
X201333D01*
X201133Y591333D01*
X200800Y591667D01*
X200333Y591833D01*
X199867Y591750D01*
X199467Y591500D01*
X199200Y590917D01*
X199067Y590417D01*
Y589917D01*
X199200Y589417D01*
X199533Y588917D01*
X199933Y588583D01*
X200400Y588500D01*
X200867Y588667D01*
X201333Y589167D01*
G01X204367Y588500D02*
Y591833D01*
G01Y591167D02*
X204700Y591500D01*
X205033Y591750D01*
X205500Y591833D01*
X205833Y591750D01*
X206233Y591500D01*
G01X211600Y588500D02*
Y591833D01*
G01Y591250D02*
X211333Y591583D01*
X210933Y591750D01*
X210467Y591833D01*
X210000Y591667D01*
X209600Y591333D01*
X209333Y590833D01*
X209200Y590167D01*
X209333Y589500D01*
X209600Y589000D01*
X210000Y588667D01*
X210467Y588500D01*
X210933Y588583D01*
X211333Y588833D01*
X211600Y589167D01*
G01X214367Y588500D02*
Y591833D01*
G01Y591000D02*
X214633Y591417D01*
X215033Y591750D01*
X215567Y591833D01*
X216033Y591750D01*
X216433Y591417D01*
X216633Y590833D01*
Y588500D01*
G01X221667Y591417D02*
X221200Y591750D01*
X220800Y591833D01*
X220267Y591667D01*
X219867Y591333D01*
X219600Y590750D01*
X219533Y590167D01*
X219600Y589583D01*
X219867Y589083D01*
X220267Y588667D01*
X220800Y588500D01*
X221267Y588667D01*
X221667Y589000D01*
G01X224700Y590750D02*
X226833D01*
X226633Y591333D01*
X226300Y591667D01*
X225833Y591833D01*
X225367Y591750D01*
X224967Y591500D01*
X224700Y590917D01*
X224567Y590417D01*
Y589917D01*
X224700Y589417D01*
X225033Y588917D01*
X225433Y588583D01*
X225900Y588500D01*
X226367Y588667D01*
X226833Y589167D01*
G01X111833Y610000D02*
X113500Y605000D01*
X115167Y610000D01*
G01X118600Y608333D02*
Y605000D01*
G01Y609667D02*
X118467Y609750D01*
Y609917D01*
X118600Y610000D01*
X118733Y609917D01*
Y609750D01*
X118600Y609667D01*
G01X124900Y605000D02*
Y608333D01*
G01Y607750D02*
X124633Y608083D01*
X124233Y608250D01*
X123767Y608333D01*
X123300Y608167D01*
X122900Y607833D01*
X122633Y607333D01*
X122500Y606667D01*
X122633Y606000D01*
X122900Y605500D01*
X123300Y605167D01*
X123767Y605000D01*
X124233Y605083D01*
X124633Y605333D01*
X124900Y605667D01*
G01X132767Y605000D02*
Y610000D01*
G01Y607583D02*
X133100Y608000D01*
X133433Y608250D01*
X133967Y608333D01*
X134367Y608250D01*
X134833Y607917D01*
X135033Y607417D01*
Y605000D01*
G01X139000D02*
X138600Y605083D01*
X138200Y605417D01*
X137933Y606000D01*
X137800Y606667D01*
X137933Y607333D01*
X138200Y607917D01*
X138600Y608250D01*
X139000Y608333D01*
X139400Y608250D01*
X139800Y607917D01*
X140067Y607333D01*
X140133Y606667D01*
X140067Y606000D01*
X139800Y605417D01*
X139400Y605083D01*
X139000Y605000D01*
G01X144100D02*
Y610000D01*
G01X148200Y607250D02*
X150333D01*
X150133Y607833D01*
X149800Y608167D01*
X149333Y608333D01*
X148867Y608250D01*
X148467Y608000D01*
X148200Y607417D01*
X148067Y606917D01*
Y606417D01*
X148200Y605917D01*
X148533Y605417D01*
X148933Y605083D01*
X149400Y605000D01*
X149867Y605167D01*
X150333Y605667D01*
G01X159400Y610000D02*
Y605000D01*
G01X158467Y608333D02*
X160333D01*
G01X163367Y605000D02*
Y610000D01*
G01Y607583D02*
X163700Y608000D01*
X164033Y608250D01*
X164567Y608333D01*
X164967Y608250D01*
X165433Y607917D01*
X165633Y607417D01*
Y605000D01*
G01X168600Y607250D02*
X170733D01*
X170533Y607833D01*
X170200Y608167D01*
X169733Y608333D01*
X169267Y608250D01*
X168867Y608000D01*
X168600Y607417D01*
X168467Y606917D01*
Y606417D01*
X168600Y605917D01*
X168933Y605417D01*
X169333Y605083D01*
X169800Y605000D01*
X170267Y605167D01*
X170733Y605667D01*
G01X173767Y605000D02*
Y608333D01*
G01Y607667D02*
X174100Y608000D01*
X174433Y608250D01*
X174900Y608333D01*
X175233Y608250D01*
X175633Y608000D01*
G01X177800Y605000D02*
Y608333D01*
G01Y607417D02*
X178000Y607833D01*
X178333Y608167D01*
X178800Y608333D01*
X179267Y608167D01*
X179600Y607833D01*
X179800Y607417D01*
Y605000D01*
G01Y607417D02*
X180000Y607833D01*
X180333Y608167D01*
X180800Y608333D01*
X181267Y608167D01*
X181600Y607833D01*
X181800Y607333D01*
Y605000D01*
G01X186100D02*
Y608333D01*
G01Y607750D02*
X185833Y608083D01*
X185433Y608250D01*
X184967Y608333D01*
X184500Y608167D01*
X184100Y607833D01*
X183833Y607333D01*
X183700Y606667D01*
X183833Y606000D01*
X184100Y605500D01*
X184500Y605167D01*
X184967Y605000D01*
X185433Y605083D01*
X185833Y605333D01*
X186100Y605667D01*
G01X190000Y605000D02*
Y610000D01*
G01X199000Y603333D02*
Y608333D01*
G01Y607583D02*
X199333Y608000D01*
X199667Y608250D01*
X200200Y608333D01*
X200667Y608250D01*
X201133Y607833D01*
X201333Y607250D01*
X201400Y606667D01*
X201333Y606083D01*
X201133Y605500D01*
X200733Y605167D01*
X200200Y605000D01*
X199733Y605083D01*
X199267Y605333D01*
X199000Y605667D01*
G01X206500Y605000D02*
Y608333D01*
G01Y607750D02*
X206233Y608083D01*
X205833Y608250D01*
X205367Y608333D01*
X204900Y608167D01*
X204500Y607833D01*
X204233Y607333D01*
X204100Y606667D01*
X204233Y606000D01*
X204500Y605500D01*
X204900Y605167D01*
X205367Y605000D01*
X205833Y605083D01*
X206233Y605333D01*
X206500Y605667D01*
G01X211600Y610000D02*
Y605000D01*
G01Y605750D02*
X211333Y605333D01*
X210933Y605083D01*
X210467Y605000D01*
X209933Y605167D01*
X209533Y605583D01*
X209267Y606083D01*
X209200Y606667D01*
X209267Y607250D01*
X209533Y607750D01*
X209933Y608167D01*
X210467Y608333D01*
X210933Y608250D01*
X211267Y608083D01*
X211600Y607750D01*
G01X111833Y620000D02*
X113500Y625000D01*
X115167Y620000D01*
G01X114567Y621750D02*
X112433D01*
G01X117467Y620000D02*
Y623333D01*
G01Y622500D02*
X117733Y622917D01*
X118133Y623250D01*
X118667Y623333D01*
X119133Y623250D01*
X119533Y622917D01*
X119733Y622333D01*
Y620000D01*
G01X123700Y625000D02*
Y620000D01*
G01X122767Y623333D02*
X124633D01*
G01X128800D02*
Y620000D01*
G01Y624667D02*
X128667Y624750D01*
Y624917D01*
X128800Y625000D01*
X128933Y624917D01*
Y624750D01*
X128800Y624667D01*
G01X133033Y621667D02*
X134767D01*
G01X142900Y618333D02*
Y623333D01*
G01Y622583D02*
X143233Y623000D01*
X143567Y623250D01*
X144100Y623333D01*
X144567Y623250D01*
X145033Y622833D01*
X145233Y622250D01*
X145300Y621667D01*
X145233Y621083D01*
X145033Y620500D01*
X144633Y620167D01*
X144100Y620000D01*
X143633Y620083D01*
X143167Y620333D01*
X142900Y620667D01*
G01X150400Y620000D02*
Y623333D01*
G01Y622750D02*
X150133Y623083D01*
X149733Y623250D01*
X149267Y623333D01*
X148800Y623167D01*
X148400Y622833D01*
X148133Y622333D01*
X148000Y621667D01*
X148133Y621000D01*
X148400Y620500D01*
X148800Y620167D01*
X149267Y620000D01*
X149733Y620083D01*
X150133Y620333D01*
X150400Y620667D01*
G01X155500Y625000D02*
Y620000D01*
G01Y620750D02*
X155233Y620333D01*
X154833Y620083D01*
X154367Y620000D01*
X153833Y620167D01*
X153433Y620583D01*
X153167Y621083D01*
X153100Y621667D01*
X153167Y622250D01*
X153433Y622750D01*
X153833Y623167D01*
X154367Y623333D01*
X154833Y623250D01*
X155167Y623083D01*
X155500Y622750D01*
G01X111727Y639590D02*
Y644590D01*
X114793Y639590D01*
Y644590D01*
G01X118360Y639590D02*
X117960Y639673D01*
X117560Y640007D01*
X117293Y640590D01*
X117160Y641257D01*
X117293Y641923D01*
X117560Y642507D01*
X117960Y642840D01*
X118360Y642923D01*
X118760Y642840D01*
X119160Y642507D01*
X119427Y641923D01*
X119493Y641257D01*
X119427Y640590D01*
X119160Y640007D01*
X118760Y639673D01*
X118360Y639590D01*
G01X122327D02*
Y642923D01*
G01Y642090D02*
X122593Y642507D01*
X122993Y642840D01*
X123527Y642923D01*
X123993Y642840D01*
X124393Y642507D01*
X124593Y641923D01*
Y639590D01*
G01X127693Y641257D02*
X129427D01*
G01X133260Y639590D02*
Y643840D01*
X133393Y644257D01*
X133660Y644507D01*
X134060Y644590D01*
X134460Y644423D01*
X134660Y644007D01*
G01X133860Y642590D02*
X132527D01*
G01X137627Y642923D02*
Y640590D01*
X137893Y640007D01*
X138293Y639673D01*
X138760Y639590D01*
X139227Y639673D01*
X139627Y640007D01*
X139893Y640590D01*
G01Y639590D02*
Y642923D01*
G01X142727Y639590D02*
Y642923D01*
G01Y642090D02*
X142993Y642507D01*
X143393Y642840D01*
X143927Y642923D01*
X144393Y642840D01*
X144793Y642507D01*
X144993Y641923D01*
Y639590D01*
G01X150027Y642507D02*
X149560Y642840D01*
X149160Y642923D01*
X148627Y642757D01*
X148227Y642423D01*
X147960Y641840D01*
X147893Y641257D01*
X147960Y640673D01*
X148227Y640173D01*
X148627Y639757D01*
X149160Y639590D01*
X149627Y639757D01*
X150027Y640090D01*
G01X154060Y644590D02*
Y639590D01*
G01X153127Y642923D02*
X154993D01*
G01X159160D02*
Y639590D01*
G01Y644257D02*
X159027Y644340D01*
Y644507D01*
X159160Y644590D01*
X159293Y644507D01*
Y644340D01*
X159160Y644257D01*
G01X164260Y639590D02*
X163860Y639673D01*
X163460Y640007D01*
X163193Y640590D01*
X163060Y641257D01*
X163193Y641923D01*
X163460Y642507D01*
X163860Y642840D01*
X164260Y642923D01*
X164660Y642840D01*
X165060Y642507D01*
X165327Y641923D01*
X165393Y641257D01*
X165327Y640590D01*
X165060Y640007D01*
X164660Y639673D01*
X164260Y639590D01*
G01X168227D02*
Y642923D01*
G01Y642090D02*
X168493Y642507D01*
X168893Y642840D01*
X169427Y642923D01*
X169893Y642840D01*
X170293Y642507D01*
X170493Y641923D01*
Y639590D01*
G01X175660D02*
Y642923D01*
G01Y642340D02*
X175393Y642673D01*
X174993Y642840D01*
X174527Y642923D01*
X174060Y642757D01*
X173660Y642423D01*
X173393Y641923D01*
X173260Y641257D01*
X173393Y640590D01*
X173660Y640090D01*
X174060Y639757D01*
X174527Y639590D01*
X174993Y639673D01*
X175393Y639923D01*
X175660Y640257D01*
G01X179560Y639590D02*
Y644590D01*
G01X188560Y637923D02*
Y642923D01*
G01Y642173D02*
X188893Y642590D01*
X189227Y642840D01*
X189760Y642923D01*
X190227Y642840D01*
X190693Y642423D01*
X190893Y641840D01*
X190960Y641257D01*
X190893Y640673D01*
X190693Y640090D01*
X190293Y639757D01*
X189760Y639590D01*
X189293Y639673D01*
X188827Y639923D01*
X188560Y640257D01*
G01X196060Y639590D02*
Y642923D01*
G01Y642340D02*
X195793Y642673D01*
X195393Y642840D01*
X194927Y642923D01*
X194460Y642757D01*
X194060Y642423D01*
X193793Y641923D01*
X193660Y641257D01*
X193793Y640590D01*
X194060Y640090D01*
X194460Y639757D01*
X194927Y639590D01*
X195393Y639673D01*
X195793Y639923D01*
X196060Y640257D01*
G01X201160Y644590D02*
Y639590D01*
G01Y640340D02*
X200893Y639923D01*
X200493Y639673D01*
X200027Y639590D01*
X199493Y639757D01*
X199093Y640173D01*
X198827Y640673D01*
X198760Y641257D01*
X198827Y641840D01*
X199093Y642340D01*
X199493Y642757D01*
X200027Y642923D01*
X200493Y642840D01*
X200827Y642673D01*
X201160Y642340D01*
G01X159467Y668083D02*
X159067Y668333D01*
X158600Y668500D01*
X158067D01*
X157467Y668250D01*
X157000Y667833D01*
X156667Y667333D01*
X156400Y666500D01*
X156333Y665750D01*
X156467Y665000D01*
X156667Y664500D01*
X157067Y664000D01*
X157533Y663667D01*
X158000Y663500D01*
X158467D01*
X158933Y663667D01*
X159333Y663917D01*
X159667Y664250D01*
G01X163100Y663500D02*
Y668500D01*
G01X169400Y663500D02*
Y666833D01*
G01Y666250D02*
X169133Y666583D01*
X168733Y666750D01*
X168267Y666833D01*
X167800Y666667D01*
X167400Y666333D01*
X167133Y665833D01*
X167000Y665167D01*
X167133Y664500D01*
X167400Y664000D01*
X167800Y663667D01*
X168267Y663500D01*
X168733Y663583D01*
X169133Y663833D01*
X169400Y664167D01*
G01X172300Y664083D02*
X172633Y663750D01*
X173100Y663500D01*
X173500D01*
X173900Y663667D01*
X174167Y663917D01*
X174300Y664250D01*
X174233Y664750D01*
X173967Y665000D01*
X172767Y665500D01*
X172500Y666083D01*
X172633Y666500D01*
X172900Y666750D01*
X173300Y666833D01*
X173700Y666750D01*
X174100Y666500D01*
G01X177400Y664083D02*
X177733Y663750D01*
X178200Y663500D01*
X178600D01*
X179000Y663667D01*
X179267Y663917D01*
X179400Y664250D01*
X179333Y664750D01*
X179067Y665000D01*
X177867Y665500D01*
X177600Y666083D01*
X177733Y666500D01*
X178000Y666750D01*
X178400Y666833D01*
X178800Y666750D01*
X179200Y666500D01*
G01X183500Y666833D02*
Y663500D01*
G01Y668167D02*
X183367Y668250D01*
Y668417D01*
X183500Y668500D01*
X183633Y668417D01*
Y668250D01*
X183500Y668167D01*
G01X188200Y663500D02*
Y667750D01*
X188333Y668167D01*
X188600Y668417D01*
X189000Y668500D01*
X189400Y668333D01*
X189600Y667917D01*
G01X188800Y666500D02*
X187467D01*
G01X192300Y662000D02*
X192700Y661833D01*
X193233Y662000D01*
X193567Y662333D01*
X193833Y662750D01*
X194233Y664083D01*
X195100Y666833D01*
G01X192967D02*
X194233Y664083D01*
G01X273200Y-63500D02*
Y-60167D01*
G01Y-60750D02*
X272933Y-60417D01*
X272533Y-60250D01*
X272067Y-60167D01*
X271600Y-60333D01*
X271200Y-60667D01*
X270933Y-61167D01*
X270800Y-61833D01*
X270933Y-62500D01*
X271200Y-63000D01*
X271600Y-63333D01*
X272067Y-63500D01*
X272533Y-63417D01*
X272933Y-63167D01*
X273200Y-62833D01*
G01X278300Y-58500D02*
Y-63500D01*
G01Y-62750D02*
X278033Y-63167D01*
X277633Y-63417D01*
X277167Y-63500D01*
X276633Y-63333D01*
X276233Y-62917D01*
X275967Y-62417D01*
X275900Y-61833D01*
X275967Y-61250D01*
X276233Y-60750D01*
X276633Y-60333D01*
X277167Y-60167D01*
X277633Y-60250D01*
X277967Y-60417D01*
X278300Y-60750D01*
G01X283400Y-58500D02*
Y-63500D01*
G01Y-62750D02*
X283133Y-63167D01*
X282733Y-63417D01*
X282267Y-63500D01*
X281733Y-63333D01*
X281333Y-62917D01*
X281067Y-62417D01*
X281000Y-61833D01*
X281067Y-61250D01*
X281333Y-60750D01*
X281733Y-60333D01*
X282267Y-60167D01*
X282733Y-60250D01*
X283067Y-60417D01*
X283400Y-60750D01*
G01X291400Y-62917D02*
X291733Y-63250D01*
X292200Y-63500D01*
X292600D01*
X293000Y-63333D01*
X293267Y-63083D01*
X293400Y-62750D01*
X293333Y-62250D01*
X293067Y-62000D01*
X291867Y-61500D01*
X291600Y-60917D01*
X291733Y-60500D01*
X292000Y-60250D01*
X292400Y-60167D01*
X292800Y-60250D01*
X293200Y-60500D01*
G01X296367Y-60167D02*
Y-62500D01*
X296633Y-63083D01*
X297033Y-63417D01*
X297500Y-63500D01*
X297967Y-63417D01*
X298367Y-63083D01*
X298633Y-62500D01*
G01Y-63500D02*
Y-60167D01*
G01X301400Y-65167D02*
Y-60167D01*
G01Y-60917D02*
X301733Y-60500D01*
X302067Y-60250D01*
X302600Y-60167D01*
X303067Y-60250D01*
X303533Y-60667D01*
X303733Y-61250D01*
X303800Y-61833D01*
X303733Y-62417D01*
X303533Y-63000D01*
X303133Y-63333D01*
X302600Y-63500D01*
X302133Y-63417D01*
X301667Y-63167D01*
X301400Y-62833D01*
G01X306500Y-65167D02*
Y-60167D01*
G01Y-60917D02*
X306833Y-60500D01*
X307167Y-60250D01*
X307700Y-60167D01*
X308167Y-60250D01*
X308633Y-60667D01*
X308833Y-61250D01*
X308900Y-61833D01*
X308833Y-62417D01*
X308633Y-63000D01*
X308233Y-63333D01*
X307700Y-63500D01*
X307233Y-63417D01*
X306767Y-63167D01*
X306500Y-62833D01*
G01X312800Y-63500D02*
Y-58500D01*
G01X317900Y-60167D02*
Y-63500D01*
G01Y-58833D02*
X317767Y-58750D01*
Y-58583D01*
X317900Y-58500D01*
X318033Y-58583D01*
Y-58750D01*
X317900Y-58833D01*
G01X322000Y-61250D02*
X324133D01*
X323933Y-60667D01*
X323600Y-60333D01*
X323133Y-60167D01*
X322667Y-60250D01*
X322267Y-60500D01*
X322000Y-61083D01*
X321867Y-61583D01*
Y-62083D01*
X322000Y-62583D01*
X322333Y-63083D01*
X322733Y-63417D01*
X323200Y-63500D01*
X323667Y-63333D01*
X324133Y-62833D01*
G01X327167Y-63500D02*
Y-60167D01*
G01Y-60833D02*
X327500Y-60500D01*
X327833Y-60250D01*
X328300Y-60167D01*
X328633Y-60250D01*
X329033Y-60500D01*
G01X333200Y-60167D02*
X333867Y-59125D01*
Y-58500D01*
X333367D01*
Y-59125D01*
X333867D01*
G01X337300Y-62917D02*
X337633Y-63250D01*
X338100Y-63500D01*
X338500D01*
X338900Y-63333D01*
X339167Y-63083D01*
X339300Y-62750D01*
X339233Y-62250D01*
X338967Y-62000D01*
X337767Y-61500D01*
X337500Y-60917D01*
X337633Y-60500D01*
X337900Y-60250D01*
X338300Y-60167D01*
X338700Y-60250D01*
X339100Y-60500D01*
G01X347167Y-58500D02*
Y-63500D01*
X349833D01*
G01X353600D02*
X353200Y-63417D01*
X352800Y-63083D01*
X352533Y-62500D01*
X352400Y-61833D01*
X352533Y-61167D01*
X352800Y-60583D01*
X353200Y-60250D01*
X353600Y-60167D01*
X354000Y-60250D01*
X354400Y-60583D01*
X354667Y-61167D01*
X354733Y-61833D01*
X354667Y-62500D01*
X354400Y-63083D01*
X354000Y-63417D01*
X353600Y-63500D01*
G01X357767Y-64750D02*
X358233Y-65083D01*
X358767Y-65167D01*
X359233Y-65083D01*
X359633Y-64667D01*
X359900Y-64083D01*
Y-60167D01*
G01Y-60833D02*
X359633Y-60500D01*
X359233Y-60250D01*
X358767Y-60167D01*
X358233Y-60333D01*
X357900Y-60667D01*
X357633Y-61250D01*
X357500Y-61833D01*
X357567Y-62333D01*
X357833Y-62917D01*
X358233Y-63333D01*
X358767Y-63500D01*
X359167Y-63417D01*
X359633Y-63083D01*
X359900Y-62750D01*
G01X363800Y-63500D02*
X363400Y-63417D01*
X363000Y-63083D01*
X362733Y-62500D01*
X362600Y-61833D01*
X362733Y-61167D01*
X363000Y-60583D01*
X363400Y-60250D01*
X363800Y-60167D01*
X364200Y-60250D01*
X364600Y-60583D01*
X364867Y-61167D01*
X364933Y-61833D01*
X364867Y-62500D01*
X364600Y-63083D01*
X364200Y-63417D01*
X363800Y-63500D01*
G01X375200D02*
Y-60167D01*
G01Y-60750D02*
X374933Y-60417D01*
X374533Y-60250D01*
X374067Y-60167D01*
X373600Y-60333D01*
X373200Y-60667D01*
X372933Y-61167D01*
X372800Y-61833D01*
X372933Y-62500D01*
X373200Y-63000D01*
X373600Y-63333D01*
X374067Y-63500D01*
X374533Y-63417D01*
X374933Y-63167D01*
X375200Y-62833D01*
G01X377967Y-63500D02*
Y-60167D01*
G01Y-61000D02*
X378233Y-60583D01*
X378633Y-60250D01*
X379167Y-60167D01*
X379633Y-60250D01*
X380033Y-60583D01*
X380233Y-61167D01*
Y-63500D01*
G01X385400Y-58500D02*
Y-63500D01*
G01Y-62750D02*
X385133Y-63167D01*
X384733Y-63417D01*
X384267Y-63500D01*
X383733Y-63333D01*
X383333Y-62917D01*
X383067Y-62417D01*
X383000Y-61833D01*
X383067Y-61250D01*
X383333Y-60750D01*
X383733Y-60333D01*
X384267Y-60167D01*
X384733Y-60250D01*
X385067Y-60417D01*
X385400Y-60750D01*
G01X392933Y-58500D02*
Y-62083D01*
X393200Y-62833D01*
X393733Y-63333D01*
X394400Y-63500D01*
X395067Y-63333D01*
X395600Y-62833D01*
X395867Y-62083D01*
Y-58500D01*
G01X398167D02*
Y-63500D01*
X400833D01*
G01X409300D02*
Y-59250D01*
X409433Y-58833D01*
X409700Y-58583D01*
X410100Y-58500D01*
X410500Y-58667D01*
X410700Y-59083D01*
G01X409900Y-60500D02*
X408567D01*
G01X414800Y-60167D02*
Y-63500D01*
G01Y-58833D02*
X414667Y-58750D01*
Y-58583D01*
X414800Y-58500D01*
X414933Y-58583D01*
Y-58750D01*
X414800Y-58833D01*
G01X419900Y-63500D02*
Y-58500D01*
G01X424000Y-61250D02*
X426133D01*
X425933Y-60667D01*
X425600Y-60333D01*
X425133Y-60167D01*
X424667Y-60250D01*
X424267Y-60500D01*
X424000Y-61083D01*
X423867Y-61583D01*
Y-62083D01*
X424000Y-62583D01*
X424333Y-63083D01*
X424733Y-63417D01*
X425200Y-63500D01*
X425667Y-63333D01*
X426133Y-62833D01*
G01X433667Y-63500D02*
Y-58500D01*
X436733Y-63500D01*
Y-58500D01*
G01X439167Y-60167D02*
Y-62500D01*
X439433Y-63083D01*
X439833Y-63417D01*
X440300Y-63500D01*
X440767Y-63417D01*
X441167Y-63083D01*
X441433Y-62500D01*
G01Y-63500D02*
Y-60167D01*
G01X443400Y-63500D02*
Y-60167D01*
G01Y-61083D02*
X443600Y-60667D01*
X443933Y-60333D01*
X444400Y-60167D01*
X444867Y-60333D01*
X445200Y-60667D01*
X445400Y-61083D01*
Y-63500D01*
G01Y-61083D02*
X445600Y-60667D01*
X445933Y-60333D01*
X446400Y-60167D01*
X446867Y-60333D01*
X447200Y-60667D01*
X447400Y-61167D01*
Y-63500D01*
G01X449300D02*
Y-58500D01*
G01Y-61000D02*
X449633Y-60500D01*
X450033Y-60250D01*
X450433Y-60167D01*
X451033Y-60333D01*
X451433Y-60667D01*
X451700Y-61250D01*
Y-61917D01*
X451567Y-62583D01*
X451300Y-63083D01*
X450833Y-63417D01*
X450433Y-63500D01*
X450033Y-63417D01*
X449633Y-63167D01*
X449300Y-62750D01*
G01X454600Y-61250D02*
X456733D01*
X456533Y-60667D01*
X456200Y-60333D01*
X455733Y-60167D01*
X455267Y-60250D01*
X454867Y-60500D01*
X454600Y-61083D01*
X454467Y-61583D01*
Y-62083D01*
X454600Y-62583D01*
X454933Y-63083D01*
X455333Y-63417D01*
X455800Y-63500D01*
X456267Y-63333D01*
X456733Y-62833D01*
G01X459767Y-63500D02*
Y-60167D01*
G01Y-60833D02*
X460100Y-60500D01*
X460433Y-60250D01*
X460900Y-60167D01*
X461233Y-60250D01*
X461633Y-60500D01*
G01X470900Y-60167D02*
Y-63500D01*
G01Y-58833D02*
X470767Y-58750D01*
Y-58583D01*
X470900Y-58500D01*
X471033Y-58583D01*
Y-58750D01*
X470900Y-58833D01*
G01X474867Y-63500D02*
Y-60167D01*
G01Y-61000D02*
X475133Y-60583D01*
X475533Y-60250D01*
X476067Y-60167D01*
X476533Y-60250D01*
X476933Y-60583D01*
X477133Y-61167D01*
Y-63500D01*
G01X485200Y-62917D02*
X485533Y-63250D01*
X486000Y-63500D01*
X486400D01*
X486800Y-63333D01*
X487067Y-63083D01*
X487200Y-62750D01*
X487133Y-62250D01*
X486867Y-62000D01*
X485667Y-61500D01*
X485400Y-60917D01*
X485533Y-60500D01*
X485800Y-60250D01*
X486200Y-60167D01*
X486600Y-60250D01*
X487000Y-60500D01*
G01X491300Y-60167D02*
Y-63500D01*
G01Y-58833D02*
X491167Y-58750D01*
Y-58583D01*
X491300Y-58500D01*
X491433Y-58583D01*
Y-58750D01*
X491300Y-58833D01*
G01X496400Y-63500D02*
Y-58500D01*
G01X500367Y-63500D02*
Y-58500D01*
G01X502500Y-60167D02*
X500367Y-62083D01*
G01X501233Y-61333D02*
X502633Y-63500D01*
G01X505600Y-62917D02*
X505933Y-63250D01*
X506400Y-63500D01*
X506800D01*
X507200Y-63333D01*
X507467Y-63083D01*
X507600Y-62750D01*
X507533Y-62250D01*
X507267Y-62000D01*
X506067Y-61500D01*
X505800Y-60917D01*
X505933Y-60500D01*
X506200Y-60250D01*
X506600Y-60167D01*
X507000Y-60250D01*
X507400Y-60500D01*
G01X512767Y-60583D02*
X512300Y-60250D01*
X511900Y-60167D01*
X511367Y-60333D01*
X510967Y-60667D01*
X510700Y-61250D01*
X510633Y-61833D01*
X510700Y-62417D01*
X510967Y-62917D01*
X511367Y-63333D01*
X511900Y-63500D01*
X512367Y-63333D01*
X512767Y-63000D01*
G01X515867Y-63500D02*
Y-60167D01*
G01Y-60833D02*
X516200Y-60500D01*
X516533Y-60250D01*
X517000Y-60167D01*
X517333Y-60250D01*
X517733Y-60500D01*
G01X520900Y-61250D02*
X523033D01*
X522833Y-60667D01*
X522500Y-60333D01*
X522033Y-60167D01*
X521567Y-60250D01*
X521167Y-60500D01*
X520900Y-61083D01*
X520767Y-61583D01*
Y-62083D01*
X520900Y-62583D01*
X521233Y-63083D01*
X521633Y-63417D01*
X522100Y-63500D01*
X522567Y-63333D01*
X523033Y-62833D01*
G01X526000Y-61250D02*
X528133D01*
X527933Y-60667D01*
X527600Y-60333D01*
X527133Y-60167D01*
X526667Y-60250D01*
X526267Y-60500D01*
X526000Y-61083D01*
X525867Y-61583D01*
Y-62083D01*
X526000Y-62583D01*
X526333Y-63083D01*
X526733Y-63417D01*
X527200Y-63500D01*
X527667Y-63333D01*
X528133Y-62833D01*
G01X530967Y-63500D02*
Y-60167D01*
G01Y-61000D02*
X531233Y-60583D01*
X531633Y-60250D01*
X532167Y-60167D01*
X532633Y-60250D01*
X533033Y-60583D01*
X533233Y-61167D01*
Y-63500D01*
G01X270600Y-47833D02*
X271133Y-48250D01*
X271733Y-48500D01*
X272267D01*
X272800Y-48250D01*
X273200Y-47833D01*
X273400Y-47250D01*
X273267Y-46667D01*
X272933Y-46167D01*
X272333Y-45833D01*
X271533Y-45667D01*
X271067Y-45333D01*
X270867Y-44750D01*
X271000Y-44167D01*
X271333Y-43750D01*
X271800Y-43500D01*
X272267D01*
X272733Y-43667D01*
X273133Y-44083D01*
G01X277100Y-48500D02*
X276700Y-48417D01*
X276300Y-48083D01*
X276033Y-47500D01*
X275900Y-46833D01*
X276033Y-46167D01*
X276300Y-45583D01*
X276700Y-45250D01*
X277100Y-45167D01*
X277500Y-45250D01*
X277900Y-45583D01*
X278167Y-46167D01*
X278233Y-46833D01*
X278167Y-47500D01*
X277900Y-48083D01*
X277500Y-48417D01*
X277100Y-48500D01*
G01X282200D02*
Y-43500D01*
G01X288500D02*
Y-48500D01*
G01Y-47750D02*
X288233Y-48167D01*
X287833Y-48417D01*
X287367Y-48500D01*
X286833Y-48333D01*
X286433Y-47917D01*
X286167Y-47417D01*
X286100Y-46833D01*
X286167Y-46250D01*
X286433Y-45750D01*
X286833Y-45333D01*
X287367Y-45167D01*
X287833Y-45250D01*
X288167Y-45417D01*
X288500Y-45750D01*
G01X291400Y-46250D02*
X293533D01*
X293333Y-45667D01*
X293000Y-45333D01*
X292533Y-45167D01*
X292067Y-45250D01*
X291667Y-45500D01*
X291400Y-46083D01*
X291267Y-46583D01*
Y-47083D01*
X291400Y-47583D01*
X291733Y-48083D01*
X292133Y-48417D01*
X292600Y-48500D01*
X293067Y-48333D01*
X293533Y-47833D01*
G01X296567Y-48500D02*
Y-45167D01*
G01Y-45833D02*
X296900Y-45500D01*
X297233Y-45250D01*
X297700Y-45167D01*
X298033Y-45250D01*
X298433Y-45500D01*
G01X305700Y-48500D02*
Y-45167D01*
G01Y-46083D02*
X305900Y-45667D01*
X306233Y-45333D01*
X306700Y-45167D01*
X307167Y-45333D01*
X307500Y-45667D01*
X307700Y-46083D01*
Y-48500D01*
G01Y-46083D02*
X307900Y-45667D01*
X308233Y-45333D01*
X308700Y-45167D01*
X309167Y-45333D01*
X309500Y-45667D01*
X309700Y-46167D01*
Y-48500D01*
G01X314000D02*
Y-45167D01*
G01Y-45750D02*
X313733Y-45417D01*
X313333Y-45250D01*
X312867Y-45167D01*
X312400Y-45333D01*
X312000Y-45667D01*
X311733Y-46167D01*
X311600Y-46833D01*
X311733Y-47500D01*
X312000Y-48000D01*
X312400Y-48333D01*
X312867Y-48500D01*
X313333Y-48417D01*
X313733Y-48167D01*
X314000Y-47833D01*
G01X316900Y-47917D02*
X317233Y-48250D01*
X317700Y-48500D01*
X318100D01*
X318500Y-48333D01*
X318767Y-48083D01*
X318900Y-47750D01*
X318833Y-47250D01*
X318567Y-47000D01*
X317367Y-46500D01*
X317100Y-45917D01*
X317233Y-45500D01*
X317500Y-45250D01*
X317900Y-45167D01*
X318300Y-45250D01*
X318700Y-45500D01*
G01X321867Y-48500D02*
Y-43500D01*
G01X324000Y-45167D02*
X321867Y-47083D01*
G01X322733Y-46333D02*
X324133Y-48500D01*
G01X333200Y-43500D02*
Y-48500D01*
G01X332267Y-45167D02*
X334133D01*
G01X337167Y-48500D02*
Y-43500D01*
G01Y-45917D02*
X337500Y-45500D01*
X337833Y-45250D01*
X338367Y-45167D01*
X338767Y-45250D01*
X339233Y-45583D01*
X339433Y-46083D01*
Y-48500D01*
G01X343400Y-45167D02*
Y-48500D01*
G01Y-43833D02*
X343267Y-43750D01*
Y-43583D01*
X343400Y-43500D01*
X343533Y-43583D01*
Y-43750D01*
X343400Y-43833D01*
G01X349567Y-45583D02*
X349100Y-45250D01*
X348700Y-45167D01*
X348167Y-45333D01*
X347767Y-45667D01*
X347500Y-46250D01*
X347433Y-46833D01*
X347500Y-47417D01*
X347767Y-47917D01*
X348167Y-48333D01*
X348700Y-48500D01*
X349167Y-48333D01*
X349567Y-48000D01*
G01X352467Y-48500D02*
Y-43500D01*
G01X354600Y-45167D02*
X352467Y-47083D01*
G01X353333Y-46333D02*
X354733Y-48500D01*
G01X357567D02*
Y-45167D01*
G01Y-46000D02*
X357833Y-45583D01*
X358233Y-45250D01*
X358767Y-45167D01*
X359233Y-45250D01*
X359633Y-45583D01*
X359833Y-46167D01*
Y-48500D01*
G01X362800Y-46250D02*
X364933D01*
X364733Y-45667D01*
X364400Y-45333D01*
X363933Y-45167D01*
X363467Y-45250D01*
X363067Y-45500D01*
X362800Y-46083D01*
X362667Y-46583D01*
Y-47083D01*
X362800Y-47583D01*
X363133Y-48083D01*
X363533Y-48417D01*
X364000Y-48500D01*
X364467Y-48333D01*
X364933Y-47833D01*
G01X367900Y-47917D02*
X368233Y-48250D01*
X368700Y-48500D01*
X369100D01*
X369500Y-48333D01*
X369767Y-48083D01*
X369900Y-47750D01*
X369833Y-47250D01*
X369567Y-47000D01*
X368367Y-46500D01*
X368100Y-45917D01*
X368233Y-45500D01*
X368500Y-45250D01*
X368900Y-45167D01*
X369300Y-45250D01*
X369700Y-45500D01*
G01X373000Y-47917D02*
X373333Y-48250D01*
X373800Y-48500D01*
X374200D01*
X374600Y-48333D01*
X374867Y-48083D01*
X375000Y-47750D01*
X374933Y-47250D01*
X374667Y-47000D01*
X373467Y-46500D01*
X373200Y-45917D01*
X373333Y-45500D01*
X373600Y-45250D01*
X374000Y-45167D01*
X374400Y-45250D01*
X374800Y-45500D01*
G01X383000Y-50167D02*
Y-45167D01*
G01Y-45917D02*
X383333Y-45500D01*
X383667Y-45250D01*
X384200Y-45167D01*
X384667Y-45250D01*
X385133Y-45667D01*
X385333Y-46250D01*
X385400Y-46833D01*
X385333Y-47417D01*
X385133Y-48000D01*
X384733Y-48333D01*
X384200Y-48500D01*
X383733Y-48417D01*
X383267Y-48167D01*
X383000Y-47833D01*
G01X389300Y-48500D02*
Y-43500D01*
G01X393267Y-45167D02*
Y-47500D01*
X393533Y-48083D01*
X393933Y-48417D01*
X394400Y-48500D01*
X394867Y-48417D01*
X395267Y-48083D01*
X395533Y-47500D01*
G01Y-48500D02*
Y-45167D01*
G01X398500Y-47917D02*
X398833Y-48250D01*
X399300Y-48500D01*
X399700D01*
X400100Y-48333D01*
X400367Y-48083D01*
X400500Y-47750D01*
X400433Y-47250D01*
X400167Y-47000D01*
X398967Y-46500D01*
X398700Y-45917D01*
X398833Y-45500D01*
X399100Y-45250D01*
X399500Y-45167D01*
X399900Y-45250D01*
X400300Y-45500D01*
G01X409700Y-48500D02*
Y-43500D01*
G01X413800Y-46250D02*
X415933D01*
X415733Y-45667D01*
X415400Y-45333D01*
X414933Y-45167D01*
X414467Y-45250D01*
X414067Y-45500D01*
X413800Y-46083D01*
X413667Y-46583D01*
Y-47083D01*
X413800Y-47583D01*
X414133Y-48083D01*
X414533Y-48417D01*
X415000Y-48500D01*
X415467Y-48333D01*
X415933Y-47833D01*
G01X418967Y-49750D02*
X419433Y-50083D01*
X419967Y-50167D01*
X420433Y-50083D01*
X420833Y-49667D01*
X421100Y-49083D01*
Y-45167D01*
G01Y-45833D02*
X420833Y-45500D01*
X420433Y-45250D01*
X419967Y-45167D01*
X419433Y-45333D01*
X419100Y-45667D01*
X418833Y-46250D01*
X418700Y-46833D01*
X418767Y-47333D01*
X419033Y-47917D01*
X419433Y-48333D01*
X419967Y-48500D01*
X420367Y-48417D01*
X420833Y-48083D01*
X421100Y-47750D01*
G01X424000Y-46250D02*
X426133D01*
X425933Y-45667D01*
X425600Y-45333D01*
X425133Y-45167D01*
X424667Y-45250D01*
X424267Y-45500D01*
X424000Y-46083D01*
X423867Y-46583D01*
Y-47083D01*
X424000Y-47583D01*
X424333Y-48083D01*
X424733Y-48417D01*
X425200Y-48500D01*
X425667Y-48333D01*
X426133Y-47833D01*
G01X428967Y-48500D02*
Y-45167D01*
G01Y-46000D02*
X429233Y-45583D01*
X429633Y-45250D01*
X430167Y-45167D01*
X430633Y-45250D01*
X431033Y-45583D01*
X431233Y-46167D01*
Y-48500D01*
G01X436400Y-43500D02*
Y-48500D01*
G01Y-47750D02*
X436133Y-48167D01*
X435733Y-48417D01*
X435267Y-48500D01*
X434733Y-48333D01*
X434333Y-47917D01*
X434067Y-47417D01*
X434000Y-46833D01*
X434067Y-46250D01*
X434333Y-45750D01*
X434733Y-45333D01*
X435267Y-45167D01*
X435733Y-45250D01*
X436067Y-45417D01*
X436400Y-45750D01*
G01X445400Y-43500D02*
Y-48500D01*
G01X444467Y-45167D02*
X446333D01*
G01X449367Y-48500D02*
Y-43500D01*
G01Y-45917D02*
X449700Y-45500D01*
X450033Y-45250D01*
X450567Y-45167D01*
X450967Y-45250D01*
X451433Y-45583D01*
X451633Y-46083D01*
Y-48500D01*
G01X455600Y-45167D02*
Y-48500D01*
G01Y-43833D02*
X455467Y-43750D01*
Y-43583D01*
X455600Y-43500D01*
X455733Y-43583D01*
Y-43750D01*
X455600Y-43833D01*
G01X461767Y-45583D02*
X461300Y-45250D01*
X460900Y-45167D01*
X460367Y-45333D01*
X459967Y-45667D01*
X459700Y-46250D01*
X459633Y-46833D01*
X459700Y-47417D01*
X459967Y-47917D01*
X460367Y-48333D01*
X460900Y-48500D01*
X461367Y-48333D01*
X461767Y-48000D01*
G01X464667Y-48500D02*
Y-43500D01*
G01X466800Y-45167D02*
X464667Y-47083D01*
G01X465533Y-46333D02*
X466933Y-48500D01*
G01X469767D02*
Y-45167D01*
G01Y-46000D02*
X470033Y-45583D01*
X470433Y-45250D01*
X470967Y-45167D01*
X471433Y-45250D01*
X471833Y-45583D01*
X472033Y-46167D01*
Y-48500D01*
G01X475000Y-46250D02*
X477133D01*
X476933Y-45667D01*
X476600Y-45333D01*
X476133Y-45167D01*
X475667Y-45250D01*
X475267Y-45500D01*
X475000Y-46083D01*
X474867Y-46583D01*
Y-47083D01*
X475000Y-47583D01*
X475333Y-48083D01*
X475733Y-48417D01*
X476200Y-48500D01*
X476667Y-48333D01*
X477133Y-47833D01*
G01X480100Y-47917D02*
X480433Y-48250D01*
X480900Y-48500D01*
X481300D01*
X481700Y-48333D01*
X481967Y-48083D01*
X482100Y-47750D01*
X482033Y-47250D01*
X481767Y-47000D01*
X480567Y-46500D01*
X480300Y-45917D01*
X480433Y-45500D01*
X480700Y-45250D01*
X481100Y-45167D01*
X481500Y-45250D01*
X481900Y-45500D01*
G01X485200Y-47917D02*
X485533Y-48250D01*
X486000Y-48500D01*
X486400D01*
X486800Y-48333D01*
X487067Y-48083D01*
X487200Y-47750D01*
X487133Y-47250D01*
X486867Y-47000D01*
X485667Y-46500D01*
X485400Y-45917D01*
X485533Y-45500D01*
X485800Y-45250D01*
X486200Y-45167D01*
X486600Y-45250D01*
X487000Y-45500D01*
G01X496400Y-48500D02*
X496000Y-48417D01*
X495600Y-48083D01*
X495333Y-47500D01*
X495200Y-46833D01*
X495333Y-46167D01*
X495600Y-45583D01*
X496000Y-45250D01*
X496400Y-45167D01*
X496800Y-45250D01*
X497200Y-45583D01*
X497467Y-46167D01*
X497533Y-46833D01*
X497467Y-47500D01*
X497200Y-48083D01*
X496800Y-48417D01*
X496400Y-48500D01*
G01X500367D02*
Y-45167D01*
G01Y-46000D02*
X500633Y-45583D01*
X501033Y-45250D01*
X501567Y-45167D01*
X502033Y-45250D01*
X502433Y-45583D01*
X502633Y-46167D01*
Y-48500D01*
G01X511700Y-43500D02*
Y-48500D01*
G01X510767Y-45167D02*
X512633D01*
G01X515867Y-48500D02*
Y-45167D01*
G01Y-45833D02*
X516200Y-45500D01*
X516533Y-45250D01*
X517000Y-45167D01*
X517333Y-45250D01*
X517733Y-45500D01*
G01X523100Y-48500D02*
Y-45167D01*
G01Y-45750D02*
X522833Y-45417D01*
X522433Y-45250D01*
X521967Y-45167D01*
X521500Y-45333D01*
X521100Y-45667D01*
X520833Y-46167D01*
X520700Y-46833D01*
X520833Y-47500D01*
X521100Y-48000D01*
X521500Y-48333D01*
X521967Y-48500D01*
X522433Y-48417D01*
X522833Y-48167D01*
X523100Y-47833D01*
G01X528067Y-45583D02*
X527600Y-45250D01*
X527200Y-45167D01*
X526667Y-45333D01*
X526267Y-45667D01*
X526000Y-46250D01*
X525933Y-46833D01*
X526000Y-47417D01*
X526267Y-47917D01*
X526667Y-48333D01*
X527200Y-48500D01*
X527667Y-48333D01*
X528067Y-48000D01*
G01X531100Y-46250D02*
X533233D01*
X533033Y-45667D01*
X532700Y-45333D01*
X532233Y-45167D01*
X531767Y-45250D01*
X531367Y-45500D01*
X531100Y-46083D01*
X530967Y-46583D01*
Y-47083D01*
X531100Y-47583D01*
X531433Y-48083D01*
X531833Y-48417D01*
X532300Y-48500D01*
X532767Y-48333D01*
X533233Y-47833D01*
G01X537200Y-48667D02*
X537067Y-48583D01*
Y-48417D01*
X537200Y-48333D01*
X537333Y-48417D01*
Y-48583D01*
X537200Y-48667D01*
G01X272000Y-33500D02*
Y-28500D01*
G01X276100Y-31250D02*
X278233D01*
X278033Y-30667D01*
X277700Y-30333D01*
X277233Y-30167D01*
X276767Y-30250D01*
X276367Y-30500D01*
X276100Y-31083D01*
X275967Y-31583D01*
Y-32083D01*
X276100Y-32583D01*
X276433Y-33083D01*
X276833Y-33417D01*
X277300Y-33500D01*
X277767Y-33333D01*
X278233Y-32833D01*
G01X281267Y-34750D02*
X281733Y-35083D01*
X282267Y-35167D01*
X282733Y-35083D01*
X283133Y-34667D01*
X283400Y-34083D01*
Y-30167D01*
G01Y-30833D02*
X283133Y-30500D01*
X282733Y-30250D01*
X282267Y-30167D01*
X281733Y-30333D01*
X281400Y-30667D01*
X281133Y-31250D01*
X281000Y-31833D01*
X281067Y-32333D01*
X281333Y-32917D01*
X281733Y-33333D01*
X282267Y-33500D01*
X282667Y-33417D01*
X283133Y-33083D01*
X283400Y-32750D01*
G01X286300Y-31250D02*
X288433D01*
X288233Y-30667D01*
X287900Y-30333D01*
X287433Y-30167D01*
X286967Y-30250D01*
X286567Y-30500D01*
X286300Y-31083D01*
X286167Y-31583D01*
Y-32083D01*
X286300Y-32583D01*
X286633Y-33083D01*
X287033Y-33417D01*
X287500Y-33500D01*
X287967Y-33333D01*
X288433Y-32833D01*
G01X291267Y-33500D02*
Y-30167D01*
G01Y-31000D02*
X291533Y-30583D01*
X291933Y-30250D01*
X292467Y-30167D01*
X292933Y-30250D01*
X293333Y-30583D01*
X293533Y-31167D01*
Y-33500D01*
G01X298700Y-28500D02*
Y-33500D01*
G01Y-32750D02*
X298433Y-33167D01*
X298033Y-33417D01*
X297567Y-33500D01*
X297033Y-33333D01*
X296633Y-32917D01*
X296367Y-32417D01*
X296300Y-31833D01*
X296367Y-31250D01*
X296633Y-30750D01*
X297033Y-30333D01*
X297567Y-30167D01*
X298033Y-30250D01*
X298367Y-30417D01*
X298700Y-30750D01*
G01X307700Y-28500D02*
Y-33500D01*
G01X306767Y-30167D02*
X308633D01*
G01X311667Y-33500D02*
Y-28500D01*
G01Y-30917D02*
X312000Y-30500D01*
X312333Y-30250D01*
X312867Y-30167D01*
X313267Y-30250D01*
X313733Y-30583D01*
X313933Y-31083D01*
Y-33500D01*
G01X317900Y-30167D02*
Y-33500D01*
G01Y-28833D02*
X317767Y-28750D01*
Y-28583D01*
X317900Y-28500D01*
X318033Y-28583D01*
Y-28750D01*
X317900Y-28833D01*
G01X324067Y-30583D02*
X323600Y-30250D01*
X323200Y-30167D01*
X322667Y-30333D01*
X322267Y-30667D01*
X322000Y-31250D01*
X321933Y-31833D01*
X322000Y-32417D01*
X322267Y-32917D01*
X322667Y-33333D01*
X323200Y-33500D01*
X323667Y-33333D01*
X324067Y-33000D01*
G01X326967Y-33500D02*
Y-28500D01*
G01X329100Y-30167D02*
X326967Y-32083D01*
G01X327833Y-31333D02*
X329233Y-33500D01*
G01X332067D02*
Y-30167D01*
G01Y-31000D02*
X332333Y-30583D01*
X332733Y-30250D01*
X333267Y-30167D01*
X333733Y-30250D01*
X334133Y-30583D01*
X334333Y-31167D01*
Y-33500D01*
G01X337300Y-31250D02*
X339433D01*
X339233Y-30667D01*
X338900Y-30333D01*
X338433Y-30167D01*
X337967Y-30250D01*
X337567Y-30500D01*
X337300Y-31083D01*
X337167Y-31583D01*
Y-32083D01*
X337300Y-32583D01*
X337633Y-33083D01*
X338033Y-33417D01*
X338500Y-33500D01*
X338967Y-33333D01*
X339433Y-32833D01*
G01X342400Y-32917D02*
X342733Y-33250D01*
X343200Y-33500D01*
X343600D01*
X344000Y-33333D01*
X344267Y-33083D01*
X344400Y-32750D01*
X344333Y-32250D01*
X344067Y-32000D01*
X342867Y-31500D01*
X342600Y-30917D01*
X342733Y-30500D01*
X343000Y-30250D01*
X343400Y-30167D01*
X343800Y-30250D01*
X344200Y-30500D01*
G01X347500Y-32917D02*
X347833Y-33250D01*
X348300Y-33500D01*
X348700D01*
X349100Y-33333D01*
X349367Y-33083D01*
X349500Y-32750D01*
X349433Y-32250D01*
X349167Y-32000D01*
X347967Y-31500D01*
X347700Y-30917D01*
X347833Y-30500D01*
X348100Y-30250D01*
X348500Y-30167D01*
X348900Y-30250D01*
X349300Y-30500D01*
G01X358700Y-33500D02*
X358300Y-33417D01*
X357900Y-33083D01*
X357633Y-32500D01*
X357500Y-31833D01*
X357633Y-31167D01*
X357900Y-30583D01*
X358300Y-30250D01*
X358700Y-30167D01*
X359100Y-30250D01*
X359500Y-30583D01*
X359767Y-31167D01*
X359833Y-31833D01*
X359767Y-32500D01*
X359500Y-33083D01*
X359100Y-33417D01*
X358700Y-33500D01*
G01X362667D02*
Y-30167D01*
G01Y-31000D02*
X362933Y-30583D01*
X363333Y-30250D01*
X363867Y-30167D01*
X364333Y-30250D01*
X364733Y-30583D01*
X364933Y-31167D01*
Y-33500D01*
G01X375067Y-30583D02*
X374600Y-30250D01*
X374200Y-30167D01*
X373667Y-30333D01*
X373267Y-30667D01*
X373000Y-31250D01*
X372933Y-31833D01*
X373000Y-32417D01*
X373267Y-32917D01*
X373667Y-33333D01*
X374200Y-33500D01*
X374667Y-33333D01*
X375067Y-33000D01*
G01X379100Y-33500D02*
X378700Y-33417D01*
X378300Y-33083D01*
X378033Y-32500D01*
X377900Y-31833D01*
X378033Y-31167D01*
X378300Y-30583D01*
X378700Y-30250D01*
X379100Y-30167D01*
X379500Y-30250D01*
X379900Y-30583D01*
X380167Y-31167D01*
X380233Y-31833D01*
X380167Y-32500D01*
X379900Y-33083D01*
X379500Y-33417D01*
X379100Y-33500D01*
G01X383000Y-35167D02*
Y-30167D01*
G01Y-30917D02*
X383333Y-30500D01*
X383667Y-30250D01*
X384200Y-30167D01*
X384667Y-30250D01*
X385133Y-30667D01*
X385333Y-31250D01*
X385400Y-31833D01*
X385333Y-32417D01*
X385133Y-33000D01*
X384733Y-33333D01*
X384200Y-33500D01*
X383733Y-33417D01*
X383267Y-33167D01*
X383000Y-32833D01*
G01X388100Y-35167D02*
Y-30167D01*
G01Y-30917D02*
X388433Y-30500D01*
X388767Y-30250D01*
X389300Y-30167D01*
X389767Y-30250D01*
X390233Y-30667D01*
X390433Y-31250D01*
X390500Y-31833D01*
X390433Y-32417D01*
X390233Y-33000D01*
X389833Y-33333D01*
X389300Y-33500D01*
X388833Y-33417D01*
X388367Y-33167D01*
X388100Y-32833D01*
G01X393400Y-31250D02*
X395533D01*
X395333Y-30667D01*
X395000Y-30333D01*
X394533Y-30167D01*
X394067Y-30250D01*
X393667Y-30500D01*
X393400Y-31083D01*
X393267Y-31583D01*
Y-32083D01*
X393400Y-32583D01*
X393733Y-33083D01*
X394133Y-33417D01*
X394600Y-33500D01*
X395067Y-33333D01*
X395533Y-32833D01*
G01X398567Y-33500D02*
Y-30167D01*
G01Y-30833D02*
X398900Y-30500D01*
X399233Y-30250D01*
X399700Y-30167D01*
X400033Y-30250D01*
X400433Y-30500D01*
G01X409367Y-35167D02*
X408700Y-34333D01*
X408367Y-33500D01*
Y-30167D01*
X408700Y-29333D01*
X409367Y-28500D01*
G01X413133Y-30167D02*
X413933Y-33500D01*
X414800Y-30167D01*
X415667Y-33500D01*
X416467Y-30167D01*
G01X418767Y-33500D02*
Y-28500D01*
G01Y-30917D02*
X419100Y-30500D01*
X419433Y-30250D01*
X419967Y-30167D01*
X420367Y-30250D01*
X420833Y-30583D01*
X421033Y-31083D01*
Y-33500D01*
G01X425000Y-30167D02*
Y-33500D01*
G01Y-28833D02*
X424867Y-28750D01*
Y-28583D01*
X425000Y-28500D01*
X425133Y-28583D01*
Y-28750D01*
X425000Y-28833D01*
G01X431167Y-30583D02*
X430700Y-30250D01*
X430300Y-30167D01*
X429767Y-30333D01*
X429367Y-30667D01*
X429100Y-31250D01*
X429033Y-31833D01*
X429100Y-32417D01*
X429367Y-32917D01*
X429767Y-33333D01*
X430300Y-33500D01*
X430767Y-33333D01*
X431167Y-33000D01*
G01X434067Y-33500D02*
Y-28500D01*
G01Y-30917D02*
X434400Y-30500D01*
X434733Y-30250D01*
X435267Y-30167D01*
X435667Y-30250D01*
X436133Y-30583D01*
X436333Y-31083D01*
Y-33500D01*
G01X445400Y-30167D02*
Y-33500D01*
G01Y-28833D02*
X445267Y-28750D01*
Y-28583D01*
X445400Y-28500D01*
X445533Y-28583D01*
Y-28750D01*
X445400Y-28833D01*
G01X449500Y-32917D02*
X449833Y-33250D01*
X450300Y-33500D01*
X450700D01*
X451100Y-33333D01*
X451367Y-33083D01*
X451500Y-32750D01*
X451433Y-32250D01*
X451167Y-32000D01*
X449967Y-31500D01*
X449700Y-30917D01*
X449833Y-30500D01*
X450100Y-30250D01*
X450500Y-30167D01*
X450900Y-30250D01*
X451300Y-30500D01*
G01X459500Y-33500D02*
Y-28500D01*
G01Y-31000D02*
X459833Y-30500D01*
X460233Y-30250D01*
X460633Y-30167D01*
X461233Y-30333D01*
X461633Y-30667D01*
X461900Y-31250D01*
Y-31917D01*
X461767Y-32583D01*
X461500Y-33083D01*
X461033Y-33417D01*
X460633Y-33500D01*
X460233Y-33417D01*
X459833Y-33167D01*
X459500Y-32750D01*
G01X464800Y-31250D02*
X466933D01*
X466733Y-30667D01*
X466400Y-30333D01*
X465933Y-30167D01*
X465467Y-30250D01*
X465067Y-30500D01*
X464800Y-31083D01*
X464667Y-31583D01*
Y-32083D01*
X464800Y-32583D01*
X465133Y-33083D01*
X465533Y-33417D01*
X466000Y-33500D01*
X466467Y-33333D01*
X466933Y-32833D01*
G01X470900Y-28500D02*
Y-33500D01*
G01X469967Y-30167D02*
X471833D01*
G01X476000Y-28500D02*
Y-33500D01*
G01X475067Y-30167D02*
X476933D01*
G01X480100Y-31250D02*
X482233D01*
X482033Y-30667D01*
X481700Y-30333D01*
X481233Y-30167D01*
X480767Y-30250D01*
X480367Y-30500D01*
X480100Y-31083D01*
X479967Y-31583D01*
Y-32083D01*
X480100Y-32583D01*
X480433Y-33083D01*
X480833Y-33417D01*
X481300Y-33500D01*
X481767Y-33333D01*
X482233Y-32833D01*
G01X485267Y-33500D02*
Y-30167D01*
G01Y-30833D02*
X485600Y-30500D01*
X485933Y-30250D01*
X486400Y-30167D01*
X486733Y-30250D01*
X487133Y-30500D01*
G01X491633Y-35167D02*
X492300Y-34333D01*
X492633Y-33500D01*
Y-30167D01*
X492300Y-29333D01*
X491633Y-28500D01*
G01X264000Y-39500D02*
X694500D01*
G01X262500Y-69500D02*
Y439000D01*
G01X272000Y0D02*
Y-5000D01*
G01X270467Y0D02*
X273533D01*
G01X275967Y-5000D02*
Y0D01*
G01Y-2417D02*
X276300Y-2000D01*
X276633Y-1750D01*
X277167Y-1667D01*
X277567Y-1750D01*
X278033Y-2083D01*
X278233Y-2583D01*
Y-5000D01*
G01X281200Y-2750D02*
X283333D01*
X283133Y-2167D01*
X282800Y-1833D01*
X282333Y-1667D01*
X281867Y-1750D01*
X281467Y-2000D01*
X281200Y-2583D01*
X281067Y-3083D01*
Y-3583D01*
X281200Y-4083D01*
X281533Y-4583D01*
X281933Y-4917D01*
X282400Y-5000D01*
X282867Y-4833D01*
X283333Y-4333D01*
G01X292400Y-5000D02*
Y0D01*
G01X298700Y-5000D02*
Y-1667D01*
G01Y-2250D02*
X298433Y-1917D01*
X298033Y-1750D01*
X297567Y-1667D01*
X297100Y-1833D01*
X296700Y-2167D01*
X296433Y-2667D01*
X296300Y-3333D01*
X296433Y-4000D01*
X296700Y-4500D01*
X297100Y-4833D01*
X297567Y-5000D01*
X298033Y-4917D01*
X298433Y-4667D01*
X298700Y-4333D01*
G01X301667Y-5000D02*
Y-1667D01*
G01Y-2333D02*
X302000Y-2000D01*
X302333Y-1750D01*
X302800Y-1667D01*
X303133Y-1750D01*
X303533Y-2000D01*
G01X306767Y-6250D02*
X307233Y-6583D01*
X307767Y-6667D01*
X308233Y-6583D01*
X308633Y-6167D01*
X308900Y-5583D01*
Y-1667D01*
G01Y-2333D02*
X308633Y-2000D01*
X308233Y-1750D01*
X307767Y-1667D01*
X307233Y-1833D01*
X306900Y-2167D01*
X306633Y-2750D01*
X306500Y-3333D01*
X306567Y-3833D01*
X306833Y-4417D01*
X307233Y-4833D01*
X307767Y-5000D01*
X308167Y-4917D01*
X308633Y-4583D01*
X308900Y-4250D01*
G01X311800Y-2750D02*
X313933D01*
X313733Y-2167D01*
X313400Y-1833D01*
X312933Y-1667D01*
X312467Y-1750D01*
X312067Y-2000D01*
X311800Y-2583D01*
X311667Y-3083D01*
Y-3583D01*
X311800Y-4083D01*
X312133Y-4583D01*
X312533Y-4917D01*
X313000Y-5000D01*
X313467Y-4833D01*
X313933Y-4333D01*
G01X316900Y-4417D02*
X317233Y-4750D01*
X317700Y-5000D01*
X318100D01*
X318500Y-4833D01*
X318767Y-4583D01*
X318900Y-4250D01*
X318833Y-3750D01*
X318567Y-3500D01*
X317367Y-3000D01*
X317100Y-2417D01*
X317233Y-2000D01*
X317500Y-1750D01*
X317900Y-1667D01*
X318300Y-1750D01*
X318700Y-2000D01*
G01X323000Y0D02*
Y-5000D01*
G01X322067Y-1667D02*
X323933D01*
G01X334400Y0D02*
Y-5000D01*
G01Y-4250D02*
X334133Y-4667D01*
X333733Y-4917D01*
X333267Y-5000D01*
X332733Y-4833D01*
X332333Y-4417D01*
X332067Y-3917D01*
X332000Y-3333D01*
X332067Y-2750D01*
X332333Y-2250D01*
X332733Y-1833D01*
X333267Y-1667D01*
X333733Y-1750D01*
X334067Y-1917D01*
X334400Y-2250D01*
G01X338300Y-1667D02*
Y-5000D01*
G01Y-333D02*
X338167Y-250D01*
Y-83D01*
X338300Y0D01*
X338433Y-83D01*
Y-250D01*
X338300Y-333D01*
G01X341400Y-5000D02*
Y-1667D01*
G01Y-2583D02*
X341600Y-2167D01*
X341933Y-1833D01*
X342400Y-1667D01*
X342867Y-1833D01*
X343200Y-2167D01*
X343400Y-2583D01*
Y-5000D01*
G01Y-2583D02*
X343600Y-2167D01*
X343933Y-1833D01*
X344400Y-1667D01*
X344867Y-1833D01*
X345200Y-2167D01*
X345400Y-2667D01*
Y-5000D01*
G01X347500Y-2750D02*
X349633D01*
X349433Y-2167D01*
X349100Y-1833D01*
X348633Y-1667D01*
X348167Y-1750D01*
X347767Y-2000D01*
X347500Y-2583D01*
X347367Y-3083D01*
Y-3583D01*
X347500Y-4083D01*
X347833Y-4583D01*
X348233Y-4917D01*
X348700Y-5000D01*
X349167Y-4833D01*
X349633Y-4333D01*
G01X352467Y-5000D02*
Y-1667D01*
G01Y-2500D02*
X352733Y-2083D01*
X353133Y-1750D01*
X353667Y-1667D01*
X354133Y-1750D01*
X354533Y-2083D01*
X354733Y-2667D01*
Y-5000D01*
G01X357700Y-4417D02*
X358033Y-4750D01*
X358500Y-5000D01*
X358900D01*
X359300Y-4833D01*
X359567Y-4583D01*
X359700Y-4250D01*
X359633Y-3750D01*
X359367Y-3500D01*
X358167Y-3000D01*
X357900Y-2417D01*
X358033Y-2000D01*
X358300Y-1750D01*
X358700Y-1667D01*
X359100Y-1750D01*
X359500Y-2000D01*
G01X363800Y-1667D02*
Y-5000D01*
G01Y-333D02*
X363667Y-250D01*
Y-83D01*
X363800Y0D01*
X363933Y-83D01*
Y-250D01*
X363800Y-333D01*
G01X368900Y-5000D02*
X368500Y-4917D01*
X368100Y-4583D01*
X367833Y-4000D01*
X367700Y-3333D01*
X367833Y-2667D01*
X368100Y-2083D01*
X368500Y-1750D01*
X368900Y-1667D01*
X369300Y-1750D01*
X369700Y-2083D01*
X369967Y-2667D01*
X370033Y-3333D01*
X369967Y-4000D01*
X369700Y-4583D01*
X369300Y-4917D01*
X368900Y-5000D01*
G01X372867D02*
Y-1667D01*
G01Y-2500D02*
X373133Y-2083D01*
X373533Y-1750D01*
X374067Y-1667D01*
X374533Y-1750D01*
X374933Y-2083D01*
X375133Y-2667D01*
Y-5000D01*
G01X384200D02*
X383800Y-4917D01*
X383400Y-4583D01*
X383133Y-4000D01*
X383000Y-3333D01*
X383133Y-2667D01*
X383400Y-2083D01*
X383800Y-1750D01*
X384200Y-1667D01*
X384600Y-1750D01*
X385000Y-2083D01*
X385267Y-2667D01*
X385333Y-3333D01*
X385267Y-4000D01*
X385000Y-4583D01*
X384600Y-4917D01*
X384200Y-5000D01*
G01X388900D02*
Y-750D01*
X389033Y-333D01*
X389300Y-83D01*
X389700Y0D01*
X390100Y-167D01*
X390300Y-583D01*
G01X389500Y-2000D02*
X388167D01*
G01X398300Y-6667D02*
Y-1667D01*
G01Y-2417D02*
X398633Y-2000D01*
X398967Y-1750D01*
X399500Y-1667D01*
X399967Y-1750D01*
X400433Y-2167D01*
X400633Y-2750D01*
X400700Y-3333D01*
X400633Y-3917D01*
X400433Y-4500D01*
X400033Y-4833D01*
X399500Y-5000D01*
X399033Y-4917D01*
X398567Y-4667D01*
X398300Y-4333D01*
G01X405800Y-5000D02*
Y-1667D01*
G01Y-2250D02*
X405533Y-1917D01*
X405133Y-1750D01*
X404667Y-1667D01*
X404200Y-1833D01*
X403800Y-2167D01*
X403533Y-2667D01*
X403400Y-3333D01*
X403533Y-4000D01*
X403800Y-4500D01*
X404200Y-4833D01*
X404667Y-5000D01*
X405133Y-4917D01*
X405533Y-4667D01*
X405800Y-4333D01*
G01X410900Y0D02*
Y-5000D01*
G01Y-4250D02*
X410633Y-4667D01*
X410233Y-4917D01*
X409767Y-5000D01*
X409233Y-4833D01*
X408833Y-4417D01*
X408567Y-3917D01*
X408500Y-3333D01*
X408567Y-2750D01*
X408833Y-2250D01*
X409233Y-1833D01*
X409767Y-1667D01*
X410233Y-1750D01*
X410567Y-1917D01*
X410900Y-2250D01*
G01X419900Y-5000D02*
X419500Y-4917D01*
X419100Y-4583D01*
X418833Y-4000D01*
X418700Y-3333D01*
X418833Y-2667D01*
X419100Y-2083D01*
X419500Y-1750D01*
X419900Y-1667D01*
X420300Y-1750D01*
X420700Y-2083D01*
X420967Y-2667D01*
X421033Y-3333D01*
X420967Y-4000D01*
X420700Y-4583D01*
X420300Y-4917D01*
X419900Y-5000D01*
G01X424067D02*
Y-1667D01*
G01Y-2333D02*
X424400Y-2000D01*
X424733Y-1750D01*
X425200Y-1667D01*
X425533Y-1750D01*
X425933Y-2000D01*
G01X436400Y0D02*
Y-5000D01*
G01Y-4250D02*
X436133Y-4667D01*
X435733Y-4917D01*
X435267Y-5000D01*
X434733Y-4833D01*
X434333Y-4417D01*
X434067Y-3917D01*
X434000Y-3333D01*
X434067Y-2750D01*
X434333Y-2250D01*
X434733Y-1833D01*
X435267Y-1667D01*
X435733Y-1750D01*
X436067Y-1917D01*
X436400Y-2250D01*
G01X440300Y-1667D02*
Y-5000D01*
G01Y-333D02*
X440167Y-250D01*
Y-83D01*
X440300Y0D01*
X440433Y-83D01*
Y-250D01*
X440300Y-333D01*
G01X446600Y-5000D02*
Y-1667D01*
G01Y-2250D02*
X446333Y-1917D01*
X445933Y-1750D01*
X445467Y-1667D01*
X445000Y-1833D01*
X444600Y-2167D01*
X444333Y-2667D01*
X444200Y-3333D01*
X444333Y-4000D01*
X444600Y-4500D01*
X445000Y-4833D01*
X445467Y-5000D01*
X445933Y-4917D01*
X446333Y-4667D01*
X446600Y-4333D01*
G01X448500Y-5000D02*
Y-1667D01*
G01Y-2583D02*
X448700Y-2167D01*
X449033Y-1833D01*
X449500Y-1667D01*
X449967Y-1833D01*
X450300Y-2167D01*
X450500Y-2583D01*
Y-5000D01*
G01Y-2583D02*
X450700Y-2167D01*
X451033Y-1833D01*
X451500Y-1667D01*
X451967Y-1833D01*
X452300Y-2167D01*
X452500Y-2667D01*
Y-5000D01*
G01X454600Y-2750D02*
X456733D01*
X456533Y-2167D01*
X456200Y-1833D01*
X455733Y-1667D01*
X455267Y-1750D01*
X454867Y-2000D01*
X454600Y-2583D01*
X454467Y-3083D01*
Y-3583D01*
X454600Y-4083D01*
X454933Y-4583D01*
X455333Y-4917D01*
X455800Y-5000D01*
X456267Y-4833D01*
X456733Y-4333D01*
G01X460700Y0D02*
Y-5000D01*
G01X459767Y-1667D02*
X461633D01*
G01X464800Y-2750D02*
X466933D01*
X466733Y-2167D01*
X466400Y-1833D01*
X465933Y-1667D01*
X465467Y-1750D01*
X465067Y-2000D01*
X464800Y-2583D01*
X464667Y-3083D01*
Y-3583D01*
X464800Y-4083D01*
X465133Y-4583D01*
X465533Y-4917D01*
X466000Y-5000D01*
X466467Y-4833D01*
X466933Y-4333D01*
G01X469967Y-5000D02*
Y-1667D01*
G01Y-2333D02*
X470300Y-2000D01*
X470633Y-1750D01*
X471100Y-1667D01*
X471433Y-1750D01*
X471833Y-2000D01*
G01X482433Y-5000D02*
X479767Y-3333D01*
X482433Y-1667D01*
G01X485333Y-4083D02*
X487067D01*
G01Y-2583D02*
X485333D01*
G01X496400Y-5000D02*
Y0D01*
X495600Y-1000D01*
G01Y-5000D02*
X497200D01*
G01X502300D02*
Y0D01*
X499833Y-3583D01*
X503167D01*
G01X509700Y-5000D02*
Y-1667D01*
G01Y-2583D02*
X509900Y-2167D01*
X510233Y-1833D01*
X510700Y-1667D01*
X511167Y-1833D01*
X511500Y-2167D01*
X511700Y-2583D01*
Y-5000D01*
G01Y-2583D02*
X511900Y-2167D01*
X512233Y-1833D01*
X512700Y-1667D01*
X513167Y-1833D01*
X513500Y-2167D01*
X513700Y-2667D01*
Y-5000D01*
G01X516800Y-1667D02*
Y-5000D01*
G01Y-333D02*
X516667Y-250D01*
Y-83D01*
X516800Y0D01*
X516933Y-83D01*
Y-250D01*
X516800Y-333D01*
G01X521900Y-5000D02*
Y0D01*
G01X271000Y-19417D02*
X271333Y-19750D01*
X271800Y-20000D01*
X272200D01*
X272600Y-19833D01*
X272867Y-19583D01*
X273000Y-19250D01*
X272933Y-18750D01*
X272667Y-18500D01*
X271467Y-18000D01*
X271200Y-17417D01*
X271333Y-17000D01*
X271600Y-16750D01*
X272000Y-16667D01*
X272400Y-16750D01*
X272800Y-17000D01*
G01X277100Y-20000D02*
X276700Y-19917D01*
X276300Y-19583D01*
X276033Y-19000D01*
X275900Y-18333D01*
X276033Y-17667D01*
X276300Y-17083D01*
X276700Y-16750D01*
X277100Y-16667D01*
X277500Y-16750D01*
X277900Y-17083D01*
X278167Y-17667D01*
X278233Y-18333D01*
X278167Y-19000D01*
X277900Y-19583D01*
X277500Y-19917D01*
X277100Y-20000D01*
G01X282200D02*
Y-15000D01*
G01X288500D02*
Y-20000D01*
G01Y-19250D02*
X288233Y-19667D01*
X287833Y-19917D01*
X287367Y-20000D01*
X286833Y-19833D01*
X286433Y-19417D01*
X286167Y-18917D01*
X286100Y-18333D01*
X286167Y-17750D01*
X286433Y-17250D01*
X286833Y-16833D01*
X287367Y-16667D01*
X287833Y-16750D01*
X288167Y-16917D01*
X288500Y-17250D01*
G01X291400Y-17750D02*
X293533D01*
X293333Y-17167D01*
X293000Y-16833D01*
X292533Y-16667D01*
X292067Y-16750D01*
X291667Y-17000D01*
X291400Y-17583D01*
X291267Y-18083D01*
Y-18583D01*
X291400Y-19083D01*
X291733Y-19583D01*
X292133Y-19917D01*
X292600Y-20000D01*
X293067Y-19833D01*
X293533Y-19333D01*
G01X296567Y-20000D02*
Y-16667D01*
G01Y-17333D02*
X296900Y-17000D01*
X297233Y-16750D01*
X297700Y-16667D01*
X298033Y-16750D01*
X298433Y-17000D01*
G01X305700Y-20000D02*
Y-16667D01*
G01Y-17583D02*
X305900Y-17167D01*
X306233Y-16833D01*
X306700Y-16667D01*
X307167Y-16833D01*
X307500Y-17167D01*
X307700Y-17583D01*
Y-20000D01*
G01Y-17583D02*
X307900Y-17167D01*
X308233Y-16833D01*
X308700Y-16667D01*
X309167Y-16833D01*
X309500Y-17167D01*
X309700Y-17667D01*
Y-20000D01*
G01X314000D02*
Y-16667D01*
G01Y-17250D02*
X313733Y-16917D01*
X313333Y-16750D01*
X312867Y-16667D01*
X312400Y-16833D01*
X312000Y-17167D01*
X311733Y-17667D01*
X311600Y-18333D01*
X311733Y-19000D01*
X312000Y-19500D01*
X312400Y-19833D01*
X312867Y-20000D01*
X313333Y-19917D01*
X313733Y-19667D01*
X314000Y-19333D01*
G01X316900Y-19417D02*
X317233Y-19750D01*
X317700Y-20000D01*
X318100D01*
X318500Y-19833D01*
X318767Y-19583D01*
X318900Y-19250D01*
X318833Y-18750D01*
X318567Y-18500D01*
X317367Y-18000D01*
X317100Y-17417D01*
X317233Y-17000D01*
X317500Y-16750D01*
X317900Y-16667D01*
X318300Y-16750D01*
X318700Y-17000D01*
G01X321867Y-20000D02*
Y-15000D01*
G01X324000Y-16667D02*
X321867Y-18583D01*
G01X322733Y-17833D02*
X324133Y-20000D01*
G01X333200Y-15000D02*
Y-20000D01*
G01X332267Y-16667D02*
X334133D01*
G01X337167Y-20000D02*
Y-15000D01*
G01Y-17417D02*
X337500Y-17000D01*
X337833Y-16750D01*
X338367Y-16667D01*
X338767Y-16750D01*
X339233Y-17083D01*
X339433Y-17583D01*
Y-20000D01*
G01X343400Y-16667D02*
Y-20000D01*
G01Y-15333D02*
X343267Y-15250D01*
Y-15083D01*
X343400Y-15000D01*
X343533Y-15083D01*
Y-15250D01*
X343400Y-15333D01*
G01X349567Y-17083D02*
X349100Y-16750D01*
X348700Y-16667D01*
X348167Y-16833D01*
X347767Y-17167D01*
X347500Y-17750D01*
X347433Y-18333D01*
X347500Y-18917D01*
X347767Y-19417D01*
X348167Y-19833D01*
X348700Y-20000D01*
X349167Y-19833D01*
X349567Y-19500D01*
G01X352467Y-20000D02*
Y-15000D01*
G01X354600Y-16667D02*
X352467Y-18583D01*
G01X353333Y-17833D02*
X354733Y-20000D01*
G01X357567D02*
Y-16667D01*
G01Y-17500D02*
X357833Y-17083D01*
X358233Y-16750D01*
X358767Y-16667D01*
X359233Y-16750D01*
X359633Y-17083D01*
X359833Y-17667D01*
Y-20000D01*
G01X362800Y-17750D02*
X364933D01*
X364733Y-17167D01*
X364400Y-16833D01*
X363933Y-16667D01*
X363467Y-16750D01*
X363067Y-17000D01*
X362800Y-17583D01*
X362667Y-18083D01*
Y-18583D01*
X362800Y-19083D01*
X363133Y-19583D01*
X363533Y-19917D01*
X364000Y-20000D01*
X364467Y-19833D01*
X364933Y-19333D01*
G01X367900Y-19417D02*
X368233Y-19750D01*
X368700Y-20000D01*
X369100D01*
X369500Y-19833D01*
X369767Y-19583D01*
X369900Y-19250D01*
X369833Y-18750D01*
X369567Y-18500D01*
X368367Y-18000D01*
X368100Y-17417D01*
X368233Y-17000D01*
X368500Y-16750D01*
X368900Y-16667D01*
X369300Y-16750D01*
X369700Y-17000D01*
G01X373000Y-19417D02*
X373333Y-19750D01*
X373800Y-20000D01*
X374200D01*
X374600Y-19833D01*
X374867Y-19583D01*
X375000Y-19250D01*
X374933Y-18750D01*
X374667Y-18500D01*
X373467Y-18000D01*
X373200Y-17417D01*
X373333Y-17000D01*
X373600Y-16750D01*
X374000Y-16667D01*
X374400Y-16750D01*
X374800Y-17000D01*
G01X273080Y32670D02*
Y27670D01*
G01X271547Y32670D02*
X274613D01*
G01X277047Y27670D02*
Y32670D01*
G01Y30253D02*
X277380Y30670D01*
X277713Y30920D01*
X278247Y31003D01*
X278647Y30920D01*
X279113Y30587D01*
X279313Y30087D01*
Y27670D01*
G01X282280Y29920D02*
X284413D01*
X284213Y30503D01*
X283880Y30837D01*
X283413Y31003D01*
X282947Y30920D01*
X282547Y30670D01*
X282280Y30087D01*
X282147Y29587D01*
Y29087D01*
X282280Y28587D01*
X282613Y28087D01*
X283013Y27753D01*
X283480Y27670D01*
X283947Y27837D01*
X284413Y28337D01*
G01X293480Y27670D02*
Y32670D01*
G01X299780Y27670D02*
Y31003D01*
G01Y30420D02*
X299513Y30753D01*
X299113Y30920D01*
X298647Y31003D01*
X298180Y30837D01*
X297780Y30503D01*
X297513Y30003D01*
X297380Y29337D01*
X297513Y28670D01*
X297780Y28170D01*
X298180Y27837D01*
X298647Y27670D01*
X299113Y27753D01*
X299513Y28003D01*
X299780Y28337D01*
G01X302747Y27670D02*
Y31003D01*
G01Y30337D02*
X303080Y30670D01*
X303413Y30920D01*
X303880Y31003D01*
X304213Y30920D01*
X304613Y30670D01*
G01X307847Y26420D02*
X308313Y26087D01*
X308847Y26003D01*
X309313Y26087D01*
X309713Y26503D01*
X309980Y27087D01*
Y31003D01*
G01Y30337D02*
X309713Y30670D01*
X309313Y30920D01*
X308847Y31003D01*
X308313Y30837D01*
X307980Y30503D01*
X307713Y29920D01*
X307580Y29337D01*
X307647Y28837D01*
X307913Y28253D01*
X308313Y27837D01*
X308847Y27670D01*
X309247Y27753D01*
X309713Y28087D01*
X309980Y28420D01*
G01X312880Y29920D02*
X315013D01*
X314813Y30503D01*
X314480Y30837D01*
X314013Y31003D01*
X313547Y30920D01*
X313147Y30670D01*
X312880Y30087D01*
X312747Y29587D01*
Y29087D01*
X312880Y28587D01*
X313213Y28087D01*
X313613Y27753D01*
X314080Y27670D01*
X314547Y27837D01*
X315013Y28337D01*
G01X317980Y28253D02*
X318313Y27920D01*
X318780Y27670D01*
X319180D01*
X319580Y27837D01*
X319847Y28087D01*
X319980Y28420D01*
X319913Y28920D01*
X319647Y29170D01*
X318447Y29670D01*
X318180Y30253D01*
X318313Y30670D01*
X318580Y30920D01*
X318980Y31003D01*
X319380Y30920D01*
X319780Y30670D01*
G01X324080Y32670D02*
Y27670D01*
G01X323147Y31003D02*
X325013D01*
G01X335480Y32670D02*
Y27670D01*
G01Y28420D02*
X335213Y28003D01*
X334813Y27753D01*
X334347Y27670D01*
X333813Y27837D01*
X333413Y28253D01*
X333147Y28753D01*
X333080Y29337D01*
X333147Y29920D01*
X333413Y30420D01*
X333813Y30837D01*
X334347Y31003D01*
X334813Y30920D01*
X335147Y30753D01*
X335480Y30420D01*
G01X339380Y31003D02*
Y27670D01*
G01Y32337D02*
X339247Y32420D01*
Y32587D01*
X339380Y32670D01*
X339513Y32587D01*
Y32420D01*
X339380Y32337D01*
G01X342480Y27670D02*
Y31003D01*
G01Y30087D02*
X342680Y30503D01*
X343013Y30837D01*
X343480Y31003D01*
X343947Y30837D01*
X344280Y30503D01*
X344480Y30087D01*
Y27670D01*
G01Y30087D02*
X344680Y30503D01*
X345013Y30837D01*
X345480Y31003D01*
X345947Y30837D01*
X346280Y30503D01*
X346480Y30003D01*
Y27670D01*
G01X348580Y29920D02*
X350713D01*
X350513Y30503D01*
X350180Y30837D01*
X349713Y31003D01*
X349247Y30920D01*
X348847Y30670D01*
X348580Y30087D01*
X348447Y29587D01*
Y29087D01*
X348580Y28587D01*
X348913Y28087D01*
X349313Y27753D01*
X349780Y27670D01*
X350247Y27837D01*
X350713Y28337D01*
G01X353547Y27670D02*
Y31003D01*
G01Y30170D02*
X353813Y30587D01*
X354213Y30920D01*
X354747Y31003D01*
X355213Y30920D01*
X355613Y30587D01*
X355813Y30003D01*
Y27670D01*
G01X358780Y28253D02*
X359113Y27920D01*
X359580Y27670D01*
X359980D01*
X360380Y27837D01*
X360647Y28087D01*
X360780Y28420D01*
X360713Y28920D01*
X360447Y29170D01*
X359247Y29670D01*
X358980Y30253D01*
X359113Y30670D01*
X359380Y30920D01*
X359780Y31003D01*
X360180Y30920D01*
X360580Y30670D01*
G01X364880Y31003D02*
Y27670D01*
G01Y32337D02*
X364747Y32420D01*
Y32587D01*
X364880Y32670D01*
X365013Y32587D01*
Y32420D01*
X364880Y32337D01*
G01X369980Y27670D02*
X369580Y27753D01*
X369180Y28087D01*
X368913Y28670D01*
X368780Y29337D01*
X368913Y30003D01*
X369180Y30587D01*
X369580Y30920D01*
X369980Y31003D01*
X370380Y30920D01*
X370780Y30587D01*
X371047Y30003D01*
X371113Y29337D01*
X371047Y28670D01*
X370780Y28087D01*
X370380Y27753D01*
X369980Y27670D01*
G01X373947D02*
Y31003D01*
G01Y30170D02*
X374213Y30587D01*
X374613Y30920D01*
X375147Y31003D01*
X375613Y30920D01*
X376013Y30587D01*
X376213Y30003D01*
Y27670D01*
G01X385280D02*
X384880Y27753D01*
X384480Y28087D01*
X384213Y28670D01*
X384080Y29337D01*
X384213Y30003D01*
X384480Y30587D01*
X384880Y30920D01*
X385280Y31003D01*
X385680Y30920D01*
X386080Y30587D01*
X386347Y30003D01*
X386413Y29337D01*
X386347Y28670D01*
X386080Y28087D01*
X385680Y27753D01*
X385280Y27670D01*
G01X389980D02*
Y31920D01*
X390113Y32337D01*
X390380Y32587D01*
X390780Y32670D01*
X391180Y32503D01*
X391380Y32087D01*
G01X390580Y30670D02*
X389247D01*
G01X399380Y26003D02*
Y31003D01*
G01Y30253D02*
X399713Y30670D01*
X400047Y30920D01*
X400580Y31003D01*
X401047Y30920D01*
X401513Y30503D01*
X401713Y29920D01*
X401780Y29337D01*
X401713Y28753D01*
X401513Y28170D01*
X401113Y27837D01*
X400580Y27670D01*
X400113Y27753D01*
X399647Y28003D01*
X399380Y28337D01*
G01X406880Y27670D02*
Y31003D01*
G01Y30420D02*
X406613Y30753D01*
X406213Y30920D01*
X405747Y31003D01*
X405280Y30837D01*
X404880Y30503D01*
X404613Y30003D01*
X404480Y29337D01*
X404613Y28670D01*
X404880Y28170D01*
X405280Y27837D01*
X405747Y27670D01*
X406213Y27753D01*
X406613Y28003D01*
X406880Y28337D01*
G01X411980Y32670D02*
Y27670D01*
G01Y28420D02*
X411713Y28003D01*
X411313Y27753D01*
X410847Y27670D01*
X410313Y27837D01*
X409913Y28253D01*
X409647Y28753D01*
X409580Y29337D01*
X409647Y29920D01*
X409913Y30420D01*
X410313Y30837D01*
X410847Y31003D01*
X411313Y30920D01*
X411647Y30753D01*
X411980Y30420D01*
G01X420980Y27670D02*
X420580Y27753D01*
X420180Y28087D01*
X419913Y28670D01*
X419780Y29337D01*
X419913Y30003D01*
X420180Y30587D01*
X420580Y30920D01*
X420980Y31003D01*
X421380Y30920D01*
X421780Y30587D01*
X422047Y30003D01*
X422113Y29337D01*
X422047Y28670D01*
X421780Y28087D01*
X421380Y27753D01*
X420980Y27670D01*
G01X425147D02*
Y31003D01*
G01Y30337D02*
X425480Y30670D01*
X425813Y30920D01*
X426280Y31003D01*
X426613Y30920D01*
X427013Y30670D01*
G01X437480Y32670D02*
Y27670D01*
G01Y28420D02*
X437213Y28003D01*
X436813Y27753D01*
X436347Y27670D01*
X435813Y27837D01*
X435413Y28253D01*
X435147Y28753D01*
X435080Y29337D01*
X435147Y29920D01*
X435413Y30420D01*
X435813Y30837D01*
X436347Y31003D01*
X436813Y30920D01*
X437147Y30753D01*
X437480Y30420D01*
G01X441380Y31003D02*
Y27670D01*
G01Y32337D02*
X441247Y32420D01*
Y32587D01*
X441380Y32670D01*
X441513Y32587D01*
Y32420D01*
X441380Y32337D01*
G01X447680Y27670D02*
Y31003D01*
G01Y30420D02*
X447413Y30753D01*
X447013Y30920D01*
X446547Y31003D01*
X446080Y30837D01*
X445680Y30503D01*
X445413Y30003D01*
X445280Y29337D01*
X445413Y28670D01*
X445680Y28170D01*
X446080Y27837D01*
X446547Y27670D01*
X447013Y27753D01*
X447413Y28003D01*
X447680Y28337D01*
G01X449580Y27670D02*
Y31003D01*
G01Y30087D02*
X449780Y30503D01*
X450113Y30837D01*
X450580Y31003D01*
X451047Y30837D01*
X451380Y30503D01*
X451580Y30087D01*
Y27670D01*
G01Y30087D02*
X451780Y30503D01*
X452113Y30837D01*
X452580Y31003D01*
X453047Y30837D01*
X453380Y30503D01*
X453580Y30003D01*
Y27670D01*
G01X455680Y29920D02*
X457813D01*
X457613Y30503D01*
X457280Y30837D01*
X456813Y31003D01*
X456347Y30920D01*
X455947Y30670D01*
X455680Y30087D01*
X455547Y29587D01*
Y29087D01*
X455680Y28587D01*
X456013Y28087D01*
X456413Y27753D01*
X456880Y27670D01*
X457347Y27837D01*
X457813Y28337D01*
G01X461780Y32670D02*
Y27670D01*
G01X460847Y31003D02*
X462713D01*
G01X465880Y29920D02*
X468013D01*
X467813Y30503D01*
X467480Y30837D01*
X467013Y31003D01*
X466547Y30920D01*
X466147Y30670D01*
X465880Y30087D01*
X465747Y29587D01*
Y29087D01*
X465880Y28587D01*
X466213Y28087D01*
X466613Y27753D01*
X467080Y27670D01*
X467547Y27837D01*
X468013Y28337D01*
G01X471047Y27670D02*
Y31003D01*
G01Y30337D02*
X471380Y30670D01*
X471713Y30920D01*
X472180Y31003D01*
X472513Y30920D01*
X472913Y30670D01*
G01X483513Y27670D02*
X480847Y29337D01*
X483513Y31003D01*
G01X486413Y28587D02*
X488147D01*
G01Y30087D02*
X486413D01*
G01X497480Y27670D02*
Y32670D01*
X496680Y31670D01*
G01Y27670D02*
X498280D01*
G01X503380D02*
Y32670D01*
X500913Y29087D01*
X504247D01*
G01X510780Y27670D02*
Y31003D01*
G01Y30087D02*
X510980Y30503D01*
X511313Y30837D01*
X511780Y31003D01*
X512247Y30837D01*
X512580Y30503D01*
X512780Y30087D01*
Y27670D01*
G01Y30087D02*
X512980Y30503D01*
X513313Y30837D01*
X513780Y31003D01*
X514247Y30837D01*
X514580Y30503D01*
X514780Y30003D01*
Y27670D01*
G01X517880Y31003D02*
Y27670D01*
G01Y32337D02*
X517747Y32420D01*
Y32587D01*
X517880Y32670D01*
X518013Y32587D01*
Y32420D01*
X517880Y32337D01*
G01X522980Y27670D02*
Y32670D01*
G01X272000Y15000D02*
Y10000D01*
G01X270467Y15000D02*
X273533D01*
G01X275967Y10000D02*
Y15000D01*
G01Y12583D02*
X276300Y13000D01*
X276633Y13250D01*
X277167Y13333D01*
X277567Y13250D01*
X278033Y12917D01*
X278233Y12417D01*
Y10000D01*
G01X281200Y12250D02*
X283333D01*
X283133Y12833D01*
X282800Y13167D01*
X282333Y13333D01*
X281867Y13250D01*
X281467Y13000D01*
X281200Y12417D01*
X281067Y11917D01*
Y11417D01*
X281200Y10917D01*
X281533Y10417D01*
X281933Y10083D01*
X282400Y10000D01*
X282867Y10167D01*
X283333Y10667D01*
G01X292400Y10000D02*
Y15000D01*
G01X298700Y10000D02*
Y13333D01*
G01Y12750D02*
X298433Y13083D01*
X298033Y13250D01*
X297567Y13333D01*
X297100Y13167D01*
X296700Y12833D01*
X296433Y12333D01*
X296300Y11667D01*
X296433Y11000D01*
X296700Y10500D01*
X297100Y10167D01*
X297567Y10000D01*
X298033Y10083D01*
X298433Y10333D01*
X298700Y10667D01*
G01X301667Y10000D02*
Y13333D01*
G01Y12667D02*
X302000Y13000D01*
X302333Y13250D01*
X302800Y13333D01*
X303133Y13250D01*
X303533Y13000D01*
G01X306767Y8750D02*
X307233Y8417D01*
X307767Y8333D01*
X308233Y8417D01*
X308633Y8833D01*
X308900Y9417D01*
Y13333D01*
G01Y12667D02*
X308633Y13000D01*
X308233Y13250D01*
X307767Y13333D01*
X307233Y13167D01*
X306900Y12833D01*
X306633Y12250D01*
X306500Y11667D01*
X306567Y11167D01*
X306833Y10583D01*
X307233Y10167D01*
X307767Y10000D01*
X308167Y10083D01*
X308633Y10417D01*
X308900Y10750D01*
G01X311800Y12250D02*
X313933D01*
X313733Y12833D01*
X313400Y13167D01*
X312933Y13333D01*
X312467Y13250D01*
X312067Y13000D01*
X311800Y12417D01*
X311667Y11917D01*
Y11417D01*
X311800Y10917D01*
X312133Y10417D01*
X312533Y10083D01*
X313000Y10000D01*
X313467Y10167D01*
X313933Y10667D01*
G01X316900Y10583D02*
X317233Y10250D01*
X317700Y10000D01*
X318100D01*
X318500Y10167D01*
X318767Y10417D01*
X318900Y10750D01*
X318833Y11250D01*
X318567Y11500D01*
X317367Y12000D01*
X317100Y12583D01*
X317233Y13000D01*
X317500Y13250D01*
X317900Y13333D01*
X318300Y13250D01*
X318700Y13000D01*
G01X323000Y15000D02*
Y10000D01*
G01X322067Y13333D02*
X323933D01*
G01X334400Y15000D02*
Y10000D01*
G01Y10750D02*
X334133Y10333D01*
X333733Y10083D01*
X333267Y10000D01*
X332733Y10167D01*
X332333Y10583D01*
X332067Y11083D01*
X332000Y11667D01*
X332067Y12250D01*
X332333Y12750D01*
X332733Y13167D01*
X333267Y13333D01*
X333733Y13250D01*
X334067Y13083D01*
X334400Y12750D01*
G01X338300Y13333D02*
Y10000D01*
G01Y14667D02*
X338167Y14750D01*
Y14917D01*
X338300Y15000D01*
X338433Y14917D01*
Y14750D01*
X338300Y14667D01*
G01X341400Y10000D02*
Y13333D01*
G01Y12417D02*
X341600Y12833D01*
X341933Y13167D01*
X342400Y13333D01*
X342867Y13167D01*
X343200Y12833D01*
X343400Y12417D01*
Y10000D01*
G01Y12417D02*
X343600Y12833D01*
X343933Y13167D01*
X344400Y13333D01*
X344867Y13167D01*
X345200Y12833D01*
X345400Y12333D01*
Y10000D01*
G01X347500Y12250D02*
X349633D01*
X349433Y12833D01*
X349100Y13167D01*
X348633Y13333D01*
X348167Y13250D01*
X347767Y13000D01*
X347500Y12417D01*
X347367Y11917D01*
Y11417D01*
X347500Y10917D01*
X347833Y10417D01*
X348233Y10083D01*
X348700Y10000D01*
X349167Y10167D01*
X349633Y10667D01*
G01X352467Y10000D02*
Y13333D01*
G01Y12500D02*
X352733Y12917D01*
X353133Y13250D01*
X353667Y13333D01*
X354133Y13250D01*
X354533Y12917D01*
X354733Y12333D01*
Y10000D01*
G01X357700Y10583D02*
X358033Y10250D01*
X358500Y10000D01*
X358900D01*
X359300Y10167D01*
X359567Y10417D01*
X359700Y10750D01*
X359633Y11250D01*
X359367Y11500D01*
X358167Y12000D01*
X357900Y12583D01*
X358033Y13000D01*
X358300Y13250D01*
X358700Y13333D01*
X359100Y13250D01*
X359500Y13000D01*
G01X363800Y13333D02*
Y10000D01*
G01Y14667D02*
X363667Y14750D01*
Y14917D01*
X363800Y15000D01*
X363933Y14917D01*
Y14750D01*
X363800Y14667D01*
G01X368900Y10000D02*
X368500Y10083D01*
X368100Y10417D01*
X367833Y11000D01*
X367700Y11667D01*
X367833Y12333D01*
X368100Y12917D01*
X368500Y13250D01*
X368900Y13333D01*
X369300Y13250D01*
X369700Y12917D01*
X369967Y12333D01*
X370033Y11667D01*
X369967Y11000D01*
X369700Y10417D01*
X369300Y10083D01*
X368900Y10000D01*
G01X372867D02*
Y13333D01*
G01Y12500D02*
X373133Y12917D01*
X373533Y13250D01*
X374067Y13333D01*
X374533Y13250D01*
X374933Y12917D01*
X375133Y12333D01*
Y10000D01*
G01X384200D02*
X383800Y10083D01*
X383400Y10417D01*
X383133Y11000D01*
X383000Y11667D01*
X383133Y12333D01*
X383400Y12917D01*
X383800Y13250D01*
X384200Y13333D01*
X384600Y13250D01*
X385000Y12917D01*
X385267Y12333D01*
X385333Y11667D01*
X385267Y11000D01*
X385000Y10417D01*
X384600Y10083D01*
X384200Y10000D01*
G01X388900D02*
Y14250D01*
X389033Y14667D01*
X389300Y14917D01*
X389700Y15000D01*
X390100Y14833D01*
X390300Y14417D01*
G01X389500Y13000D02*
X388167D01*
G01X398300Y8333D02*
Y13333D01*
G01Y12583D02*
X398633Y13000D01*
X398967Y13250D01*
X399500Y13333D01*
X399967Y13250D01*
X400433Y12833D01*
X400633Y12250D01*
X400700Y11667D01*
X400633Y11083D01*
X400433Y10500D01*
X400033Y10167D01*
X399500Y10000D01*
X399033Y10083D01*
X398567Y10333D01*
X398300Y10667D01*
G01X405800Y10000D02*
Y13333D01*
G01Y12750D02*
X405533Y13083D01*
X405133Y13250D01*
X404667Y13333D01*
X404200Y13167D01*
X403800Y12833D01*
X403533Y12333D01*
X403400Y11667D01*
X403533Y11000D01*
X403800Y10500D01*
X404200Y10167D01*
X404667Y10000D01*
X405133Y10083D01*
X405533Y10333D01*
X405800Y10667D01*
G01X410900Y15000D02*
Y10000D01*
G01Y10750D02*
X410633Y10333D01*
X410233Y10083D01*
X409767Y10000D01*
X409233Y10167D01*
X408833Y10583D01*
X408567Y11083D01*
X408500Y11667D01*
X408567Y12250D01*
X408833Y12750D01*
X409233Y13167D01*
X409767Y13333D01*
X410233Y13250D01*
X410567Y13083D01*
X410900Y12750D01*
G01X419900Y10000D02*
X419500Y10083D01*
X419100Y10417D01*
X418833Y11000D01*
X418700Y11667D01*
X418833Y12333D01*
X419100Y12917D01*
X419500Y13250D01*
X419900Y13333D01*
X420300Y13250D01*
X420700Y12917D01*
X420967Y12333D01*
X421033Y11667D01*
X420967Y11000D01*
X420700Y10417D01*
X420300Y10083D01*
X419900Y10000D01*
G01X424067D02*
Y13333D01*
G01Y12667D02*
X424400Y13000D01*
X424733Y13250D01*
X425200Y13333D01*
X425533Y13250D01*
X425933Y13000D01*
G01X436400Y15000D02*
Y10000D01*
G01Y10750D02*
X436133Y10333D01*
X435733Y10083D01*
X435267Y10000D01*
X434733Y10167D01*
X434333Y10583D01*
X434067Y11083D01*
X434000Y11667D01*
X434067Y12250D01*
X434333Y12750D01*
X434733Y13167D01*
X435267Y13333D01*
X435733Y13250D01*
X436067Y13083D01*
X436400Y12750D01*
G01X440300Y13333D02*
Y10000D01*
G01Y14667D02*
X440167Y14750D01*
Y14917D01*
X440300Y15000D01*
X440433Y14917D01*
Y14750D01*
X440300Y14667D01*
G01X446600Y10000D02*
Y13333D01*
G01Y12750D02*
X446333Y13083D01*
X445933Y13250D01*
X445467Y13333D01*
X445000Y13167D01*
X444600Y12833D01*
X444333Y12333D01*
X444200Y11667D01*
X444333Y11000D01*
X444600Y10500D01*
X445000Y10167D01*
X445467Y10000D01*
X445933Y10083D01*
X446333Y10333D01*
X446600Y10667D01*
G01X448500Y10000D02*
Y13333D01*
G01Y12417D02*
X448700Y12833D01*
X449033Y13167D01*
X449500Y13333D01*
X449967Y13167D01*
X450300Y12833D01*
X450500Y12417D01*
Y10000D01*
G01Y12417D02*
X450700Y12833D01*
X451033Y13167D01*
X451500Y13333D01*
X451967Y13167D01*
X452300Y12833D01*
X452500Y12333D01*
Y10000D01*
G01X454600Y12250D02*
X456733D01*
X456533Y12833D01*
X456200Y13167D01*
X455733Y13333D01*
X455267Y13250D01*
X454867Y13000D01*
X454600Y12417D01*
X454467Y11917D01*
Y11417D01*
X454600Y10917D01*
X454933Y10417D01*
X455333Y10083D01*
X455800Y10000D01*
X456267Y10167D01*
X456733Y10667D01*
G01X460700Y15000D02*
Y10000D01*
G01X459767Y13333D02*
X461633D01*
G01X464800Y12250D02*
X466933D01*
X466733Y12833D01*
X466400Y13167D01*
X465933Y13333D01*
X465467Y13250D01*
X465067Y13000D01*
X464800Y12417D01*
X464667Y11917D01*
Y11417D01*
X464800Y10917D01*
X465133Y10417D01*
X465533Y10083D01*
X466000Y10000D01*
X466467Y10167D01*
X466933Y10667D01*
G01X469967Y10000D02*
Y13333D01*
G01Y12667D02*
X470300Y13000D01*
X470633Y13250D01*
X471100Y13333D01*
X471433Y13250D01*
X471833Y13000D01*
G01X479767Y10000D02*
X482433Y11667D01*
X479767Y13333D01*
G01X486200Y10000D02*
Y15000D01*
X485400Y14000D01*
G01Y10000D02*
X487000D01*
G01X492100D02*
Y15000D01*
X489633Y11417D01*
X492967D01*
G01X499500Y10000D02*
Y13333D01*
G01Y12417D02*
X499700Y12833D01*
X500033Y13167D01*
X500500Y13333D01*
X500967Y13167D01*
X501300Y12833D01*
X501500Y12417D01*
Y10000D01*
G01Y12417D02*
X501700Y12833D01*
X502033Y13167D01*
X502500Y13333D01*
X502967Y13167D01*
X503300Y12833D01*
X503500Y12333D01*
Y10000D01*
G01X506600Y13333D02*
Y10000D01*
G01Y14667D02*
X506467Y14750D01*
Y14917D01*
X506600Y15000D01*
X506733Y14917D01*
Y14750D01*
X506600Y14667D01*
G01X511700Y10000D02*
Y15000D01*
G01X264000Y5500D02*
X694500D01*
G01X270533Y82250D02*
X270933Y81833D01*
X271400Y81583D01*
X272000Y81500D01*
X272600Y81667D01*
X273067Y82000D01*
X273400Y82583D01*
X273467Y83250D01*
X273333Y83917D01*
X273000Y84333D01*
X272533Y84667D01*
X272067Y84750D01*
X271600Y84667D01*
X271000Y84333D01*
X271200Y86500D01*
X273000D01*
G01X280200Y81500D02*
Y84833D01*
G01Y83917D02*
X280400Y84333D01*
X280733Y84667D01*
X281200Y84833D01*
X281667Y84667D01*
X282000Y84333D01*
X282200Y83917D01*
Y81500D01*
G01Y83917D02*
X282400Y84333D01*
X282733Y84667D01*
X283200Y84833D01*
X283667Y84667D01*
X284000Y84333D01*
X284200Y83833D01*
Y81500D01*
G01X287300Y84833D02*
Y81500D01*
G01Y86167D02*
X287167Y86250D01*
Y86417D01*
X287300Y86500D01*
X287433Y86417D01*
Y86250D01*
X287300Y86167D01*
G01X292400Y81500D02*
Y86500D01*
G01X303933Y81500D02*
X301267Y83167D01*
X303933Y84833D01*
G01X312800Y86500D02*
Y81500D01*
G01X311867Y84833D02*
X313733D01*
G01X316967Y81500D02*
Y84833D01*
G01Y84167D02*
X317300Y84500D01*
X317633Y84750D01*
X318100Y84833D01*
X318433Y84750D01*
X318833Y84500D01*
G01X324200Y81500D02*
Y84833D01*
G01Y84250D02*
X323933Y84583D01*
X323533Y84750D01*
X323067Y84833D01*
X322600Y84667D01*
X322200Y84333D01*
X321933Y83833D01*
X321800Y83167D01*
X321933Y82500D01*
X322200Y82000D01*
X322600Y81667D01*
X323067Y81500D01*
X323533Y81583D01*
X323933Y81833D01*
X324200Y82167D01*
G01X329167Y84417D02*
X328700Y84750D01*
X328300Y84833D01*
X327767Y84667D01*
X327367Y84333D01*
X327100Y83750D01*
X327033Y83167D01*
X327100Y82583D01*
X327367Y82083D01*
X327767Y81667D01*
X328300Y81500D01*
X328767Y81667D01*
X329167Y82000D01*
G01X332200Y83750D02*
X334333D01*
X334133Y84333D01*
X333800Y84667D01*
X333333Y84833D01*
X332867Y84750D01*
X332467Y84500D01*
X332200Y83917D01*
X332067Y83417D01*
Y82917D01*
X332200Y82417D01*
X332533Y81917D01*
X332933Y81583D01*
X333400Y81500D01*
X333867Y81667D01*
X334333Y82167D01*
G01X341733Y84833D02*
X342533Y81500D01*
X343400Y84833D01*
X344267Y81500D01*
X345067Y84833D01*
G01X348500D02*
Y81500D01*
G01Y86167D02*
X348367Y86250D01*
Y86417D01*
X348500Y86500D01*
X348633Y86417D01*
Y86250D01*
X348500Y86167D01*
G01X354800Y86500D02*
Y81500D01*
G01Y82250D02*
X354533Y81833D01*
X354133Y81583D01*
X353667Y81500D01*
X353133Y81667D01*
X352733Y82083D01*
X352467Y82583D01*
X352400Y83167D01*
X352467Y83750D01*
X352733Y84250D01*
X353133Y84667D01*
X353667Y84833D01*
X354133Y84750D01*
X354467Y84583D01*
X354800Y84250D01*
G01X358700Y86500D02*
Y81500D01*
G01X357767Y84833D02*
X359633D01*
G01X362667Y81500D02*
Y86500D01*
G01Y84083D02*
X363000Y84500D01*
X363333Y84750D01*
X363867Y84833D01*
X364267Y84750D01*
X364733Y84417D01*
X364933Y83917D01*
Y81500D01*
G01X375333D02*
X372667Y83167D01*
X375333Y84833D01*
G01X378233Y82417D02*
X379967D01*
G01Y83917D02*
X378233D01*
G01X389167Y81500D02*
X389300Y82583D01*
X389500Y83500D01*
X389767Y84333D01*
X390100Y85250D01*
X390633Y86500D01*
X387967D01*
G01X397500Y81500D02*
Y84833D01*
G01Y83917D02*
X397700Y84333D01*
X398033Y84667D01*
X398500Y84833D01*
X398967Y84667D01*
X399300Y84333D01*
X399500Y83917D01*
Y81500D01*
G01Y83917D02*
X399700Y84333D01*
X400033Y84667D01*
X400500Y84833D01*
X400967Y84667D01*
X401300Y84333D01*
X401500Y83833D01*
Y81500D01*
G01X404600Y84833D02*
Y81500D01*
G01Y86167D02*
X404467Y86250D01*
Y86417D01*
X404600Y86500D01*
X404733Y86417D01*
Y86250D01*
X404600Y86167D01*
G01X409700Y81500D02*
Y86500D01*
G01X272000Y71500D02*
Y66500D01*
G01X271067Y69833D02*
X272933D01*
G01X276167Y66500D02*
Y69833D01*
G01Y69167D02*
X276500Y69500D01*
X276833Y69750D01*
X277300Y69833D01*
X277633Y69750D01*
X278033Y69500D01*
G01X283400Y66500D02*
Y69833D01*
G01Y69250D02*
X283133Y69583D01*
X282733Y69750D01*
X282267Y69833D01*
X281800Y69667D01*
X281400Y69333D01*
X281133Y68833D01*
X281000Y68167D01*
X281133Y67500D01*
X281400Y67000D01*
X281800Y66667D01*
X282267Y66500D01*
X282733Y66583D01*
X283133Y66833D01*
X283400Y67167D01*
G01X288367Y69417D02*
X287900Y69750D01*
X287500Y69833D01*
X286967Y69667D01*
X286567Y69333D01*
X286300Y68750D01*
X286233Y68167D01*
X286300Y67583D01*
X286567Y67083D01*
X286967Y66667D01*
X287500Y66500D01*
X287967Y66667D01*
X288367Y67000D01*
G01X291400Y68750D02*
X293533D01*
X293333Y69333D01*
X293000Y69667D01*
X292533Y69833D01*
X292067Y69750D01*
X291667Y69500D01*
X291400Y68917D01*
X291267Y68417D01*
Y67917D01*
X291400Y67417D01*
X291733Y66917D01*
X292133Y66583D01*
X292600Y66500D01*
X293067Y66667D01*
X293533Y67167D01*
G01X300933Y69833D02*
X301733Y66500D01*
X302600Y69833D01*
X303467Y66500D01*
X304267Y69833D01*
G01X307700D02*
Y66500D01*
G01Y71167D02*
X307567Y71250D01*
Y71417D01*
X307700Y71500D01*
X307833Y71417D01*
Y71250D01*
X307700Y71167D01*
G01X314000Y71500D02*
Y66500D01*
G01Y67250D02*
X313733Y66833D01*
X313333Y66583D01*
X312867Y66500D01*
X312333Y66667D01*
X311933Y67083D01*
X311667Y67583D01*
X311600Y68167D01*
X311667Y68750D01*
X311933Y69250D01*
X312333Y69667D01*
X312867Y69833D01*
X313333Y69750D01*
X313667Y69583D01*
X314000Y69250D01*
G01X317900Y71500D02*
Y66500D01*
G01X316967Y69833D02*
X318833D01*
G01X321867Y66500D02*
Y71500D01*
G01Y69083D02*
X322200Y69500D01*
X322533Y69750D01*
X323067Y69833D01*
X323467Y69750D01*
X323933Y69417D01*
X324133Y68917D01*
Y66500D01*
G01X331867D02*
X334533Y68167D01*
X331867Y69833D01*
G01X343267Y66500D02*
X343400Y67583D01*
X343600Y68500D01*
X343867Y69333D01*
X344200Y70250D01*
X344733Y71500D01*
X342067D01*
G01X351600Y66500D02*
Y69833D01*
G01Y68917D02*
X351800Y69333D01*
X352133Y69667D01*
X352600Y69833D01*
X353067Y69667D01*
X353400Y69333D01*
X353600Y68917D01*
Y66500D01*
G01Y68917D02*
X353800Y69333D01*
X354133Y69667D01*
X354600Y69833D01*
X355067Y69667D01*
X355400Y69333D01*
X355600Y68833D01*
Y66500D01*
G01X358700Y69833D02*
Y66500D01*
G01Y71167D02*
X358567Y71250D01*
Y71417D01*
X358700Y71500D01*
X358833Y71417D01*
Y71250D01*
X358700Y71167D01*
G01X363800Y66500D02*
Y71500D01*
G01X272000Y52000D02*
Y47000D01*
G01X270467Y52000D02*
X273533D01*
G01X275967Y47000D02*
Y52000D01*
G01Y49583D02*
X276300Y50000D01*
X276633Y50250D01*
X277167Y50333D01*
X277567Y50250D01*
X278033Y49917D01*
X278233Y49417D01*
Y47000D01*
G01X281200Y49250D02*
X283333D01*
X283133Y49833D01*
X282800Y50167D01*
X282333Y50333D01*
X281867Y50250D01*
X281467Y50000D01*
X281200Y49417D01*
X281067Y48917D01*
Y48417D01*
X281200Y47917D01*
X281533Y47417D01*
X281933Y47083D01*
X282400Y47000D01*
X282867Y47167D01*
X283333Y47667D01*
G01X292400Y47000D02*
Y52000D01*
G01X298700Y47000D02*
Y50333D01*
G01Y49750D02*
X298433Y50083D01*
X298033Y50250D01*
X297567Y50333D01*
X297100Y50167D01*
X296700Y49833D01*
X296433Y49333D01*
X296300Y48667D01*
X296433Y48000D01*
X296700Y47500D01*
X297100Y47167D01*
X297567Y47000D01*
X298033Y47083D01*
X298433Y47333D01*
X298700Y47667D01*
G01X301667Y47000D02*
Y50333D01*
G01Y49667D02*
X302000Y50000D01*
X302333Y50250D01*
X302800Y50333D01*
X303133Y50250D01*
X303533Y50000D01*
G01X306767Y45750D02*
X307233Y45417D01*
X307767Y45333D01*
X308233Y45417D01*
X308633Y45833D01*
X308900Y46417D01*
Y50333D01*
G01Y49667D02*
X308633Y50000D01*
X308233Y50250D01*
X307767Y50333D01*
X307233Y50167D01*
X306900Y49833D01*
X306633Y49250D01*
X306500Y48667D01*
X306567Y48167D01*
X306833Y47583D01*
X307233Y47167D01*
X307767Y47000D01*
X308167Y47083D01*
X308633Y47417D01*
X308900Y47750D01*
G01X311800Y49250D02*
X313933D01*
X313733Y49833D01*
X313400Y50167D01*
X312933Y50333D01*
X312467Y50250D01*
X312067Y50000D01*
X311800Y49417D01*
X311667Y48917D01*
Y48417D01*
X311800Y47917D01*
X312133Y47417D01*
X312533Y47083D01*
X313000Y47000D01*
X313467Y47167D01*
X313933Y47667D01*
G01X316900Y47583D02*
X317233Y47250D01*
X317700Y47000D01*
X318100D01*
X318500Y47167D01*
X318767Y47417D01*
X318900Y47750D01*
X318833Y48250D01*
X318567Y48500D01*
X317367Y49000D01*
X317100Y49583D01*
X317233Y50000D01*
X317500Y50250D01*
X317900Y50333D01*
X318300Y50250D01*
X318700Y50000D01*
G01X323000Y52000D02*
Y47000D01*
G01X322067Y50333D02*
X323933D01*
G01X334400Y52000D02*
Y47000D01*
G01Y47750D02*
X334133Y47333D01*
X333733Y47083D01*
X333267Y47000D01*
X332733Y47167D01*
X332333Y47583D01*
X332067Y48083D01*
X332000Y48667D01*
X332067Y49250D01*
X332333Y49750D01*
X332733Y50167D01*
X333267Y50333D01*
X333733Y50250D01*
X334067Y50083D01*
X334400Y49750D01*
G01X338300Y50333D02*
Y47000D01*
G01Y51667D02*
X338167Y51750D01*
Y51917D01*
X338300Y52000D01*
X338433Y51917D01*
Y51750D01*
X338300Y51667D01*
G01X341400Y47000D02*
Y50333D01*
G01Y49417D02*
X341600Y49833D01*
X341933Y50167D01*
X342400Y50333D01*
X342867Y50167D01*
X343200Y49833D01*
X343400Y49417D01*
Y47000D01*
G01Y49417D02*
X343600Y49833D01*
X343933Y50167D01*
X344400Y50333D01*
X344867Y50167D01*
X345200Y49833D01*
X345400Y49333D01*
Y47000D01*
G01X347500Y49250D02*
X349633D01*
X349433Y49833D01*
X349100Y50167D01*
X348633Y50333D01*
X348167Y50250D01*
X347767Y50000D01*
X347500Y49417D01*
X347367Y48917D01*
Y48417D01*
X347500Y47917D01*
X347833Y47417D01*
X348233Y47083D01*
X348700Y47000D01*
X349167Y47167D01*
X349633Y47667D01*
G01X352467Y47000D02*
Y50333D01*
G01Y49500D02*
X352733Y49917D01*
X353133Y50250D01*
X353667Y50333D01*
X354133Y50250D01*
X354533Y49917D01*
X354733Y49333D01*
Y47000D01*
G01X357700Y47583D02*
X358033Y47250D01*
X358500Y47000D01*
X358900D01*
X359300Y47167D01*
X359567Y47417D01*
X359700Y47750D01*
X359633Y48250D01*
X359367Y48500D01*
X358167Y49000D01*
X357900Y49583D01*
X358033Y50000D01*
X358300Y50250D01*
X358700Y50333D01*
X359100Y50250D01*
X359500Y50000D01*
G01X363800Y50333D02*
Y47000D01*
G01Y51667D02*
X363667Y51750D01*
Y51917D01*
X363800Y52000D01*
X363933Y51917D01*
Y51750D01*
X363800Y51667D01*
G01X368900Y47000D02*
X368500Y47083D01*
X368100Y47417D01*
X367833Y48000D01*
X367700Y48667D01*
X367833Y49333D01*
X368100Y49917D01*
X368500Y50250D01*
X368900Y50333D01*
X369300Y50250D01*
X369700Y49917D01*
X369967Y49333D01*
X370033Y48667D01*
X369967Y48000D01*
X369700Y47417D01*
X369300Y47083D01*
X368900Y47000D01*
G01X372867D02*
Y50333D01*
G01Y49500D02*
X373133Y49917D01*
X373533Y50250D01*
X374067Y50333D01*
X374533Y50250D01*
X374933Y49917D01*
X375133Y49333D01*
Y47000D01*
G01X384200D02*
X383800Y47083D01*
X383400Y47417D01*
X383133Y48000D01*
X383000Y48667D01*
X383133Y49333D01*
X383400Y49917D01*
X383800Y50250D01*
X384200Y50333D01*
X384600Y50250D01*
X385000Y49917D01*
X385267Y49333D01*
X385333Y48667D01*
X385267Y48000D01*
X385000Y47417D01*
X384600Y47083D01*
X384200Y47000D01*
G01X388900D02*
Y51250D01*
X389033Y51667D01*
X389300Y51917D01*
X389700Y52000D01*
X390100Y51833D01*
X390300Y51417D01*
G01X389500Y50000D02*
X388167D01*
G01X398300Y45333D02*
Y50333D01*
G01Y49583D02*
X398633Y50000D01*
X398967Y50250D01*
X399500Y50333D01*
X399967Y50250D01*
X400433Y49833D01*
X400633Y49250D01*
X400700Y48667D01*
X400633Y48083D01*
X400433Y47500D01*
X400033Y47167D01*
X399500Y47000D01*
X399033Y47083D01*
X398567Y47333D01*
X398300Y47667D01*
G01X405800Y47000D02*
Y50333D01*
G01Y49750D02*
X405533Y50083D01*
X405133Y50250D01*
X404667Y50333D01*
X404200Y50167D01*
X403800Y49833D01*
X403533Y49333D01*
X403400Y48667D01*
X403533Y48000D01*
X403800Y47500D01*
X404200Y47167D01*
X404667Y47000D01*
X405133Y47083D01*
X405533Y47333D01*
X405800Y47667D01*
G01X410900Y52000D02*
Y47000D01*
G01Y47750D02*
X410633Y47333D01*
X410233Y47083D01*
X409767Y47000D01*
X409233Y47167D01*
X408833Y47583D01*
X408567Y48083D01*
X408500Y48667D01*
X408567Y49250D01*
X408833Y49750D01*
X409233Y50167D01*
X409767Y50333D01*
X410233Y50250D01*
X410567Y50083D01*
X410900Y49750D01*
G01X419900Y47000D02*
X419500Y47083D01*
X419100Y47417D01*
X418833Y48000D01*
X418700Y48667D01*
X418833Y49333D01*
X419100Y49917D01*
X419500Y50250D01*
X419900Y50333D01*
X420300Y50250D01*
X420700Y49917D01*
X420967Y49333D01*
X421033Y48667D01*
X420967Y48000D01*
X420700Y47417D01*
X420300Y47083D01*
X419900Y47000D01*
G01X424067D02*
Y50333D01*
G01Y49667D02*
X424400Y50000D01*
X424733Y50250D01*
X425200Y50333D01*
X425533Y50250D01*
X425933Y50000D01*
G01X436400Y52000D02*
Y47000D01*
G01Y47750D02*
X436133Y47333D01*
X435733Y47083D01*
X435267Y47000D01*
X434733Y47167D01*
X434333Y47583D01*
X434067Y48083D01*
X434000Y48667D01*
X434067Y49250D01*
X434333Y49750D01*
X434733Y50167D01*
X435267Y50333D01*
X435733Y50250D01*
X436067Y50083D01*
X436400Y49750D01*
G01X440300Y50333D02*
Y47000D01*
G01Y51667D02*
X440167Y51750D01*
Y51917D01*
X440300Y52000D01*
X440433Y51917D01*
Y51750D01*
X440300Y51667D01*
G01X446600Y47000D02*
Y50333D01*
G01Y49750D02*
X446333Y50083D01*
X445933Y50250D01*
X445467Y50333D01*
X445000Y50167D01*
X444600Y49833D01*
X444333Y49333D01*
X444200Y48667D01*
X444333Y48000D01*
X444600Y47500D01*
X445000Y47167D01*
X445467Y47000D01*
X445933Y47083D01*
X446333Y47333D01*
X446600Y47667D01*
G01X448500Y47000D02*
Y50333D01*
G01Y49417D02*
X448700Y49833D01*
X449033Y50167D01*
X449500Y50333D01*
X449967Y50167D01*
X450300Y49833D01*
X450500Y49417D01*
Y47000D01*
G01Y49417D02*
X450700Y49833D01*
X451033Y50167D01*
X451500Y50333D01*
X451967Y50167D01*
X452300Y49833D01*
X452500Y49333D01*
Y47000D01*
G01X454600Y49250D02*
X456733D01*
X456533Y49833D01*
X456200Y50167D01*
X455733Y50333D01*
X455267Y50250D01*
X454867Y50000D01*
X454600Y49417D01*
X454467Y48917D01*
Y48417D01*
X454600Y47917D01*
X454933Y47417D01*
X455333Y47083D01*
X455800Y47000D01*
X456267Y47167D01*
X456733Y47667D01*
G01X460700Y52000D02*
Y47000D01*
G01X459767Y50333D02*
X461633D01*
G01X464800Y49250D02*
X466933D01*
X466733Y49833D01*
X466400Y50167D01*
X465933Y50333D01*
X465467Y50250D01*
X465067Y50000D01*
X464800Y49417D01*
X464667Y48917D01*
Y48417D01*
X464800Y47917D01*
X465133Y47417D01*
X465533Y47083D01*
X466000Y47000D01*
X466467Y47167D01*
X466933Y47667D01*
G01X469967Y47000D02*
Y50333D01*
G01Y49667D02*
X470300Y50000D01*
X470633Y50250D01*
X471100Y50333D01*
X471433Y50250D01*
X471833Y50000D01*
G01X479767Y47000D02*
X482433Y48667D01*
X479767Y50333D01*
G01X491300Y47000D02*
Y52000D01*
X490500Y51000D01*
G01Y47000D02*
X492100D01*
G01X497200D02*
Y52000D01*
X494733Y48417D01*
X498067D01*
G01X504600Y47000D02*
Y50333D01*
G01Y49417D02*
X504800Y49833D01*
X505133Y50167D01*
X505600Y50333D01*
X506067Y50167D01*
X506400Y49833D01*
X506600Y49417D01*
Y47000D01*
G01Y49417D02*
X506800Y49833D01*
X507133Y50167D01*
X507600Y50333D01*
X508067Y50167D01*
X508400Y49833D01*
X508600Y49333D01*
Y47000D01*
G01X511700Y50333D02*
Y47000D01*
G01Y51667D02*
X511567Y51750D01*
Y51917D01*
X511700Y52000D01*
X511833Y51917D01*
Y51750D01*
X511700Y51667D01*
G01X516800Y47000D02*
Y52000D01*
G01X264000Y40500D02*
X694500D01*
G01X264000Y75500D02*
X694500D01*
G01X264000Y90500D02*
X694500D01*
G01X271000Y141583D02*
X271333Y141250D01*
X271800Y141000D01*
X272200D01*
X272600Y141167D01*
X272867Y141417D01*
X273000Y141750D01*
X272933Y142250D01*
X272667Y142500D01*
X271467Y143000D01*
X271200Y143583D01*
X271333Y144000D01*
X271600Y144250D01*
X272000Y144333D01*
X272400Y144250D01*
X272800Y144000D01*
G01X275900Y139333D02*
Y144333D01*
G01Y143583D02*
X276233Y144000D01*
X276567Y144250D01*
X277100Y144333D01*
X277567Y144250D01*
X278033Y143833D01*
X278233Y143250D01*
X278300Y142667D01*
X278233Y142083D01*
X278033Y141500D01*
X277633Y141167D01*
X277100Y141000D01*
X276633Y141083D01*
X276167Y141333D01*
X275900Y141667D01*
G01X281200Y143250D02*
X283333D01*
X283133Y143833D01*
X282800Y144167D01*
X282333Y144333D01*
X281867Y144250D01*
X281467Y144000D01*
X281200Y143417D01*
X281067Y142917D01*
Y142417D01*
X281200Y141917D01*
X281533Y141417D01*
X281933Y141083D01*
X282400Y141000D01*
X282867Y141167D01*
X283333Y141667D01*
G01X288367Y143917D02*
X287900Y144250D01*
X287500Y144333D01*
X286967Y144167D01*
X286567Y143833D01*
X286300Y143250D01*
X286233Y142667D01*
X286300Y142083D01*
X286567Y141583D01*
X286967Y141167D01*
X287500Y141000D01*
X287967Y141167D01*
X288367Y141500D01*
G01X292400Y144333D02*
Y141000D01*
G01Y145667D02*
X292267Y145750D01*
Y145917D01*
X292400Y146000D01*
X292533Y145917D01*
Y145750D01*
X292400Y145667D01*
G01X297100Y141000D02*
Y145250D01*
X297233Y145667D01*
X297500Y145917D01*
X297900Y146000D01*
X298300Y145833D01*
X298500Y145417D01*
G01X297700Y144000D02*
X296367D01*
G01X302600Y144333D02*
Y141000D01*
G01Y145667D02*
X302467Y145750D01*
Y145917D01*
X302600Y146000D01*
X302733Y145917D01*
Y145750D01*
X302600Y145667D01*
G01X308767Y143917D02*
X308300Y144250D01*
X307900Y144333D01*
X307367Y144167D01*
X306967Y143833D01*
X306700Y143250D01*
X306633Y142667D01*
X306700Y142083D01*
X306967Y141583D01*
X307367Y141167D01*
X307900Y141000D01*
X308367Y141167D01*
X308767Y141500D01*
G01X314000Y141000D02*
Y144333D01*
G01Y143750D02*
X313733Y144083D01*
X313333Y144250D01*
X312867Y144333D01*
X312400Y144167D01*
X312000Y143833D01*
X311733Y143333D01*
X311600Y142667D01*
X311733Y142000D01*
X312000Y141500D01*
X312400Y141167D01*
X312867Y141000D01*
X313333Y141083D01*
X313733Y141333D01*
X314000Y141667D01*
G01X317900Y146000D02*
Y141000D01*
G01X316967Y144333D02*
X318833D01*
G01X323000D02*
Y141000D01*
G01Y145667D02*
X322867Y145750D01*
Y145917D01*
X323000Y146000D01*
X323133Y145917D01*
Y145750D01*
X323000Y145667D01*
G01X328100Y141000D02*
X327700Y141083D01*
X327300Y141417D01*
X327033Y142000D01*
X326900Y142667D01*
X327033Y143333D01*
X327300Y143917D01*
X327700Y144250D01*
X328100Y144333D01*
X328500Y144250D01*
X328900Y143917D01*
X329167Y143333D01*
X329233Y142667D01*
X329167Y142000D01*
X328900Y141417D01*
X328500Y141083D01*
X328100Y141000D01*
G01X332067D02*
Y144333D01*
G01Y143500D02*
X332333Y143917D01*
X332733Y144250D01*
X333267Y144333D01*
X333733Y144250D01*
X334133Y143917D01*
X334333Y143333D01*
Y141000D01*
G01X338300Y140833D02*
X338167Y140917D01*
Y141083D01*
X338300Y141167D01*
X338433Y141083D01*
Y140917D01*
X338300Y140833D01*
G01X272000Y101500D02*
Y96500D01*
G01X271067Y99833D02*
X272933D01*
G01X276167Y96500D02*
Y99833D01*
G01Y99167D02*
X276500Y99500D01*
X276833Y99750D01*
X277300Y99833D01*
X277633Y99750D01*
X278033Y99500D01*
G01X283400Y96500D02*
Y99833D01*
G01Y99250D02*
X283133Y99583D01*
X282733Y99750D01*
X282267Y99833D01*
X281800Y99667D01*
X281400Y99333D01*
X281133Y98833D01*
X281000Y98167D01*
X281133Y97500D01*
X281400Y97000D01*
X281800Y96667D01*
X282267Y96500D01*
X282733Y96583D01*
X283133Y96833D01*
X283400Y97167D01*
G01X288367Y99417D02*
X287900Y99750D01*
X287500Y99833D01*
X286967Y99667D01*
X286567Y99333D01*
X286300Y98750D01*
X286233Y98167D01*
X286300Y97583D01*
X286567Y97083D01*
X286967Y96667D01*
X287500Y96500D01*
X287967Y96667D01*
X288367Y97000D01*
G01X291400Y98750D02*
X293533D01*
X293333Y99333D01*
X293000Y99667D01*
X292533Y99833D01*
X292067Y99750D01*
X291667Y99500D01*
X291400Y98917D01*
X291267Y98417D01*
Y97917D01*
X291400Y97417D01*
X291733Y96917D01*
X292133Y96583D01*
X292600Y96500D01*
X293067Y96667D01*
X293533Y97167D01*
G01X300933Y99833D02*
X301733Y96500D01*
X302600Y99833D01*
X303467Y96500D01*
X304267Y99833D01*
G01X307700D02*
Y96500D01*
G01Y101167D02*
X307567Y101250D01*
Y101417D01*
X307700Y101500D01*
X307833Y101417D01*
Y101250D01*
X307700Y101167D01*
G01X314000Y101500D02*
Y96500D01*
G01Y97250D02*
X313733Y96833D01*
X313333Y96583D01*
X312867Y96500D01*
X312333Y96667D01*
X311933Y97083D01*
X311667Y97583D01*
X311600Y98167D01*
X311667Y98750D01*
X311933Y99250D01*
X312333Y99667D01*
X312867Y99833D01*
X313333Y99750D01*
X313667Y99583D01*
X314000Y99250D01*
G01X317900Y101500D02*
Y96500D01*
G01X316967Y99833D02*
X318833D01*
G01X321867Y96500D02*
Y101500D01*
G01Y99083D02*
X322200Y99500D01*
X322533Y99750D01*
X323067Y99833D01*
X323467Y99750D01*
X323933Y99417D01*
X324133Y98917D01*
Y96500D01*
G01X334533D02*
X331867Y98167D01*
X334533Y99833D01*
G01X337433Y97417D02*
X339167D01*
G01Y98917D02*
X337433D01*
G01X347033Y97250D02*
X347433Y96833D01*
X347900Y96583D01*
X348500Y96500D01*
X349100Y96667D01*
X349567Y97000D01*
X349900Y97583D01*
X349967Y98250D01*
X349833Y98917D01*
X349500Y99333D01*
X349033Y99667D01*
X348567Y99750D01*
X348100Y99667D01*
X347500Y99333D01*
X347700Y101500D01*
X349500D01*
G01X356700Y96500D02*
Y99833D01*
G01Y98917D02*
X356900Y99333D01*
X357233Y99667D01*
X357700Y99833D01*
X358167Y99667D01*
X358500Y99333D01*
X358700Y98917D01*
Y96500D01*
G01Y98917D02*
X358900Y99333D01*
X359233Y99667D01*
X359700Y99833D01*
X360167Y99667D01*
X360500Y99333D01*
X360700Y98833D01*
Y96500D01*
G01X363800Y99833D02*
Y96500D01*
G01Y101167D02*
X363667Y101250D01*
Y101417D01*
X363800Y101500D01*
X363933Y101417D01*
Y101250D01*
X363800Y101167D01*
G01X368900Y96500D02*
Y101500D01*
G01X270667Y110000D02*
Y115000D01*
X272333D01*
X272867Y114750D01*
X273200Y114417D01*
X273333Y113750D01*
X273200Y113083D01*
X272800Y112667D01*
X272333Y112417D01*
X270667D01*
G01X272333D02*
X273333Y110000D01*
G01X276100Y112250D02*
X278233D01*
X278033Y112833D01*
X277700Y113167D01*
X277233Y113333D01*
X276767Y113250D01*
X276367Y113000D01*
X276100Y112417D01*
X275967Y111917D01*
Y111417D01*
X276100Y110917D01*
X276433Y110417D01*
X276833Y110083D01*
X277300Y110000D01*
X277767Y110167D01*
X278233Y110667D01*
G01X282200Y110000D02*
Y115000D01*
G01X288500Y110000D02*
Y113333D01*
G01Y112750D02*
X288233Y113083D01*
X287833Y113250D01*
X287367Y113333D01*
X286900Y113167D01*
X286500Y112833D01*
X286233Y112333D01*
X286100Y111667D01*
X286233Y111000D01*
X286500Y110500D01*
X286900Y110167D01*
X287367Y110000D01*
X287833Y110083D01*
X288233Y110333D01*
X288500Y110667D01*
G01X292400Y115000D02*
Y110000D01*
G01X291467Y113333D02*
X293333D01*
G01X297500D02*
Y110000D01*
G01Y114667D02*
X297367Y114750D01*
Y114917D01*
X297500Y115000D01*
X297633Y114917D01*
Y114750D01*
X297500Y114667D01*
G01X301400Y113333D02*
X302600Y110000D01*
X303800Y113333D01*
G01X306700Y112250D02*
X308833D01*
X308633Y112833D01*
X308300Y113167D01*
X307833Y113333D01*
X307367Y113250D01*
X306967Y113000D01*
X306700Y112417D01*
X306567Y111917D01*
Y111417D01*
X306700Y110917D01*
X307033Y110417D01*
X307433Y110083D01*
X307900Y110000D01*
X308367Y110167D01*
X308833Y110667D01*
G01X316700Y108333D02*
Y113333D01*
G01Y112583D02*
X317033Y113000D01*
X317367Y113250D01*
X317900Y113333D01*
X318367Y113250D01*
X318833Y112833D01*
X319033Y112250D01*
X319100Y111667D01*
X319033Y111083D01*
X318833Y110500D01*
X318433Y110167D01*
X317900Y110000D01*
X317433Y110083D01*
X316967Y110333D01*
X316700Y110667D01*
G01X323000Y110000D02*
X322600Y110083D01*
X322200Y110417D01*
X321933Y111000D01*
X321800Y111667D01*
X321933Y112333D01*
X322200Y112917D01*
X322600Y113250D01*
X323000Y113333D01*
X323400Y113250D01*
X323800Y112917D01*
X324067Y112333D01*
X324133Y111667D01*
X324067Y111000D01*
X323800Y110417D01*
X323400Y110083D01*
X323000Y110000D01*
G01X327100Y110583D02*
X327433Y110250D01*
X327900Y110000D01*
X328300D01*
X328700Y110167D01*
X328967Y110417D01*
X329100Y110750D01*
X329033Y111250D01*
X328767Y111500D01*
X327567Y112000D01*
X327300Y112583D01*
X327433Y113000D01*
X327700Y113250D01*
X328100Y113333D01*
X328500Y113250D01*
X328900Y113000D01*
G01X333200Y113333D02*
Y110000D01*
G01Y114667D02*
X333067Y114750D01*
Y114917D01*
X333200Y115000D01*
X333333Y114917D01*
Y114750D01*
X333200Y114667D01*
G01X338300Y115000D02*
Y110000D01*
G01X337367Y113333D02*
X339233D01*
G01X343400D02*
Y110000D01*
G01Y114667D02*
X343267Y114750D01*
Y114917D01*
X343400Y115000D01*
X343533Y114917D01*
Y114750D01*
X343400Y114667D01*
G01X348500Y110000D02*
X348100Y110083D01*
X347700Y110417D01*
X347433Y111000D01*
X347300Y111667D01*
X347433Y112333D01*
X347700Y112917D01*
X348100Y113250D01*
X348500Y113333D01*
X348900Y113250D01*
X349300Y112917D01*
X349567Y112333D01*
X349633Y111667D01*
X349567Y111000D01*
X349300Y110417D01*
X348900Y110083D01*
X348500Y110000D01*
G01X352467D02*
Y113333D01*
G01Y112500D02*
X352733Y112917D01*
X353133Y113250D01*
X353667Y113333D01*
X354133Y113250D01*
X354533Y112917D01*
X354733Y112333D01*
Y110000D01*
G01X362600D02*
Y115000D01*
G01Y112500D02*
X362933Y113000D01*
X363333Y113250D01*
X363733Y113333D01*
X364333Y113167D01*
X364733Y112833D01*
X365000Y112250D01*
Y111583D01*
X364867Y110917D01*
X364600Y110417D01*
X364133Y110083D01*
X363733Y110000D01*
X363333Y110083D01*
X362933Y110333D01*
X362600Y110750D01*
G01X367900Y112250D02*
X370033D01*
X369833Y112833D01*
X369500Y113167D01*
X369033Y113333D01*
X368567Y113250D01*
X368167Y113000D01*
X367900Y112417D01*
X367767Y111917D01*
Y111417D01*
X367900Y110917D01*
X368233Y110417D01*
X368633Y110083D01*
X369100Y110000D01*
X369567Y110167D01*
X370033Y110667D01*
G01X374000Y115000D02*
Y110000D01*
G01X373067Y113333D02*
X374933D01*
G01X377433D02*
X378233Y110000D01*
X379100Y113333D01*
X379967Y110000D01*
X380767Y113333D01*
G01X383200Y112250D02*
X385333D01*
X385133Y112833D01*
X384800Y113167D01*
X384333Y113333D01*
X383867Y113250D01*
X383467Y113000D01*
X383200Y112417D01*
X383067Y111917D01*
Y111417D01*
X383200Y110917D01*
X383533Y110417D01*
X383933Y110083D01*
X384400Y110000D01*
X384867Y110167D01*
X385333Y110667D01*
G01X388300Y112250D02*
X390433D01*
X390233Y112833D01*
X389900Y113167D01*
X389433Y113333D01*
X388967Y113250D01*
X388567Y113000D01*
X388300Y112417D01*
X388167Y111917D01*
Y111417D01*
X388300Y110917D01*
X388633Y110417D01*
X389033Y110083D01*
X389500Y110000D01*
X389967Y110167D01*
X390433Y110667D01*
G01X393267Y110000D02*
Y113333D01*
G01Y112500D02*
X393533Y112917D01*
X393933Y113250D01*
X394467Y113333D01*
X394933Y113250D01*
X395333Y112917D01*
X395533Y112333D01*
Y110000D01*
G01X405800D02*
Y113333D01*
G01Y112750D02*
X405533Y113083D01*
X405133Y113250D01*
X404667Y113333D01*
X404200Y113167D01*
X403800Y112833D01*
X403533Y112333D01*
X403400Y111667D01*
X403533Y111000D01*
X403800Y110500D01*
X404200Y110167D01*
X404667Y110000D01*
X405133Y110083D01*
X405533Y110333D01*
X405800Y110667D01*
G01X408567Y110000D02*
Y113333D01*
G01Y112500D02*
X408833Y112917D01*
X409233Y113250D01*
X409767Y113333D01*
X410233Y113250D01*
X410633Y112917D01*
X410833Y112333D01*
Y110000D01*
G01X413400Y108500D02*
X413800Y108333D01*
X414333Y108500D01*
X414667Y108833D01*
X414933Y109250D01*
X415333Y110583D01*
X416200Y113333D01*
G01X414067D02*
X415333Y110583D01*
G01X423800Y108333D02*
Y113333D01*
G01Y112583D02*
X424133Y113000D01*
X424467Y113250D01*
X425000Y113333D01*
X425467Y113250D01*
X425933Y112833D01*
X426133Y112250D01*
X426200Y111667D01*
X426133Y111083D01*
X425933Y110500D01*
X425533Y110167D01*
X425000Y110000D01*
X424533Y110083D01*
X424067Y110333D01*
X423800Y110667D01*
G01X431300Y110000D02*
Y113333D01*
G01Y112750D02*
X431033Y113083D01*
X430633Y113250D01*
X430167Y113333D01*
X429700Y113167D01*
X429300Y112833D01*
X429033Y112333D01*
X428900Y111667D01*
X429033Y111000D01*
X429300Y110500D01*
X429700Y110167D01*
X430167Y110000D01*
X430633Y110083D01*
X431033Y110333D01*
X431300Y110667D01*
G01X436400Y115000D02*
Y110000D01*
G01Y110750D02*
X436133Y110333D01*
X435733Y110083D01*
X435267Y110000D01*
X434733Y110167D01*
X434333Y110583D01*
X434067Y111083D01*
X434000Y111667D01*
X434067Y112250D01*
X434333Y112750D01*
X434733Y113167D01*
X435267Y113333D01*
X435733Y113250D01*
X436067Y113083D01*
X436400Y112750D01*
G01X445400Y115000D02*
Y110000D01*
G01X444467Y113333D02*
X446333D01*
G01X450500Y110000D02*
X450100Y110083D01*
X449700Y110417D01*
X449433Y111000D01*
X449300Y111667D01*
X449433Y112333D01*
X449700Y112917D01*
X450100Y113250D01*
X450500Y113333D01*
X450900Y113250D01*
X451300Y112917D01*
X451567Y112333D01*
X451633Y111667D01*
X451567Y111000D01*
X451300Y110417D01*
X450900Y110083D01*
X450500Y110000D01*
G01X459500Y108333D02*
Y113333D01*
G01Y112583D02*
X459833Y113000D01*
X460167Y113250D01*
X460700Y113333D01*
X461167Y113250D01*
X461633Y112833D01*
X461833Y112250D01*
X461900Y111667D01*
X461833Y111083D01*
X461633Y110500D01*
X461233Y110167D01*
X460700Y110000D01*
X460233Y110083D01*
X459767Y110333D01*
X459500Y110667D01*
G01X467000Y110000D02*
Y113333D01*
G01Y112750D02*
X466733Y113083D01*
X466333Y113250D01*
X465867Y113333D01*
X465400Y113167D01*
X465000Y112833D01*
X464733Y112333D01*
X464600Y111667D01*
X464733Y111000D01*
X465000Y110500D01*
X465400Y110167D01*
X465867Y110000D01*
X466333Y110083D01*
X466733Y110333D01*
X467000Y110667D01*
G01X472100Y115000D02*
Y110000D01*
G01Y110750D02*
X471833Y110333D01*
X471433Y110083D01*
X470967Y110000D01*
X470433Y110167D01*
X470033Y110583D01*
X469767Y111083D01*
X469700Y111667D01*
X469767Y112250D01*
X470033Y112750D01*
X470433Y113167D01*
X470967Y113333D01*
X471433Y113250D01*
X471767Y113083D01*
X472100Y112750D01*
G01X270600Y125000D02*
Y130000D01*
G01X273400D02*
Y125000D01*
G01Y127500D02*
X270600D01*
G01X275633Y125000D02*
Y130000D01*
X276967D01*
X277500Y129750D01*
X277900Y129417D01*
X278233Y128917D01*
X278500Y128333D01*
X278567Y127500D01*
X278500Y126667D01*
X278233Y126083D01*
X277900Y125583D01*
X277500Y125250D01*
X276967Y125000D01*
X275633D01*
G01X281400Y130000D02*
X283000D01*
G01X282200D02*
Y125000D01*
G01X281400D02*
X283000D01*
G01X291067D02*
Y130000D01*
X292667D01*
X293200Y129750D01*
X293600Y129167D01*
X293733Y128500D01*
X293600Y127833D01*
X293267Y127333D01*
X292667Y127083D01*
X291067D01*
G01X298967Y129583D02*
X298567Y129833D01*
X298100Y130000D01*
X297567D01*
X296967Y129750D01*
X296500Y129333D01*
X296167Y128833D01*
X295900Y128000D01*
X295833Y127250D01*
X295967Y126500D01*
X296167Y126000D01*
X296567Y125500D01*
X297033Y125167D01*
X297500Y125000D01*
X297967D01*
X298433Y125167D01*
X298833Y125417D01*
X299167Y125750D01*
G01X303133Y127667D02*
X303400Y127917D01*
X303600Y128333D01*
X303733Y128917D01*
X303600Y129417D01*
X303333Y129750D01*
X302867Y130000D01*
X301067D01*
Y125000D01*
X303267D01*
X303733Y125333D01*
X304000Y125833D01*
X304133Y126417D01*
X304000Y127000D01*
X303600Y127500D01*
X303133Y127667D01*
X301067D01*
G01X307700Y124833D02*
X307567Y124917D01*
Y125083D01*
X307700Y125167D01*
X307833Y125083D01*
Y124917D01*
X307700Y124833D01*
G01X270600Y150667D02*
X271133Y150250D01*
X271733Y150000D01*
X272267D01*
X272800Y150250D01*
X273200Y150667D01*
X273400Y151250D01*
X273267Y151833D01*
X272933Y152333D01*
X272333Y152667D01*
X271533Y152833D01*
X271067Y153167D01*
X270867Y153750D01*
X271000Y154333D01*
X271333Y154750D01*
X271800Y155000D01*
X272267D01*
X272733Y154833D01*
X273133Y154417D01*
G01X276100Y152250D02*
X278233D01*
X278033Y152833D01*
X277700Y153167D01*
X277233Y153333D01*
X276767Y153250D01*
X276367Y153000D01*
X276100Y152417D01*
X275967Y151917D01*
Y151417D01*
X276100Y150917D01*
X276433Y150417D01*
X276833Y150083D01*
X277300Y150000D01*
X277767Y150167D01*
X278233Y150667D01*
G01X281267Y150000D02*
Y153333D01*
G01Y152667D02*
X281600Y153000D01*
X281933Y153250D01*
X282400Y153333D01*
X282733Y153250D01*
X283133Y153000D01*
G01X286100Y153333D02*
X287300Y150000D01*
X288500Y153333D01*
G01X291400Y152250D02*
X293533D01*
X293333Y152833D01*
X293000Y153167D01*
X292533Y153333D01*
X292067Y153250D01*
X291667Y153000D01*
X291400Y152417D01*
X291267Y151917D01*
Y151417D01*
X291400Y150917D01*
X291733Y150417D01*
X292133Y150083D01*
X292600Y150000D01*
X293067Y150167D01*
X293533Y150667D01*
G01X296567Y150000D02*
Y153333D01*
G01Y152667D02*
X296900Y153000D01*
X297233Y153250D01*
X297700Y153333D01*
X298033Y153250D01*
X298433Y153000D01*
G01X306367Y150000D02*
Y155000D01*
X307967D01*
X308500Y154750D01*
X308900Y154167D01*
X309033Y153500D01*
X308900Y152833D01*
X308567Y152333D01*
X307967Y152083D01*
X306367D01*
G01X314267Y154583D02*
X313867Y154833D01*
X313400Y155000D01*
X312867D01*
X312267Y154750D01*
X311800Y154333D01*
X311467Y153833D01*
X311200Y153000D01*
X311133Y152250D01*
X311267Y151500D01*
X311467Y151000D01*
X311867Y150500D01*
X312333Y150167D01*
X312800Y150000D01*
X313267D01*
X313733Y150167D01*
X314133Y150417D01*
X314467Y150750D01*
G01X318433Y152667D02*
X318700Y152917D01*
X318900Y153333D01*
X319033Y153917D01*
X318900Y154417D01*
X318633Y154750D01*
X318167Y155000D01*
X316367D01*
Y150000D01*
X318567D01*
X319033Y150333D01*
X319300Y150833D01*
X319433Y151417D01*
X319300Y152000D01*
X318900Y152500D01*
X318433Y152667D01*
X316367D01*
G01X323000Y149833D02*
X322867Y149917D01*
Y150083D01*
X323000Y150167D01*
X323133Y150083D01*
Y149917D01*
X323000Y149833D01*
G01Y152083D02*
X322867Y152167D01*
Y152333D01*
X323000Y152417D01*
X323133Y152333D01*
Y152167D01*
X323000Y152083D01*
G01X326833Y150000D02*
Y155000D01*
X329367D01*
G01X328433Y152583D02*
X326833D01*
G01X333200Y150000D02*
X332800Y150083D01*
X332400Y150417D01*
X332133Y151000D01*
X332000Y151667D01*
X332133Y152333D01*
X332400Y152917D01*
X332800Y153250D01*
X333200Y153333D01*
X333600Y153250D01*
X334000Y152917D01*
X334267Y152333D01*
X334333Y151667D01*
X334267Y151000D01*
X334000Y150417D01*
X333600Y150083D01*
X333200Y150000D01*
G01X338300D02*
Y155000D01*
G01X343400Y150000D02*
Y155000D01*
G01X348500Y150000D02*
X348100Y150083D01*
X347700Y150417D01*
X347433Y151000D01*
X347300Y151667D01*
X347433Y152333D01*
X347700Y152917D01*
X348100Y153250D01*
X348500Y153333D01*
X348900Y153250D01*
X349300Y152917D01*
X349567Y152333D01*
X349633Y151667D01*
X349567Y151000D01*
X349300Y150417D01*
X348900Y150083D01*
X348500Y150000D01*
G01X351933Y153333D02*
X352733Y150000D01*
X353600Y153333D01*
X354467Y150000D01*
X355267Y153333D01*
G01X362867Y150000D02*
Y153333D01*
G01Y152667D02*
X363200Y153000D01*
X363533Y153250D01*
X364000Y153333D01*
X364333Y153250D01*
X364733Y153000D01*
G01X368900Y153333D02*
Y150000D01*
G01Y154667D02*
X368767Y154750D01*
Y154917D01*
X368900Y155000D01*
X369033Y154917D01*
Y154750D01*
X368900Y154667D01*
G01X373067Y148750D02*
X373533Y148417D01*
X374067Y148333D01*
X374533Y148417D01*
X374933Y148833D01*
X375200Y149417D01*
Y153333D01*
G01Y152667D02*
X374933Y153000D01*
X374533Y153250D01*
X374067Y153333D01*
X373533Y153167D01*
X373200Y152833D01*
X372933Y152250D01*
X372800Y151667D01*
X372867Y151167D01*
X373133Y150583D01*
X373533Y150167D01*
X374067Y150000D01*
X374467Y150083D01*
X374933Y150417D01*
X375200Y150750D01*
G01X377967Y150000D02*
Y155000D01*
G01Y152583D02*
X378300Y153000D01*
X378633Y153250D01*
X379167Y153333D01*
X379567Y153250D01*
X380033Y152917D01*
X380233Y152417D01*
Y150000D01*
G01X384200Y155000D02*
Y150000D01*
G01X383267Y153333D02*
X385133D01*
G01X393400Y150583D02*
X393733Y150250D01*
X394200Y150000D01*
X394600D01*
X395000Y150167D01*
X395267Y150417D01*
X395400Y150750D01*
X395333Y151250D01*
X395067Y151500D01*
X393867Y152000D01*
X393600Y152583D01*
X393733Y153000D01*
X394000Y153250D01*
X394400Y153333D01*
X394800Y153250D01*
X395200Y153000D01*
G01X399500Y153333D02*
Y150000D01*
G01Y154667D02*
X399367Y154750D01*
Y154917D01*
X399500Y155000D01*
X399633Y154917D01*
Y154750D01*
X399500Y154667D01*
G01X405800Y155000D02*
Y150000D01*
G01Y150750D02*
X405533Y150333D01*
X405133Y150083D01*
X404667Y150000D01*
X404133Y150167D01*
X403733Y150583D01*
X403467Y151083D01*
X403400Y151667D01*
X403467Y152250D01*
X403733Y152750D01*
X404133Y153167D01*
X404667Y153333D01*
X405133Y153250D01*
X405467Y153083D01*
X405800Y152750D01*
G01X408700Y152250D02*
X410833D01*
X410633Y152833D01*
X410300Y153167D01*
X409833Y153333D01*
X409367Y153250D01*
X408967Y153000D01*
X408700Y152417D01*
X408567Y151917D01*
Y151417D01*
X408700Y150917D01*
X409033Y150417D01*
X409433Y150083D01*
X409900Y150000D01*
X410367Y150167D01*
X410833Y150667D01*
G01X418900Y150583D02*
X419233Y150250D01*
X419700Y150000D01*
X420100D01*
X420500Y150167D01*
X420767Y150417D01*
X420900Y150750D01*
X420833Y151250D01*
X420567Y151500D01*
X419367Y152000D01*
X419100Y152583D01*
X419233Y153000D01*
X419500Y153250D01*
X419900Y153333D01*
X420300Y153250D01*
X420700Y153000D01*
G01X423800Y148333D02*
Y153333D01*
G01Y152583D02*
X424133Y153000D01*
X424467Y153250D01*
X425000Y153333D01*
X425467Y153250D01*
X425933Y152833D01*
X426133Y152250D01*
X426200Y151667D01*
X426133Y151083D01*
X425933Y150500D01*
X425533Y150167D01*
X425000Y150000D01*
X424533Y150083D01*
X424067Y150333D01*
X423800Y150667D01*
G01X429100Y152250D02*
X431233D01*
X431033Y152833D01*
X430700Y153167D01*
X430233Y153333D01*
X429767Y153250D01*
X429367Y153000D01*
X429100Y152417D01*
X428967Y151917D01*
Y151417D01*
X429100Y150917D01*
X429433Y150417D01*
X429833Y150083D01*
X430300Y150000D01*
X430767Y150167D01*
X431233Y150667D01*
G01X436267Y152917D02*
X435800Y153250D01*
X435400Y153333D01*
X434867Y153167D01*
X434467Y152833D01*
X434200Y152250D01*
X434133Y151667D01*
X434200Y151083D01*
X434467Y150583D01*
X434867Y150167D01*
X435400Y150000D01*
X435867Y150167D01*
X436267Y150500D01*
G01X445267Y149083D02*
X445533Y150167D01*
G01X450500Y153333D02*
Y150000D01*
G01Y154667D02*
X450367Y154750D01*
Y154917D01*
X450500Y155000D01*
X450633Y154917D01*
Y154750D01*
X450500Y154667D01*
G01X455200Y150000D02*
Y154250D01*
X455333Y154667D01*
X455600Y154917D01*
X456000Y155000D01*
X456400Y154833D01*
X456600Y154417D01*
G01X455800Y153000D02*
X454467D01*
G01X464800Y150583D02*
X465133Y150250D01*
X465600Y150000D01*
X466000D01*
X466400Y150167D01*
X466667Y150417D01*
X466800Y150750D01*
X466733Y151250D01*
X466467Y151500D01*
X465267Y152000D01*
X465000Y152583D01*
X465133Y153000D01*
X465400Y153250D01*
X465800Y153333D01*
X466200Y153250D01*
X466600Y153000D01*
G01X470900Y155000D02*
Y150000D01*
G01X469967Y153333D02*
X471833D01*
G01X477200Y150000D02*
Y153333D01*
G01Y152750D02*
X476933Y153083D01*
X476533Y153250D01*
X476067Y153333D01*
X475600Y153167D01*
X475200Y152833D01*
X474933Y152333D01*
X474800Y151667D01*
X474933Y151000D01*
X475200Y150500D01*
X475600Y150167D01*
X476067Y150000D01*
X476533Y150083D01*
X476933Y150333D01*
X477200Y150667D01*
G01X482167Y152917D02*
X481700Y153250D01*
X481300Y153333D01*
X480767Y153167D01*
X480367Y152833D01*
X480100Y152250D01*
X480033Y151667D01*
X480100Y151083D01*
X480367Y150583D01*
X480767Y150167D01*
X481300Y150000D01*
X481767Y150167D01*
X482167Y150500D01*
G01X485067Y150000D02*
Y155000D01*
G01X487200Y153333D02*
X485067Y151417D01*
G01X485933Y152167D02*
X487333Y150000D01*
G01X495267Y153333D02*
Y151000D01*
X495533Y150417D01*
X495933Y150083D01*
X496400Y150000D01*
X496867Y150083D01*
X497267Y150417D01*
X497533Y151000D01*
G01Y150000D02*
Y153333D01*
G01X500300Y148333D02*
Y153333D01*
G01Y152583D02*
X500633Y153000D01*
X500967Y153250D01*
X501500Y153333D01*
X501967Y153250D01*
X502433Y152833D01*
X502633Y152250D01*
X502700Y151667D01*
X502633Y151083D01*
X502433Y150500D01*
X502033Y150167D01*
X501500Y150000D01*
X501033Y150083D01*
X500567Y150333D01*
X500300Y150667D01*
G01X510033Y153333D02*
X510833Y150000D01*
X511700Y153333D01*
X512567Y150000D01*
X513367Y153333D01*
G01X516800D02*
Y150000D01*
G01Y154667D02*
X516667Y154750D01*
Y154917D01*
X516800Y155000D01*
X516933Y154917D01*
Y154750D01*
X516800Y154667D01*
G01X521900Y155000D02*
Y150000D01*
G01X520967Y153333D02*
X522833D01*
G01X525867Y150000D02*
Y155000D01*
G01Y152583D02*
X526200Y153000D01*
X526533Y153250D01*
X527067Y153333D01*
X527467Y153250D01*
X527933Y152917D01*
X528133Y152417D01*
Y150000D01*
G01X532100D02*
X531700Y150083D01*
X531300Y150417D01*
X531033Y151000D01*
X530900Y151667D01*
X531033Y152333D01*
X531300Y152917D01*
X531700Y153250D01*
X532100Y153333D01*
X532500Y153250D01*
X532900Y152917D01*
X533167Y152333D01*
X533233Y151667D01*
X533167Y151000D01*
X532900Y150417D01*
X532500Y150083D01*
X532100Y150000D01*
G01X536067Y153333D02*
Y151000D01*
X536333Y150417D01*
X536733Y150083D01*
X537200Y150000D01*
X537667Y150083D01*
X538067Y150417D01*
X538333Y151000D01*
G01Y150000D02*
Y153333D01*
G01X542300Y155000D02*
Y150000D01*
G01X541367Y153333D02*
X543233D01*
G01X264000Y135500D02*
X694500D01*
G01X272000Y170000D02*
Y165000D01*
G01X270467Y170000D02*
X273533D01*
G01X276167Y165000D02*
Y168333D01*
G01Y167667D02*
X276500Y168000D01*
X276833Y168250D01*
X277300Y168333D01*
X277633Y168250D01*
X278033Y168000D01*
G01X283400Y165000D02*
Y168333D01*
G01Y167750D02*
X283133Y168083D01*
X282733Y168250D01*
X282267Y168333D01*
X281800Y168167D01*
X281400Y167833D01*
X281133Y167333D01*
X281000Y166667D01*
X281133Y166000D01*
X281400Y165500D01*
X281800Y165167D01*
X282267Y165000D01*
X282733Y165083D01*
X283133Y165333D01*
X283400Y165667D01*
G01X288500Y170000D02*
Y165000D01*
G01Y165750D02*
X288233Y165333D01*
X287833Y165083D01*
X287367Y165000D01*
X286833Y165167D01*
X286433Y165583D01*
X286167Y166083D01*
X286100Y166667D01*
X286167Y167250D01*
X286433Y167750D01*
X286833Y168167D01*
X287367Y168333D01*
X287833Y168250D01*
X288167Y168083D01*
X288500Y167750D01*
G01X292400Y168333D02*
Y165000D01*
G01Y169667D02*
X292267Y169750D01*
Y169917D01*
X292400Y170000D01*
X292533Y169917D01*
Y169750D01*
X292400Y169667D01*
G01X297500Y170000D02*
Y165000D01*
G01X296567Y168333D02*
X298433D01*
G01X302600D02*
Y165000D01*
G01Y169667D02*
X302467Y169750D01*
Y169917D01*
X302600Y170000D01*
X302733Y169917D01*
Y169750D01*
X302600Y169667D01*
G01X307700Y165000D02*
X307300Y165083D01*
X306900Y165417D01*
X306633Y166000D01*
X306500Y166667D01*
X306633Y167333D01*
X306900Y167917D01*
X307300Y168250D01*
X307700Y168333D01*
X308100Y168250D01*
X308500Y167917D01*
X308767Y167333D01*
X308833Y166667D01*
X308767Y166000D01*
X308500Y165417D01*
X308100Y165083D01*
X307700Y165000D01*
G01X311667D02*
Y168333D01*
G01Y167500D02*
X311933Y167917D01*
X312333Y168250D01*
X312867Y168333D01*
X313333Y168250D01*
X313733Y167917D01*
X313933Y167333D01*
Y165000D01*
G01X319100D02*
Y168333D01*
G01Y167750D02*
X318833Y168083D01*
X318433Y168250D01*
X317967Y168333D01*
X317500Y168167D01*
X317100Y167833D01*
X316833Y167333D01*
X316700Y166667D01*
X316833Y166000D01*
X317100Y165500D01*
X317500Y165167D01*
X317967Y165000D01*
X318433Y165083D01*
X318833Y165333D01*
X319100Y165667D01*
G01X323000Y165000D02*
Y170000D01*
G01X331867Y165000D02*
Y170000D01*
X333467D01*
X334000Y169750D01*
X334400Y169167D01*
X334533Y168500D01*
X334400Y167833D01*
X334067Y167333D01*
X333467Y167083D01*
X331867D01*
G01X339767Y169583D02*
X339367Y169833D01*
X338900Y170000D01*
X338367D01*
X337767Y169750D01*
X337300Y169333D01*
X336967Y168833D01*
X336700Y168000D01*
X336633Y167250D01*
X336767Y166500D01*
X336967Y166000D01*
X337367Y165500D01*
X337833Y165167D01*
X338300Y165000D01*
X338767D01*
X339233Y165167D01*
X339633Y165417D01*
X339967Y165750D01*
G01X343933Y167667D02*
X344200Y167917D01*
X344400Y168333D01*
X344533Y168917D01*
X344400Y169417D01*
X344133Y169750D01*
X343667Y170000D01*
X341867D01*
Y165000D01*
X344067D01*
X344533Y165333D01*
X344800Y165833D01*
X344933Y166417D01*
X344800Y167000D01*
X344400Y167500D01*
X343933Y167667D01*
X341867D01*
G01X348500Y164833D02*
X348367Y164917D01*
Y165083D01*
X348500Y165167D01*
X348633Y165083D01*
Y164917D01*
X348500Y164833D01*
G01X264000Y160500D02*
X694500D01*
G01X262500Y237500D02*
X694500D01*
G01X262500Y290500D02*
X694500D01*
G01X269500Y374000D02*
Y369000D01*
G01X268567Y372333D02*
X270433D01*
G01X274600Y369000D02*
X274200Y369083D01*
X273800Y369417D01*
X273533Y370000D01*
X273400Y370667D01*
X273533Y371333D01*
X273800Y371917D01*
X274200Y372250D01*
X274600Y372333D01*
X275000Y372250D01*
X275400Y371917D01*
X275667Y371333D01*
X275733Y370667D01*
X275667Y370000D01*
X275400Y369417D01*
X275000Y369083D01*
X274600Y369000D01*
G01X279700D02*
Y374000D01*
G01X283800Y371250D02*
X285933D01*
X285733Y371833D01*
X285400Y372167D01*
X284933Y372333D01*
X284467Y372250D01*
X284067Y372000D01*
X283800Y371417D01*
X283667Y370917D01*
Y370417D01*
X283800Y369917D01*
X284133Y369417D01*
X284533Y369083D01*
X285000Y369000D01*
X285467Y369167D01*
X285933Y369667D01*
G01X288967Y369000D02*
Y372333D01*
G01Y371667D02*
X289300Y372000D01*
X289633Y372250D01*
X290100Y372333D01*
X290433Y372250D01*
X290833Y372000D01*
G01X296200Y369000D02*
Y372333D01*
G01Y371750D02*
X295933Y372083D01*
X295533Y372250D01*
X295067Y372333D01*
X294600Y372167D01*
X294200Y371833D01*
X293933Y371333D01*
X293800Y370667D01*
X293933Y370000D01*
X294200Y369500D01*
X294600Y369167D01*
X295067Y369000D01*
X295533Y369083D01*
X295933Y369333D01*
X296200Y369667D01*
G01X298967Y369000D02*
Y372333D01*
G01Y371500D02*
X299233Y371917D01*
X299633Y372250D01*
X300167Y372333D01*
X300633Y372250D01*
X301033Y371917D01*
X301233Y371333D01*
Y369000D01*
G01X306267Y371917D02*
X305800Y372250D01*
X305400Y372333D01*
X304867Y372167D01*
X304467Y371833D01*
X304200Y371250D01*
X304133Y370667D01*
X304200Y370083D01*
X304467Y369583D01*
X304867Y369167D01*
X305400Y369000D01*
X305867Y369167D01*
X306267Y369500D01*
G01X309300Y371250D02*
X311433D01*
X311233Y371833D01*
X310900Y372167D01*
X310433Y372333D01*
X309967Y372250D01*
X309567Y372000D01*
X309300Y371417D01*
X309167Y370917D01*
Y370417D01*
X309300Y369917D01*
X309633Y369417D01*
X310033Y369083D01*
X310500Y369000D01*
X310967Y369167D01*
X311433Y369667D01*
G01X320500Y374000D02*
Y369000D01*
G01X319567Y372333D02*
X321433D01*
G01X326800Y369000D02*
Y372333D01*
G01Y371750D02*
X326533Y372083D01*
X326133Y372250D01*
X325667Y372333D01*
X325200Y372167D01*
X324800Y371833D01*
X324533Y371333D01*
X324400Y370667D01*
X324533Y370000D01*
X324800Y369500D01*
X325200Y369167D01*
X325667Y369000D01*
X326133Y369083D01*
X326533Y369333D01*
X326800Y369667D01*
G01X329500Y369000D02*
Y374000D01*
G01Y371500D02*
X329833Y372000D01*
X330233Y372250D01*
X330633Y372333D01*
X331233Y372167D01*
X331633Y371833D01*
X331900Y371250D01*
Y370583D01*
X331767Y369917D01*
X331500Y369417D01*
X331033Y369083D01*
X330633Y369000D01*
X330233Y369083D01*
X329833Y369333D01*
X329500Y369750D01*
G01X335800Y369000D02*
Y374000D01*
G01X339900Y371250D02*
X342033D01*
X341833Y371833D01*
X341500Y372167D01*
X341033Y372333D01*
X340567Y372250D01*
X340167Y372000D01*
X339900Y371417D01*
X339767Y370917D01*
Y370417D01*
X339900Y369917D01*
X340233Y369417D01*
X340633Y369083D01*
X341100Y369000D01*
X341567Y369167D01*
X342033Y369667D01*
G01X346000Y368833D02*
X345867Y368917D01*
Y369083D01*
X346000Y369167D01*
X346133Y369083D01*
Y368917D01*
X346000Y368833D01*
G01X268433Y379750D02*
X268900Y379417D01*
X269300Y379333D01*
X269833Y379500D01*
X270233Y379917D01*
X270433Y380667D01*
Y384333D01*
G01Y385667D02*
X270300Y385750D01*
Y385917D01*
X270433Y386000D01*
X270567Y385917D01*
Y385750D01*
X270433Y385667D01*
G01X273467Y384333D02*
Y382000D01*
X273733Y381417D01*
X274133Y381083D01*
X274600Y381000D01*
X275067Y381083D01*
X275467Y381417D01*
X275733Y382000D01*
G01Y381000D02*
Y384333D01*
G01X278567Y381000D02*
Y384333D01*
G01Y383500D02*
X278833Y383917D01*
X279233Y384250D01*
X279767Y384333D01*
X280233Y384250D01*
X280633Y383917D01*
X280833Y383333D01*
Y381000D01*
G01X285867Y383917D02*
X285400Y384250D01*
X285000Y384333D01*
X284467Y384167D01*
X284067Y383833D01*
X283800Y383250D01*
X283733Y382667D01*
X283800Y382083D01*
X284067Y381583D01*
X284467Y381167D01*
X285000Y381000D01*
X285467Y381167D01*
X285867Y381500D01*
G01X289900Y386000D02*
Y381000D01*
G01X288967Y384333D02*
X290833D01*
G01X295000D02*
Y381000D01*
G01Y385667D02*
X294867Y385750D01*
Y385917D01*
X295000Y386000D01*
X295133Y385917D01*
Y385750D01*
X295000Y385667D01*
G01X300100Y381000D02*
X299700Y381083D01*
X299300Y381417D01*
X299033Y382000D01*
X298900Y382667D01*
X299033Y383333D01*
X299300Y383917D01*
X299700Y384250D01*
X300100Y384333D01*
X300500Y384250D01*
X300900Y383917D01*
X301167Y383333D01*
X301233Y382667D01*
X301167Y382000D01*
X300900Y381417D01*
X300500Y381083D01*
X300100Y381000D01*
G01X304067D02*
Y384333D01*
G01Y383500D02*
X304333Y383917D01*
X304733Y384250D01*
X305267Y384333D01*
X305733Y384250D01*
X306133Y383917D01*
X306333Y383333D01*
Y381000D01*
G01X314200D02*
Y386000D01*
G01Y383500D02*
X314533Y384000D01*
X314933Y384250D01*
X315333Y384333D01*
X315933Y384167D01*
X316333Y383833D01*
X316600Y383250D01*
Y382583D01*
X316467Y381917D01*
X316200Y381417D01*
X315733Y381083D01*
X315333Y381000D01*
X314933Y381083D01*
X314533Y381333D01*
X314200Y381750D01*
G01X319500Y383250D02*
X321633D01*
X321433Y383833D01*
X321100Y384167D01*
X320633Y384333D01*
X320167Y384250D01*
X319767Y384000D01*
X319500Y383417D01*
X319367Y382917D01*
Y382417D01*
X319500Y381917D01*
X319833Y381417D01*
X320233Y381083D01*
X320700Y381000D01*
X321167Y381167D01*
X321633Y381667D01*
G01X325600Y381000D02*
Y386000D01*
G01X330700Y381000D02*
X330300Y381083D01*
X329900Y381417D01*
X329633Y382000D01*
X329500Y382667D01*
X329633Y383333D01*
X329900Y383917D01*
X330300Y384250D01*
X330700Y384333D01*
X331100Y384250D01*
X331500Y383917D01*
X331767Y383333D01*
X331833Y382667D01*
X331767Y382000D01*
X331500Y381417D01*
X331100Y381083D01*
X330700Y381000D01*
G01X334133Y384333D02*
X334933Y381000D01*
X335800Y384333D01*
X336667Y381000D01*
X337467Y384333D01*
G01X346000Y386000D02*
Y381000D01*
G01X345067Y384333D02*
X346933D01*
G01X349967Y381000D02*
Y386000D01*
G01Y383583D02*
X350300Y384000D01*
X350633Y384250D01*
X351167Y384333D01*
X351567Y384250D01*
X352033Y383917D01*
X352233Y383417D01*
Y381000D01*
G01X355200Y383250D02*
X357333D01*
X357133Y383833D01*
X356800Y384167D01*
X356333Y384333D01*
X355867Y384250D01*
X355467Y384000D01*
X355200Y383417D01*
X355067Y382917D01*
Y382417D01*
X355200Y381917D01*
X355533Y381417D01*
X355933Y381083D01*
X356400Y381000D01*
X356867Y381167D01*
X357333Y381667D01*
G01X364400Y381000D02*
Y384333D01*
G01Y383417D02*
X364600Y383833D01*
X364933Y384167D01*
X365400Y384333D01*
X365867Y384167D01*
X366200Y383833D01*
X366400Y383417D01*
Y381000D01*
G01Y383417D02*
X366600Y383833D01*
X366933Y384167D01*
X367400Y384333D01*
X367867Y384167D01*
X368200Y383833D01*
X368400Y383333D01*
Y381000D01*
G01X371500Y384333D02*
Y381000D01*
G01Y385667D02*
X371367Y385750D01*
Y385917D01*
X371500Y386000D01*
X371633Y385917D01*
Y385750D01*
X371500Y385667D01*
G01X375467Y381000D02*
Y384333D01*
G01Y383500D02*
X375733Y383917D01*
X376133Y384250D01*
X376667Y384333D01*
X377133Y384250D01*
X377533Y383917D01*
X377733Y383333D01*
Y381000D01*
G01X387867Y383917D02*
X387400Y384250D01*
X387000Y384333D01*
X386467Y384167D01*
X386067Y383833D01*
X385800Y383250D01*
X385733Y382667D01*
X385800Y382083D01*
X386067Y381583D01*
X386467Y381167D01*
X387000Y381000D01*
X387467Y381167D01*
X387867Y381500D01*
G01X391900Y381000D02*
X391500Y381083D01*
X391100Y381417D01*
X390833Y382000D01*
X390700Y382667D01*
X390833Y383333D01*
X391100Y383917D01*
X391500Y384250D01*
X391900Y384333D01*
X392300Y384250D01*
X392700Y383917D01*
X392967Y383333D01*
X393033Y382667D01*
X392967Y382000D01*
X392700Y381417D01*
X392300Y381083D01*
X391900Y381000D01*
G01X395867D02*
Y384333D01*
G01Y383500D02*
X396133Y383917D01*
X396533Y384250D01*
X397067Y384333D01*
X397533Y384250D01*
X397933Y383917D01*
X398133Y383333D01*
Y381000D01*
G01X403300Y386000D02*
Y381000D01*
G01Y381750D02*
X403033Y381333D01*
X402633Y381083D01*
X402167Y381000D01*
X401633Y381167D01*
X401233Y381583D01*
X400967Y382083D01*
X400900Y382667D01*
X400967Y383250D01*
X401233Y383750D01*
X401633Y384167D01*
X402167Y384333D01*
X402633Y384250D01*
X402967Y384083D01*
X403300Y383750D01*
G01X406067Y384333D02*
Y382000D01*
X406333Y381417D01*
X406733Y381083D01*
X407200Y381000D01*
X407667Y381083D01*
X408067Y381417D01*
X408333Y382000D01*
G01Y381000D02*
Y384333D01*
G01X413367Y383917D02*
X412900Y384250D01*
X412500Y384333D01*
X411967Y384167D01*
X411567Y383833D01*
X411300Y383250D01*
X411233Y382667D01*
X411300Y382083D01*
X411567Y381583D01*
X411967Y381167D01*
X412500Y381000D01*
X412967Y381167D01*
X413367Y381500D01*
G01X417400Y386000D02*
Y381000D01*
G01X416467Y384333D02*
X418333D01*
G01X422500Y381000D02*
X422100Y381083D01*
X421700Y381417D01*
X421433Y382000D01*
X421300Y382667D01*
X421433Y383333D01*
X421700Y383917D01*
X422100Y384250D01*
X422500Y384333D01*
X422900Y384250D01*
X423300Y383917D01*
X423567Y383333D01*
X423633Y382667D01*
X423567Y382000D01*
X423300Y381417D01*
X422900Y381083D01*
X422500Y381000D01*
G01X426667D02*
Y384333D01*
G01Y383667D02*
X427000Y384000D01*
X427333Y384250D01*
X427800Y384333D01*
X428133Y384250D01*
X428533Y384000D01*
G01X436133Y384333D02*
X436933Y381000D01*
X437800Y384333D01*
X438667Y381000D01*
X439467Y384333D01*
G01X442900D02*
Y381000D01*
G01Y385667D02*
X442767Y385750D01*
Y385917D01*
X442900Y386000D01*
X443033Y385917D01*
Y385750D01*
X442900Y385667D01*
G01X449200Y386000D02*
Y381000D01*
G01Y381750D02*
X448933Y381333D01*
X448533Y381083D01*
X448067Y381000D01*
X447533Y381167D01*
X447133Y381583D01*
X446867Y382083D01*
X446800Y382667D01*
X446867Y383250D01*
X447133Y383750D01*
X447533Y384167D01*
X448067Y384333D01*
X448533Y384250D01*
X448867Y384083D01*
X449200Y383750D01*
G01X453100Y386000D02*
Y381000D01*
G01X452167Y384333D02*
X454033D01*
G01X457067Y381000D02*
Y386000D01*
G01Y383583D02*
X457400Y384000D01*
X457733Y384250D01*
X458267Y384333D01*
X458667Y384250D01*
X459133Y383917D01*
X459333Y383417D01*
Y381000D01*
G01X467400Y381583D02*
X467733Y381250D01*
X468200Y381000D01*
X468600D01*
X469000Y381167D01*
X469267Y381417D01*
X469400Y381750D01*
X469333Y382250D01*
X469067Y382500D01*
X467867Y383000D01*
X467600Y383583D01*
X467733Y384000D01*
X468000Y384250D01*
X468400Y384333D01*
X468800Y384250D01*
X469200Y384000D01*
G01X472300Y379333D02*
Y384333D01*
G01Y383583D02*
X472633Y384000D01*
X472967Y384250D01*
X473500Y384333D01*
X473967Y384250D01*
X474433Y383833D01*
X474633Y383250D01*
X474700Y382667D01*
X474633Y382083D01*
X474433Y381500D01*
X474033Y381167D01*
X473500Y381000D01*
X473033Y381083D01*
X472567Y381333D01*
X472300Y381667D01*
G01X477600Y383250D02*
X479733D01*
X479533Y383833D01*
X479200Y384167D01*
X478733Y384333D01*
X478267Y384250D01*
X477867Y384000D01*
X477600Y383417D01*
X477467Y382917D01*
Y382417D01*
X477600Y381917D01*
X477933Y381417D01*
X478333Y381083D01*
X478800Y381000D01*
X479267Y381167D01*
X479733Y381667D01*
G01X484767Y383917D02*
X484300Y384250D01*
X483900Y384333D01*
X483367Y384167D01*
X482967Y383833D01*
X482700Y383250D01*
X482633Y382667D01*
X482700Y382083D01*
X482967Y381583D01*
X483367Y381167D01*
X483900Y381000D01*
X484367Y381167D01*
X484767Y381500D01*
G01X488800Y384333D02*
Y381000D01*
G01Y385667D02*
X488667Y385750D01*
Y385917D01*
X488800Y386000D01*
X488933Y385917D01*
Y385750D01*
X488800Y385667D01*
G01X493500Y381000D02*
Y385250D01*
X493633Y385667D01*
X493900Y385917D01*
X494300Y386000D01*
X494700Y385833D01*
X494900Y385417D01*
G01X494100Y384000D02*
X492767D01*
G01X499000Y384333D02*
Y381000D01*
G01Y385667D02*
X498867Y385750D01*
Y385917D01*
X499000Y386000D01*
X499133Y385917D01*
Y385750D01*
X499000Y385667D01*
G01X503100Y383250D02*
X505233D01*
X505033Y383833D01*
X504700Y384167D01*
X504233Y384333D01*
X503767Y384250D01*
X503367Y384000D01*
X503100Y383417D01*
X502967Y382917D01*
Y382417D01*
X503100Y381917D01*
X503433Y381417D01*
X503833Y381083D01*
X504300Y381000D01*
X504767Y381167D01*
X505233Y381667D01*
G01X510400Y386000D02*
Y381000D01*
G01Y381750D02*
X510133Y381333D01*
X509733Y381083D01*
X509267Y381000D01*
X508733Y381167D01*
X508333Y381583D01*
X508067Y382083D01*
X508000Y382667D01*
X508067Y383250D01*
X508333Y383750D01*
X508733Y384167D01*
X509267Y384333D01*
X509733Y384250D01*
X510067Y384083D01*
X510400Y383750D01*
G01X519400Y381000D02*
X519000Y381083D01*
X518600Y381417D01*
X518333Y382000D01*
X518200Y382667D01*
X518333Y383333D01*
X518600Y383917D01*
X519000Y384250D01*
X519400Y384333D01*
X519800Y384250D01*
X520200Y383917D01*
X520467Y383333D01*
X520533Y382667D01*
X520467Y382000D01*
X520200Y381417D01*
X519800Y381083D01*
X519400Y381000D01*
G01X523367D02*
Y384333D01*
G01Y383500D02*
X523633Y383917D01*
X524033Y384250D01*
X524567Y384333D01*
X525033Y384250D01*
X525433Y383917D01*
X525633Y383333D01*
Y381000D01*
G01X534700Y386000D02*
Y381000D01*
G01X533767Y384333D02*
X535633D01*
G01X538667Y381000D02*
Y386000D01*
G01Y383583D02*
X539000Y384000D01*
X539333Y384250D01*
X539867Y384333D01*
X540267Y384250D01*
X540733Y383917D01*
X540933Y383417D01*
Y381000D01*
G01X543900Y383250D02*
X546033D01*
X545833Y383833D01*
X545500Y384167D01*
X545033Y384333D01*
X544567Y384250D01*
X544167Y384000D01*
X543900Y383417D01*
X543767Y382917D01*
Y382417D01*
X543900Y381917D01*
X544233Y381417D01*
X544633Y381083D01*
X545100Y381000D01*
X545567Y381167D01*
X546033Y381667D01*
G01X268100Y391500D02*
Y396500D01*
G01X270900D02*
Y391500D01*
G01Y394000D02*
X268100D01*
G01X274600Y391500D02*
X274200Y391583D01*
X273800Y391917D01*
X273533Y392500D01*
X273400Y393167D01*
X273533Y393833D01*
X273800Y394417D01*
X274200Y394750D01*
X274600Y394833D01*
X275000Y394750D01*
X275400Y394417D01*
X275667Y393833D01*
X275733Y393167D01*
X275667Y392500D01*
X275400Y391917D01*
X275000Y391583D01*
X274600Y391500D01*
G01X278033Y394833D02*
X278833Y391500D01*
X279700Y394833D01*
X280567Y391500D01*
X281367Y394833D01*
G01X283800Y393750D02*
X285933D01*
X285733Y394333D01*
X285400Y394667D01*
X284933Y394833D01*
X284467Y394750D01*
X284067Y394500D01*
X283800Y393917D01*
X283667Y393417D01*
Y392917D01*
X283800Y392417D01*
X284133Y391917D01*
X284533Y391583D01*
X285000Y391500D01*
X285467Y391667D01*
X285933Y392167D01*
G01X288700Y394833D02*
X289900Y391500D01*
X291100Y394833D01*
G01X294000Y393750D02*
X296133D01*
X295933Y394333D01*
X295600Y394667D01*
X295133Y394833D01*
X294667Y394750D01*
X294267Y394500D01*
X294000Y393917D01*
X293867Y393417D01*
Y392917D01*
X294000Y392417D01*
X294333Y391917D01*
X294733Y391583D01*
X295200Y391500D01*
X295667Y391667D01*
X296133Y392167D01*
G01X299167Y391500D02*
Y394833D01*
G01Y394167D02*
X299500Y394500D01*
X299833Y394750D01*
X300300Y394833D01*
X300633Y394750D01*
X301033Y394500D01*
G01X305067Y390583D02*
X305333Y391667D01*
G01X310300Y396500D02*
Y391500D01*
G01X309367Y394833D02*
X311233D01*
G01X314267Y391500D02*
Y396500D01*
G01Y394083D02*
X314600Y394500D01*
X314933Y394750D01*
X315467Y394833D01*
X315867Y394750D01*
X316333Y394417D01*
X316533Y393917D01*
Y391500D01*
G01X319500Y393750D02*
X321633D01*
X321433Y394333D01*
X321100Y394667D01*
X320633Y394833D01*
X320167Y394750D01*
X319767Y394500D01*
X319500Y393917D01*
X319367Y393417D01*
Y392917D01*
X319500Y392417D01*
X319833Y391917D01*
X320233Y391583D01*
X320700Y391500D01*
X321167Y391667D01*
X321633Y392167D01*
G01X330700Y396500D02*
Y391500D01*
G01X329767Y394833D02*
X331633D01*
G01X337000Y391500D02*
Y394833D01*
G01Y394250D02*
X336733Y394583D01*
X336333Y394750D01*
X335867Y394833D01*
X335400Y394667D01*
X335000Y394333D01*
X334733Y393833D01*
X334600Y393167D01*
X334733Y392500D01*
X335000Y392000D01*
X335400Y391667D01*
X335867Y391500D01*
X336333Y391583D01*
X336733Y391833D01*
X337000Y392167D01*
G01X339767Y391500D02*
Y394833D01*
G01Y394000D02*
X340033Y394417D01*
X340433Y394750D01*
X340967Y394833D01*
X341433Y394750D01*
X341833Y394417D01*
X342033Y393833D01*
Y391500D01*
G01X345067Y390250D02*
X345533Y389917D01*
X346067Y389833D01*
X346533Y389917D01*
X346933Y390333D01*
X347200Y390917D01*
Y394833D01*
G01Y394167D02*
X346933Y394500D01*
X346533Y394750D01*
X346067Y394833D01*
X345533Y394667D01*
X345200Y394333D01*
X344933Y393750D01*
X344800Y393167D01*
X344867Y392667D01*
X345133Y392083D01*
X345533Y391667D01*
X346067Y391500D01*
X346467Y391583D01*
X346933Y391917D01*
X347200Y392250D01*
G01X350100Y393750D02*
X352233D01*
X352033Y394333D01*
X351700Y394667D01*
X351233Y394833D01*
X350767Y394750D01*
X350367Y394500D01*
X350100Y393917D01*
X349967Y393417D01*
Y392917D01*
X350100Y392417D01*
X350433Y391917D01*
X350833Y391583D01*
X351300Y391500D01*
X351767Y391667D01*
X352233Y392167D01*
G01X355067Y391500D02*
Y394833D01*
G01Y394000D02*
X355333Y394417D01*
X355733Y394750D01*
X356267Y394833D01*
X356733Y394750D01*
X357133Y394417D01*
X357333Y393833D01*
Y391500D01*
G01X362367Y394417D02*
X361900Y394750D01*
X361500Y394833D01*
X360967Y394667D01*
X360567Y394333D01*
X360300Y393750D01*
X360233Y393167D01*
X360300Y392583D01*
X360567Y392083D01*
X360967Y391667D01*
X361500Y391500D01*
X361967Y391667D01*
X362367Y392000D01*
G01X365000Y390000D02*
X365400Y389833D01*
X365933Y390000D01*
X366267Y390333D01*
X366533Y390750D01*
X366933Y392083D01*
X367800Y394833D01*
G01X365667D02*
X366933Y392083D01*
G01X375600D02*
X375933Y391750D01*
X376400Y391500D01*
X376800D01*
X377200Y391667D01*
X377467Y391917D01*
X377600Y392250D01*
X377533Y392750D01*
X377267Y393000D01*
X376067Y393500D01*
X375800Y394083D01*
X375933Y394500D01*
X376200Y394750D01*
X376600Y394833D01*
X377000Y394750D01*
X377400Y394500D01*
G01X380567Y391500D02*
Y396500D01*
G01Y394083D02*
X380900Y394500D01*
X381233Y394750D01*
X381767Y394833D01*
X382167Y394750D01*
X382633Y394417D01*
X382833Y393917D01*
Y391500D01*
G01X386800D02*
X386400Y391583D01*
X386000Y391917D01*
X385733Y392500D01*
X385600Y393167D01*
X385733Y393833D01*
X386000Y394417D01*
X386400Y394750D01*
X386800Y394833D01*
X387200Y394750D01*
X387600Y394417D01*
X387867Y393833D01*
X387933Y393167D01*
X387867Y392500D01*
X387600Y391917D01*
X387200Y391583D01*
X386800Y391500D01*
G01X390767Y394833D02*
Y392500D01*
X391033Y391917D01*
X391433Y391583D01*
X391900Y391500D01*
X392367Y391583D01*
X392767Y391917D01*
X393033Y392500D01*
G01Y391500D02*
Y394833D01*
G01X397000Y391500D02*
Y396500D01*
G01X403300D02*
Y391500D01*
G01Y392250D02*
X403033Y391833D01*
X402633Y391583D01*
X402167Y391500D01*
X401633Y391667D01*
X401233Y392083D01*
X400967Y392583D01*
X400900Y393167D01*
X400967Y393750D01*
X401233Y394250D01*
X401633Y394667D01*
X402167Y394833D01*
X402633Y394750D01*
X402967Y394583D01*
X403300Y394250D01*
G01X411167Y391500D02*
Y394833D01*
G01Y394000D02*
X411433Y394417D01*
X411833Y394750D01*
X412367Y394833D01*
X412833Y394750D01*
X413233Y394417D01*
X413433Y393833D01*
Y391500D01*
G01X417400D02*
X417000Y391583D01*
X416600Y391917D01*
X416333Y392500D01*
X416200Y393167D01*
X416333Y393833D01*
X416600Y394417D01*
X417000Y394750D01*
X417400Y394833D01*
X417800Y394750D01*
X418200Y394417D01*
X418467Y393833D01*
X418533Y393167D01*
X418467Y392500D01*
X418200Y391917D01*
X417800Y391583D01*
X417400Y391500D01*
G01X422500Y396500D02*
Y391500D01*
G01X421567Y394833D02*
X423433D01*
G01X431767Y391500D02*
Y394833D01*
G01Y394167D02*
X432100Y394500D01*
X432433Y394750D01*
X432900Y394833D01*
X433233Y394750D01*
X433633Y394500D01*
G01X436800Y393750D02*
X438933D01*
X438733Y394333D01*
X438400Y394667D01*
X437933Y394833D01*
X437467Y394750D01*
X437067Y394500D01*
X436800Y393917D01*
X436667Y393417D01*
Y392917D01*
X436800Y392417D01*
X437133Y391917D01*
X437533Y391583D01*
X438000Y391500D01*
X438467Y391667D01*
X438933Y392167D01*
G01X444100Y396500D02*
Y391500D01*
G01Y392250D02*
X443833Y391833D01*
X443433Y391583D01*
X442967Y391500D01*
X442433Y391667D01*
X442033Y392083D01*
X441767Y392583D01*
X441700Y393167D01*
X441767Y393750D01*
X442033Y394250D01*
X442433Y394667D01*
X442967Y394833D01*
X443433Y394750D01*
X443767Y394583D01*
X444100Y394250D01*
G01X446867Y394833D02*
Y392500D01*
X447133Y391917D01*
X447533Y391583D01*
X448000Y391500D01*
X448467Y391583D01*
X448867Y391917D01*
X449133Y392500D01*
G01Y391500D02*
Y394833D01*
G01X454167Y394417D02*
X453700Y394750D01*
X453300Y394833D01*
X452767Y394667D01*
X452367Y394333D01*
X452100Y393750D01*
X452033Y393167D01*
X452100Y392583D01*
X452367Y392083D01*
X452767Y391667D01*
X453300Y391500D01*
X453767Y391667D01*
X454167Y392000D01*
G01X457200Y393750D02*
X459333D01*
X459133Y394333D01*
X458800Y394667D01*
X458333Y394833D01*
X457867Y394750D01*
X457467Y394500D01*
X457200Y393917D01*
X457067Y393417D01*
Y392917D01*
X457200Y392417D01*
X457533Y391917D01*
X457933Y391583D01*
X458400Y391500D01*
X458867Y391667D01*
X459333Y392167D01*
G01X468400Y396500D02*
Y391500D01*
G01X467467Y394833D02*
X469333D01*
G01X472367Y391500D02*
Y396500D01*
G01Y394083D02*
X472700Y394500D01*
X473033Y394750D01*
X473567Y394833D01*
X473967Y394750D01*
X474433Y394417D01*
X474633Y393917D01*
Y391500D01*
G01X477600Y393750D02*
X479733D01*
X479533Y394333D01*
X479200Y394667D01*
X478733Y394833D01*
X478267Y394750D01*
X477867Y394500D01*
X477600Y393917D01*
X477467Y393417D01*
Y392917D01*
X477600Y392417D01*
X477933Y391917D01*
X478333Y391583D01*
X478800Y391500D01*
X479267Y391667D01*
X479733Y392167D01*
G01X488800Y391500D02*
Y396500D01*
G01X495100Y391500D02*
Y394833D01*
G01Y394250D02*
X494833Y394583D01*
X494433Y394750D01*
X493967Y394833D01*
X493500Y394667D01*
X493100Y394333D01*
X492833Y393833D01*
X492700Y393167D01*
X492833Y392500D01*
X493100Y392000D01*
X493500Y391667D01*
X493967Y391500D01*
X494433Y391583D01*
X494833Y391833D01*
X495100Y392167D01*
G01X497867Y391500D02*
Y394833D01*
G01Y394000D02*
X498133Y394417D01*
X498533Y394750D01*
X499067Y394833D01*
X499533Y394750D01*
X499933Y394417D01*
X500133Y393833D01*
Y391500D01*
G01X505300Y396500D02*
Y391500D01*
G01Y392250D02*
X505033Y391833D01*
X504633Y391583D01*
X504167Y391500D01*
X503633Y391667D01*
X503233Y392083D01*
X502967Y392583D01*
X502900Y393167D01*
X502967Y393750D01*
X503233Y394250D01*
X503633Y394667D01*
X504167Y394833D01*
X504633Y394750D01*
X504967Y394583D01*
X505300Y394250D01*
G01X508000Y391333D02*
X510400Y396500D01*
G01X515367Y394417D02*
X514900Y394750D01*
X514500Y394833D01*
X513967Y394667D01*
X513567Y394333D01*
X513300Y393750D01*
X513233Y393167D01*
X513300Y392583D01*
X513567Y392083D01*
X513967Y391667D01*
X514500Y391500D01*
X514967Y391667D01*
X515367Y392000D01*
G01X519400Y391500D02*
X519000Y391583D01*
X518600Y391917D01*
X518333Y392500D01*
X518200Y393167D01*
X518333Y393833D01*
X518600Y394417D01*
X519000Y394750D01*
X519400Y394833D01*
X519800Y394750D01*
X520200Y394417D01*
X520467Y393833D01*
X520533Y393167D01*
X520467Y392500D01*
X520200Y391917D01*
X519800Y391583D01*
X519400Y391500D01*
G01X523367D02*
Y394833D01*
G01Y394000D02*
X523633Y394417D01*
X524033Y394750D01*
X524567Y394833D01*
X525033Y394750D01*
X525433Y394417D01*
X525633Y393833D01*
Y391500D01*
G01X530800Y396500D02*
Y391500D01*
G01Y392250D02*
X530533Y391833D01*
X530133Y391583D01*
X529667Y391500D01*
X529133Y391667D01*
X528733Y392083D01*
X528467Y392583D01*
X528400Y393167D01*
X528467Y393750D01*
X528733Y394250D01*
X529133Y394667D01*
X529667Y394833D01*
X530133Y394750D01*
X530467Y394583D01*
X530800Y394250D01*
G01X533567Y394833D02*
Y392500D01*
X533833Y391917D01*
X534233Y391583D01*
X534700Y391500D01*
X535167Y391583D01*
X535567Y391917D01*
X535833Y392500D01*
G01Y391500D02*
Y394833D01*
G01X540867Y394417D02*
X540400Y394750D01*
X540000Y394833D01*
X539467Y394667D01*
X539067Y394333D01*
X538800Y393750D01*
X538733Y393167D01*
X538800Y392583D01*
X539067Y392083D01*
X539467Y391667D01*
X540000Y391500D01*
X540467Y391667D01*
X540867Y392000D01*
G01X544900Y396500D02*
Y391500D01*
G01X543967Y394833D02*
X545833D01*
G01X550000Y391500D02*
X549600Y391583D01*
X549200Y391917D01*
X548933Y392500D01*
X548800Y393167D01*
X548933Y393833D01*
X549200Y394417D01*
X549600Y394750D01*
X550000Y394833D01*
X550400Y394750D01*
X550800Y394417D01*
X551067Y393833D01*
X551133Y393167D01*
X551067Y392500D01*
X550800Y391917D01*
X550400Y391583D01*
X550000Y391500D01*
G01X554167D02*
Y394833D01*
G01Y394167D02*
X554500Y394500D01*
X554833Y394750D01*
X555300Y394833D01*
X555633Y394750D01*
X556033Y394500D01*
G01X270700Y402000D02*
Y405333D01*
G01Y404750D02*
X270433Y405083D01*
X270033Y405250D01*
X269567Y405333D01*
X269100Y405167D01*
X268700Y404833D01*
X268433Y404333D01*
X268300Y403667D01*
X268433Y403000D01*
X268700Y402500D01*
X269100Y402167D01*
X269567Y402000D01*
X270033Y402083D01*
X270433Y402333D01*
X270700Y402667D01*
G01X275667Y404917D02*
X275200Y405250D01*
X274800Y405333D01*
X274267Y405167D01*
X273867Y404833D01*
X273600Y404250D01*
X273533Y403667D01*
X273600Y403083D01*
X273867Y402583D01*
X274267Y402167D01*
X274800Y402000D01*
X275267Y402167D01*
X275667Y402500D01*
G01X280767Y404917D02*
X280300Y405250D01*
X279900Y405333D01*
X279367Y405167D01*
X278967Y404833D01*
X278700Y404250D01*
X278633Y403667D01*
X278700Y403083D01*
X278967Y402583D01*
X279367Y402167D01*
X279900Y402000D01*
X280367Y402167D01*
X280767Y402500D01*
G01X283800Y404250D02*
X285933D01*
X285733Y404833D01*
X285400Y405167D01*
X284933Y405333D01*
X284467Y405250D01*
X284067Y405000D01*
X283800Y404417D01*
X283667Y403917D01*
Y403417D01*
X283800Y402917D01*
X284133Y402417D01*
X284533Y402083D01*
X285000Y402000D01*
X285467Y402167D01*
X285933Y402667D01*
G01X288700Y400333D02*
Y405333D01*
G01Y404583D02*
X289033Y405000D01*
X289367Y405250D01*
X289900Y405333D01*
X290367Y405250D01*
X290833Y404833D01*
X291033Y404250D01*
X291100Y403667D01*
X291033Y403083D01*
X290833Y402500D01*
X290433Y402167D01*
X289900Y402000D01*
X289433Y402083D01*
X288967Y402333D01*
X288700Y402667D01*
G01X295000Y407000D02*
Y402000D01*
G01X294067Y405333D02*
X295933D01*
G01X301300Y402000D02*
Y405333D01*
G01Y404750D02*
X301033Y405083D01*
X300633Y405250D01*
X300167Y405333D01*
X299700Y405167D01*
X299300Y404833D01*
X299033Y404333D01*
X298900Y403667D01*
X299033Y403000D01*
X299300Y402500D01*
X299700Y402167D01*
X300167Y402000D01*
X300633Y402083D01*
X301033Y402333D01*
X301300Y402667D01*
G01X304000Y402000D02*
Y407000D01*
G01Y404500D02*
X304333Y405000D01*
X304733Y405250D01*
X305133Y405333D01*
X305733Y405167D01*
X306133Y404833D01*
X306400Y404250D01*
Y403583D01*
X306267Y402917D01*
X306000Y402417D01*
X305533Y402083D01*
X305133Y402000D01*
X304733Y402083D01*
X304333Y402333D01*
X304000Y402750D01*
G01X310300Y402000D02*
Y407000D01*
G01X314400Y404250D02*
X316533D01*
X316333Y404833D01*
X316000Y405167D01*
X315533Y405333D01*
X315067Y405250D01*
X314667Y405000D01*
X314400Y404417D01*
X314267Y403917D01*
Y403417D01*
X314400Y402917D01*
X314733Y402417D01*
X315133Y402083D01*
X315600Y402000D01*
X316067Y402167D01*
X316533Y402667D01*
G01X320500Y401833D02*
X320367Y401917D01*
Y402083D01*
X320500Y402167D01*
X320633Y402083D01*
Y401917D01*
X320500Y401833D01*
G01X262500Y397000D02*
Y679000D01*
G01X269500Y417500D02*
Y412500D01*
G01X267967Y417500D02*
X271033D01*
G01X273467Y412500D02*
Y417500D01*
G01Y415083D02*
X273800Y415500D01*
X274133Y415750D01*
X274667Y415833D01*
X275067Y415750D01*
X275533Y415417D01*
X275733Y414917D01*
Y412500D01*
G01X278700Y414750D02*
X280833D01*
X280633Y415333D01*
X280300Y415667D01*
X279833Y415833D01*
X279367Y415750D01*
X278967Y415500D01*
X278700Y414917D01*
X278567Y414417D01*
Y413917D01*
X278700Y413417D01*
X279033Y412917D01*
X279433Y412583D01*
X279900Y412500D01*
X280367Y412667D01*
X280833Y413167D01*
G01X288700Y412500D02*
Y417500D01*
G01Y415000D02*
X289033Y415500D01*
X289433Y415750D01*
X289833Y415833D01*
X290433Y415667D01*
X290833Y415333D01*
X291100Y414750D01*
Y414083D01*
X290967Y413417D01*
X290700Y412917D01*
X290233Y412583D01*
X289833Y412500D01*
X289433Y412583D01*
X289033Y412833D01*
X288700Y413250D01*
G01X294067Y412500D02*
Y415833D01*
G01Y415167D02*
X294400Y415500D01*
X294733Y415750D01*
X295200Y415833D01*
X295533Y415750D01*
X295933Y415500D01*
G01X299100Y414750D02*
X301233D01*
X301033Y415333D01*
X300700Y415667D01*
X300233Y415833D01*
X299767Y415750D01*
X299367Y415500D01*
X299100Y414917D01*
X298967Y414417D01*
Y413917D01*
X299100Y413417D01*
X299433Y412917D01*
X299833Y412583D01*
X300300Y412500D01*
X300767Y412667D01*
X301233Y413167D01*
G01X306400Y412500D02*
Y415833D01*
G01Y415250D02*
X306133Y415583D01*
X305733Y415750D01*
X305267Y415833D01*
X304800Y415667D01*
X304400Y415333D01*
X304133Y414833D01*
X304000Y414167D01*
X304133Y413500D01*
X304400Y413000D01*
X304800Y412667D01*
X305267Y412500D01*
X305733Y412583D01*
X306133Y412833D01*
X306400Y413167D01*
G01X309167Y412500D02*
Y417500D01*
G01X311300Y415833D02*
X309167Y413917D01*
G01X310033Y414667D02*
X311433Y412500D01*
G01X315400D02*
X315000Y412583D01*
X314600Y412917D01*
X314333Y413500D01*
X314200Y414167D01*
X314333Y414833D01*
X314600Y415417D01*
X315000Y415750D01*
X315400Y415833D01*
X315800Y415750D01*
X316200Y415417D01*
X316467Y414833D01*
X316533Y414167D01*
X316467Y413500D01*
X316200Y412917D01*
X315800Y412583D01*
X315400Y412500D01*
G01X319367Y415833D02*
Y413500D01*
X319633Y412917D01*
X320033Y412583D01*
X320500Y412500D01*
X320967Y412583D01*
X321367Y412917D01*
X321633Y413500D01*
G01Y412500D02*
Y415833D01*
G01X325600Y417500D02*
Y412500D01*
G01X324667Y415833D02*
X326533D01*
G01X335800D02*
Y412500D01*
G01Y417167D02*
X335667Y417250D01*
Y417417D01*
X335800Y417500D01*
X335933Y417417D01*
Y417250D01*
X335800Y417167D01*
G01X339900Y413083D02*
X340233Y412750D01*
X340700Y412500D01*
X341100D01*
X341500Y412667D01*
X341767Y412917D01*
X341900Y413250D01*
X341833Y413750D01*
X341567Y414000D01*
X340367Y414500D01*
X340100Y415083D01*
X340233Y415500D01*
X340500Y415750D01*
X340900Y415833D01*
X341300Y415750D01*
X341700Y415500D01*
G01X349967Y412500D02*
Y415833D01*
G01Y415000D02*
X350233Y415417D01*
X350633Y415750D01*
X351167Y415833D01*
X351633Y415750D01*
X352033Y415417D01*
X352233Y414833D01*
Y412500D01*
G01X356200D02*
X355800Y412583D01*
X355400Y412917D01*
X355133Y413500D01*
X355000Y414167D01*
X355133Y414833D01*
X355400Y415417D01*
X355800Y415750D01*
X356200Y415833D01*
X356600Y415750D01*
X357000Y415417D01*
X357267Y414833D01*
X357333Y414167D01*
X357267Y413500D01*
X357000Y412917D01*
X356600Y412583D01*
X356200Y412500D01*
G01X361300Y417500D02*
Y412500D01*
G01X360367Y415833D02*
X362233D01*
G01X372700Y412500D02*
Y415833D01*
G01Y415250D02*
X372433Y415583D01*
X372033Y415750D01*
X371567Y415833D01*
X371100Y415667D01*
X370700Y415333D01*
X370433Y414833D01*
X370300Y414167D01*
X370433Y413500D01*
X370700Y413000D01*
X371100Y412667D01*
X371567Y412500D01*
X372033Y412583D01*
X372433Y412833D01*
X372700Y413167D01*
G01X376600Y412500D02*
Y417500D01*
G01X381700Y412500D02*
Y417500D01*
G01X386800Y412500D02*
X386400Y412583D01*
X386000Y412917D01*
X385733Y413500D01*
X385600Y414167D01*
X385733Y414833D01*
X386000Y415417D01*
X386400Y415750D01*
X386800Y415833D01*
X387200Y415750D01*
X387600Y415417D01*
X387867Y414833D01*
X387933Y414167D01*
X387867Y413500D01*
X387600Y412917D01*
X387200Y412583D01*
X386800Y412500D01*
G01X390233Y415833D02*
X391033Y412500D01*
X391900Y415833D01*
X392767Y412500D01*
X393567Y415833D01*
G01X396000Y414750D02*
X398133D01*
X397933Y415333D01*
X397600Y415667D01*
X397133Y415833D01*
X396667Y415750D01*
X396267Y415500D01*
X396000Y414917D01*
X395867Y414417D01*
Y413917D01*
X396000Y413417D01*
X396333Y412917D01*
X396733Y412583D01*
X397200Y412500D01*
X397667Y412667D01*
X398133Y413167D01*
G01X403300Y417500D02*
Y412500D01*
G01Y413250D02*
X403033Y412833D01*
X402633Y412583D01*
X402167Y412500D01*
X401633Y412667D01*
X401233Y413083D01*
X400967Y413583D01*
X400900Y414167D01*
X400967Y414750D01*
X401233Y415250D01*
X401633Y415667D01*
X402167Y415833D01*
X402633Y415750D01*
X402967Y415583D01*
X403300Y415250D01*
G01X407067Y411583D02*
X407333Y412667D01*
G01X421300Y412500D02*
Y417500D01*
G01Y415000D02*
X421633Y415500D01*
X422033Y415750D01*
X422433Y415833D01*
X423033Y415667D01*
X423433Y415333D01*
X423700Y414750D01*
Y414083D01*
X423567Y413417D01*
X423300Y412917D01*
X422833Y412583D01*
X422433Y412500D01*
X422033Y412583D01*
X421633Y412833D01*
X421300Y413250D01*
G01X426467Y415833D02*
Y413500D01*
X426733Y412917D01*
X427133Y412583D01*
X427600Y412500D01*
X428067Y412583D01*
X428467Y412917D01*
X428733Y413500D01*
G01Y412500D02*
Y415833D01*
G01X432700Y417500D02*
Y412500D01*
G01X431767Y415833D02*
X433633D01*
G01X444100Y412500D02*
Y415833D01*
G01Y415250D02*
X443833Y415583D01*
X443433Y415750D01*
X442967Y415833D01*
X442500Y415667D01*
X442100Y415333D01*
X441833Y414833D01*
X441700Y414167D01*
X441833Y413500D01*
X442100Y413000D01*
X442500Y412667D01*
X442967Y412500D01*
X443433Y412583D01*
X443833Y412833D01*
X444100Y413167D01*
G01X446867Y412500D02*
Y415833D01*
G01Y415000D02*
X447133Y415417D01*
X447533Y415750D01*
X448067Y415833D01*
X448533Y415750D01*
X448933Y415417D01*
X449133Y414833D01*
Y412500D01*
G01X451967D02*
Y415833D01*
G01Y415000D02*
X452233Y415417D01*
X452633Y415750D01*
X453167Y415833D01*
X453633Y415750D01*
X454033Y415417D01*
X454233Y414833D01*
Y412500D01*
G01X457067Y415833D02*
Y413500D01*
X457333Y412917D01*
X457733Y412583D01*
X458200Y412500D01*
X458667Y412583D01*
X459067Y412917D01*
X459333Y413500D01*
G01Y412500D02*
Y415833D01*
G01X464500Y412500D02*
Y415833D01*
G01Y415250D02*
X464233Y415583D01*
X463833Y415750D01*
X463367Y415833D01*
X462900Y415667D01*
X462500Y415333D01*
X462233Y414833D01*
X462100Y414167D01*
X462233Y413500D01*
X462500Y413000D01*
X462900Y412667D01*
X463367Y412500D01*
X463833Y412583D01*
X464233Y412833D01*
X464500Y413167D01*
G01X468400Y412500D02*
Y417500D01*
G01X477667Y412500D02*
Y415833D01*
G01Y415167D02*
X478000Y415500D01*
X478333Y415750D01*
X478800Y415833D01*
X479133Y415750D01*
X479533Y415500D01*
G01X483700Y415833D02*
Y412500D01*
G01Y417167D02*
X483567Y417250D01*
Y417417D01*
X483700Y417500D01*
X483833Y417417D01*
Y417250D01*
X483700Y417167D01*
G01X487667Y412500D02*
Y415833D01*
G01Y415000D02*
X487933Y415417D01*
X488333Y415750D01*
X488867Y415833D01*
X489333Y415750D01*
X489733Y415417D01*
X489933Y414833D01*
Y412500D01*
G01X492967Y411250D02*
X493433Y410917D01*
X493967Y410833D01*
X494433Y410917D01*
X494833Y411333D01*
X495100Y411917D01*
Y415833D01*
G01Y415167D02*
X494833Y415500D01*
X494433Y415750D01*
X493967Y415833D01*
X493433Y415667D01*
X493100Y415333D01*
X492833Y414750D01*
X492700Y414167D01*
X492767Y413667D01*
X493033Y413083D01*
X493433Y412667D01*
X493967Y412500D01*
X494367Y412583D01*
X494833Y412917D01*
X495100Y413250D01*
G01X504100Y417500D02*
Y412500D01*
G01X503167Y415833D02*
X505033D01*
G01X510400Y412500D02*
Y415833D01*
G01Y415250D02*
X510133Y415583D01*
X509733Y415750D01*
X509267Y415833D01*
X508800Y415667D01*
X508400Y415333D01*
X508133Y414833D01*
X508000Y414167D01*
X508133Y413500D01*
X508400Y413000D01*
X508800Y412667D01*
X509267Y412500D01*
X509733Y412583D01*
X510133Y412833D01*
X510400Y413167D01*
G01X513167Y412500D02*
Y415833D01*
G01Y415000D02*
X513433Y415417D01*
X513833Y415750D01*
X514367Y415833D01*
X514833Y415750D01*
X515233Y415417D01*
X515433Y414833D01*
Y412500D01*
G01X518467Y411250D02*
X518933Y410917D01*
X519467Y410833D01*
X519933Y410917D01*
X520333Y411333D01*
X520600Y411917D01*
Y415833D01*
G01Y415167D02*
X520333Y415500D01*
X519933Y415750D01*
X519467Y415833D01*
X518933Y415667D01*
X518600Y415333D01*
X518333Y414750D01*
X518200Y414167D01*
X518267Y413667D01*
X518533Y413083D01*
X518933Y412667D01*
X519467Y412500D01*
X519867Y412583D01*
X520333Y412917D01*
X520600Y413250D01*
G01X523500Y414750D02*
X525633D01*
X525433Y415333D01*
X525100Y415667D01*
X524633Y415833D01*
X524167Y415750D01*
X523767Y415500D01*
X523500Y414917D01*
X523367Y414417D01*
Y413917D01*
X523500Y413417D01*
X523833Y412917D01*
X524233Y412583D01*
X524700Y412500D01*
X525167Y412667D01*
X525633Y413167D01*
G01X528467Y412500D02*
Y415833D01*
G01Y415000D02*
X528733Y415417D01*
X529133Y415750D01*
X529667Y415833D01*
X530133Y415750D01*
X530533Y415417D01*
X530733Y414833D01*
Y412500D01*
G01X535767Y415417D02*
X535300Y415750D01*
X534900Y415833D01*
X534367Y415667D01*
X533967Y415333D01*
X533700Y414750D01*
X533633Y414167D01*
X533700Y413583D01*
X533967Y413083D01*
X534367Y412667D01*
X534900Y412500D01*
X535367Y412667D01*
X535767Y413000D01*
G01X538400Y411000D02*
X538800Y410833D01*
X539333Y411000D01*
X539667Y411333D01*
X539933Y411750D01*
X540333Y413083D01*
X541200Y415833D01*
G01X539067D02*
X540333Y413083D01*
G01X550000Y415833D02*
Y412500D01*
G01Y417167D02*
X549867Y417250D01*
Y417417D01*
X550000Y417500D01*
X550133Y417417D01*
Y417250D01*
X550000Y417167D01*
G01X554100Y413083D02*
X554433Y412750D01*
X554900Y412500D01*
X555300D01*
X555700Y412667D01*
X555967Y412917D01*
X556100Y413250D01*
X556033Y413750D01*
X555767Y414000D01*
X554567Y414500D01*
X554300Y415083D01*
X554433Y415500D01*
X554700Y415750D01*
X555100Y415833D01*
X555500Y415750D01*
X555900Y415500D01*
G01X272200Y437500D02*
Y432500D01*
G01Y433250D02*
X271933Y432833D01*
X271533Y432583D01*
X271067Y432500D01*
X270533Y432667D01*
X270133Y433083D01*
X269867Y433583D01*
X269800Y434167D01*
X269867Y434750D01*
X270133Y435250D01*
X270533Y435667D01*
X271067Y435833D01*
X271533Y435750D01*
X271867Y435583D01*
X272200Y435250D01*
G01X275100Y434750D02*
X277233D01*
X277033Y435333D01*
X276700Y435667D01*
X276233Y435833D01*
X275767Y435750D01*
X275367Y435500D01*
X275100Y434917D01*
X274967Y434417D01*
Y433917D01*
X275100Y433417D01*
X275433Y432917D01*
X275833Y432583D01*
X276300Y432500D01*
X276767Y432667D01*
X277233Y433167D01*
G01X280000Y430833D02*
Y435833D01*
G01Y435083D02*
X280333Y435500D01*
X280667Y435750D01*
X281200Y435833D01*
X281667Y435750D01*
X282133Y435333D01*
X282333Y434750D01*
X282400Y434167D01*
X282333Y433583D01*
X282133Y433000D01*
X281733Y432667D01*
X281200Y432500D01*
X280733Y432583D01*
X280267Y432833D01*
X280000Y433167D01*
G01X286300Y437500D02*
Y432500D01*
G01X285367Y435833D02*
X287233D01*
G01X290267Y432500D02*
Y437500D01*
G01Y435083D02*
X290600Y435500D01*
X290933Y435750D01*
X291467Y435833D01*
X291867Y435750D01*
X292333Y435417D01*
X292533Y434917D01*
Y432500D01*
G01X301600Y437500D02*
Y432500D01*
G01X300667Y435833D02*
X302533D01*
G01X306700Y432500D02*
X306300Y432583D01*
X305900Y432917D01*
X305633Y433500D01*
X305500Y434167D01*
X305633Y434833D01*
X305900Y435417D01*
X306300Y435750D01*
X306700Y435833D01*
X307100Y435750D01*
X307500Y435417D01*
X307767Y434833D01*
X307833Y434167D01*
X307767Y433500D01*
X307500Y432917D01*
X307100Y432583D01*
X306700Y432500D01*
G01X311800D02*
Y437500D01*
G01X315900Y434750D02*
X318033D01*
X317833Y435333D01*
X317500Y435667D01*
X317033Y435833D01*
X316567Y435750D01*
X316167Y435500D01*
X315900Y434917D01*
X315767Y434417D01*
Y433917D01*
X315900Y433417D01*
X316233Y432917D01*
X316633Y432583D01*
X317100Y432500D01*
X317567Y432667D01*
X318033Y433167D01*
G01X321067Y432500D02*
Y435833D01*
G01Y435167D02*
X321400Y435500D01*
X321733Y435750D01*
X322200Y435833D01*
X322533Y435750D01*
X322933Y435500D01*
G01X328300Y432500D02*
Y435833D01*
G01Y435250D02*
X328033Y435583D01*
X327633Y435750D01*
X327167Y435833D01*
X326700Y435667D01*
X326300Y435333D01*
X326033Y434833D01*
X325900Y434167D01*
X326033Y433500D01*
X326300Y433000D01*
X326700Y432667D01*
X327167Y432500D01*
X327633Y432583D01*
X328033Y432833D01*
X328300Y433167D01*
G01X331067Y432500D02*
Y435833D01*
G01Y435000D02*
X331333Y435417D01*
X331733Y435750D01*
X332267Y435833D01*
X332733Y435750D01*
X333133Y435417D01*
X333333Y434833D01*
Y432500D01*
G01X338367Y435417D02*
X337900Y435750D01*
X337500Y435833D01*
X336967Y435667D01*
X336567Y435333D01*
X336300Y434750D01*
X336233Y434167D01*
X336300Y433583D01*
X336567Y433083D01*
X336967Y432667D01*
X337500Y432500D01*
X337967Y432667D01*
X338367Y433000D01*
G01X341400Y434750D02*
X343533D01*
X343333Y435333D01*
X343000Y435667D01*
X342533Y435833D01*
X342067Y435750D01*
X341667Y435500D01*
X341400Y434917D01*
X341267Y434417D01*
Y433917D01*
X341400Y433417D01*
X341733Y432917D01*
X342133Y432583D01*
X342600Y432500D01*
X343067Y432667D01*
X343533Y433167D01*
G01X270600Y453500D02*
Y458500D01*
G01X273400D02*
Y453500D01*
G01Y456000D02*
X270600D01*
G01X277100Y453500D02*
X276700Y453583D01*
X276300Y453917D01*
X276033Y454500D01*
X275900Y455167D01*
X276033Y455833D01*
X276300Y456417D01*
X276700Y456750D01*
X277100Y456833D01*
X277500Y456750D01*
X277900Y456417D01*
X278167Y455833D01*
X278233Y455167D01*
X278167Y454500D01*
X277900Y453917D01*
X277500Y453583D01*
X277100Y453500D01*
G01X282200D02*
Y458500D01*
G01X286300Y455750D02*
X288433D01*
X288233Y456333D01*
X287900Y456667D01*
X287433Y456833D01*
X286967Y456750D01*
X286567Y456500D01*
X286300Y455917D01*
X286167Y455417D01*
Y454917D01*
X286300Y454417D01*
X286633Y453917D01*
X287033Y453583D01*
X287500Y453500D01*
X287967Y453667D01*
X288433Y454167D01*
G01X295500Y458500D02*
X296433Y453500D01*
X297500Y458500D01*
X298567Y453500D01*
X299500Y458500D01*
G01X303800Y453500D02*
Y456833D01*
G01Y456250D02*
X303533Y456583D01*
X303133Y456750D01*
X302667Y456833D01*
X302200Y456667D01*
X301800Y456333D01*
X301533Y455833D01*
X301400Y455167D01*
X301533Y454500D01*
X301800Y454000D01*
X302200Y453667D01*
X302667Y453500D01*
X303133Y453583D01*
X303533Y453833D01*
X303800Y454167D01*
G01X307700Y453500D02*
Y458500D01*
G01X312800Y453500D02*
Y458500D01*
G01X321667Y453500D02*
Y458500D01*
X323333D01*
X323867Y458250D01*
X324200Y457917D01*
X324333Y457250D01*
X324200Y456583D01*
X323800Y456167D01*
X323333Y455917D01*
X321667D01*
G01X323333D02*
X324333Y453500D01*
G01X328100D02*
X327700Y453583D01*
X327300Y453917D01*
X327033Y454500D01*
X326900Y455167D01*
X327033Y455833D01*
X327300Y456417D01*
X327700Y456750D01*
X328100Y456833D01*
X328500Y456750D01*
X328900Y456417D01*
X329167Y455833D01*
X329233Y455167D01*
X329167Y454500D01*
X328900Y453917D01*
X328500Y453583D01*
X328100Y453500D01*
G01X332067Y456833D02*
Y454500D01*
X332333Y453917D01*
X332733Y453583D01*
X333200Y453500D01*
X333667Y453583D01*
X334067Y453917D01*
X334333Y454500D01*
G01Y453500D02*
Y456833D01*
G01X337367Y452250D02*
X337833Y451917D01*
X338367Y451833D01*
X338833Y451917D01*
X339233Y452333D01*
X339500Y452917D01*
Y456833D01*
G01Y456167D02*
X339233Y456500D01*
X338833Y456750D01*
X338367Y456833D01*
X337833Y456667D01*
X337500Y456333D01*
X337233Y455750D01*
X337100Y455167D01*
X337167Y454667D01*
X337433Y454083D01*
X337833Y453667D01*
X338367Y453500D01*
X338767Y453583D01*
X339233Y453917D01*
X339500Y454250D01*
G01X342267Y453500D02*
Y458500D01*
G01Y456083D02*
X342600Y456500D01*
X342933Y456750D01*
X343467Y456833D01*
X343867Y456750D01*
X344333Y456417D01*
X344533Y455917D01*
Y453500D01*
G01X347367D02*
Y456833D01*
G01Y456000D02*
X347633Y456417D01*
X348033Y456750D01*
X348567Y456833D01*
X349033Y456750D01*
X349433Y456417D01*
X349633Y455833D01*
Y453500D01*
G01X352600Y455750D02*
X354733D01*
X354533Y456333D01*
X354200Y456667D01*
X353733Y456833D01*
X353267Y456750D01*
X352867Y456500D01*
X352600Y455917D01*
X352467Y455417D01*
Y454917D01*
X352600Y454417D01*
X352933Y453917D01*
X353333Y453583D01*
X353800Y453500D01*
X354267Y453667D01*
X354733Y454167D01*
G01X357700Y454083D02*
X358033Y453750D01*
X358500Y453500D01*
X358900D01*
X359300Y453667D01*
X359567Y453917D01*
X359700Y454250D01*
X359633Y454750D01*
X359367Y455000D01*
X358167Y455500D01*
X357900Y456083D01*
X358033Y456500D01*
X358300Y456750D01*
X358700Y456833D01*
X359100Y456750D01*
X359500Y456500D01*
G01X362800Y454083D02*
X363133Y453750D01*
X363600Y453500D01*
X364000D01*
X364400Y453667D01*
X364667Y453917D01*
X364800Y454250D01*
X364733Y454750D01*
X364467Y455000D01*
X363267Y455500D01*
X363000Y456083D01*
X363133Y456500D01*
X363400Y456750D01*
X363800Y456833D01*
X364200Y456750D01*
X364600Y456500D01*
G01X272000Y470000D02*
X271467Y470083D01*
X271000Y470417D01*
X270600Y470917D01*
X270333Y471500D01*
X270200Y472167D01*
Y472833D01*
X270333Y473500D01*
X270600Y474083D01*
X271000Y474583D01*
X271467Y474917D01*
X272000Y475000D01*
X272533Y474917D01*
X273000Y474583D01*
X273400Y474083D01*
X273667Y473500D01*
X273800Y472833D01*
Y472167D01*
X273667Y471500D01*
X273400Y470917D01*
X273000Y470417D01*
X272533Y470083D01*
X272000Y470000D01*
G01X277100Y475000D02*
Y470000D01*
G01X276167Y473333D02*
X278033D01*
G01X281067Y470000D02*
Y475000D01*
G01Y472583D02*
X281400Y473000D01*
X281733Y473250D01*
X282267Y473333D01*
X282667Y473250D01*
X283133Y472917D01*
X283333Y472417D01*
Y470000D01*
G01X286300Y472250D02*
X288433D01*
X288233Y472833D01*
X287900Y473167D01*
X287433Y473333D01*
X286967Y473250D01*
X286567Y473000D01*
X286300Y472417D01*
X286167Y471917D01*
Y471417D01*
X286300Y470917D01*
X286633Y470417D01*
X287033Y470083D01*
X287500Y470000D01*
X287967Y470167D01*
X288433Y470667D01*
G01X291467Y470000D02*
Y473333D01*
G01Y472667D02*
X291800Y473000D01*
X292133Y473250D01*
X292600Y473333D01*
X292933Y473250D01*
X293333Y473000D01*
G01X296500Y470583D02*
X296833Y470250D01*
X297300Y470000D01*
X297700D01*
X298100Y470167D01*
X298367Y470417D01*
X298500Y470750D01*
X298433Y471250D01*
X298167Y471500D01*
X296967Y472000D01*
X296700Y472583D01*
X296833Y473000D01*
X297100Y473250D01*
X297500Y473333D01*
X297900Y473250D01*
X298300Y473000D01*
G01X307367Y468333D02*
X306700Y469167D01*
X306367Y470000D01*
Y473333D01*
X306700Y474167D01*
X307367Y475000D01*
G01X312800Y470000D02*
Y475000D01*
G01X317900Y473333D02*
Y470000D01*
G01Y474667D02*
X317767Y474750D01*
Y474917D01*
X317900Y475000D01*
X318033Y474917D01*
Y474750D01*
X317900Y474667D01*
G01X321867Y470000D02*
Y475000D01*
G01X324000Y473333D02*
X321867Y471417D01*
G01X322733Y472167D02*
X324133Y470000D01*
G01X327100Y472250D02*
X329233D01*
X329033Y472833D01*
X328700Y473167D01*
X328233Y473333D01*
X327767Y473250D01*
X327367Y473000D01*
X327100Y472417D01*
X326967Y471917D01*
Y471417D01*
X327100Y470917D01*
X327433Y470417D01*
X327833Y470083D01*
X328300Y470000D01*
X328767Y470167D01*
X329233Y470667D01*
G01X337300Y472250D02*
X339433D01*
X339233Y472833D01*
X338900Y473167D01*
X338433Y473333D01*
X337967Y473250D01*
X337567Y473000D01*
X337300Y472417D01*
X337167Y471917D01*
Y471417D01*
X337300Y470917D01*
X337633Y470417D01*
X338033Y470083D01*
X338500Y470000D01*
X338967Y470167D01*
X339433Y470667D01*
G01X343400Y470000D02*
Y475000D01*
G01X348500Y470000D02*
Y475000D01*
G01X353600Y473333D02*
Y470000D01*
G01Y474667D02*
X353467Y474750D01*
Y474917D01*
X353600Y475000D01*
X353733Y474917D01*
Y474750D01*
X353600Y474667D01*
G01X357500Y468333D02*
Y473333D01*
G01Y472583D02*
X357833Y473000D01*
X358167Y473250D01*
X358700Y473333D01*
X359167Y473250D01*
X359633Y472833D01*
X359833Y472250D01*
X359900Y471667D01*
X359833Y471083D01*
X359633Y470500D01*
X359233Y470167D01*
X358700Y470000D01*
X358233Y470083D01*
X357767Y470333D01*
X357500Y470667D01*
G01X362800Y470583D02*
X363133Y470250D01*
X363600Y470000D01*
X364000D01*
X364400Y470167D01*
X364667Y470417D01*
X364800Y470750D01*
X364733Y471250D01*
X364467Y471500D01*
X363267Y472000D01*
X363000Y472583D01*
X363133Y473000D01*
X363400Y473250D01*
X363800Y473333D01*
X364200Y473250D01*
X364600Y473000D01*
G01X367900Y472250D02*
X370033D01*
X369833Y472833D01*
X369500Y473167D01*
X369033Y473333D01*
X368567Y473250D01*
X368167Y473000D01*
X367900Y472417D01*
X367767Y471917D01*
Y471417D01*
X367900Y470917D01*
X368233Y470417D01*
X368633Y470083D01*
X369100Y470000D01*
X369567Y470167D01*
X370033Y470667D01*
G01X380300Y470000D02*
Y473333D01*
G01Y472750D02*
X380033Y473083D01*
X379633Y473250D01*
X379167Y473333D01*
X378700Y473167D01*
X378300Y472833D01*
X378033Y472333D01*
X377900Y471667D01*
X378033Y471000D01*
X378300Y470500D01*
X378700Y470167D01*
X379167Y470000D01*
X379633Y470083D01*
X380033Y470333D01*
X380300Y470667D01*
G01X383067Y470000D02*
Y473333D01*
G01Y472500D02*
X383333Y472917D01*
X383733Y473250D01*
X384267Y473333D01*
X384733Y473250D01*
X385133Y472917D01*
X385333Y472333D01*
Y470000D01*
G01X390500Y475000D02*
Y470000D01*
G01Y470750D02*
X390233Y470333D01*
X389833Y470083D01*
X389367Y470000D01*
X388833Y470167D01*
X388433Y470583D01*
X388167Y471083D01*
X388100Y471667D01*
X388167Y472250D01*
X388433Y472750D01*
X388833Y473167D01*
X389367Y473333D01*
X389833Y473250D01*
X390167Y473083D01*
X390500Y472750D01*
G01X399500Y470000D02*
X399100Y470083D01*
X398700Y470417D01*
X398433Y471000D01*
X398300Y471667D01*
X398433Y472333D01*
X398700Y472917D01*
X399100Y473250D01*
X399500Y473333D01*
X399900Y473250D01*
X400300Y472917D01*
X400567Y472333D01*
X400633Y471667D01*
X400567Y471000D01*
X400300Y470417D01*
X399900Y470083D01*
X399500Y470000D01*
G01X404600Y475000D02*
Y470000D01*
G01X403667Y473333D02*
X405533D01*
G01X408567Y470000D02*
Y475000D01*
G01Y472583D02*
X408900Y473000D01*
X409233Y473250D01*
X409767Y473333D01*
X410167Y473250D01*
X410633Y472917D01*
X410833Y472417D01*
Y470000D01*
G01X413800Y472250D02*
X415933D01*
X415733Y472833D01*
X415400Y473167D01*
X414933Y473333D01*
X414467Y473250D01*
X414067Y473000D01*
X413800Y472417D01*
X413667Y471917D01*
Y471417D01*
X413800Y470917D01*
X414133Y470417D01*
X414533Y470083D01*
X415000Y470000D01*
X415467Y470167D01*
X415933Y470667D01*
G01X418967Y470000D02*
Y473333D01*
G01Y472667D02*
X419300Y473000D01*
X419633Y473250D01*
X420100Y473333D01*
X420433Y473250D01*
X420833Y473000D01*
G01X424000Y470583D02*
X424333Y470250D01*
X424800Y470000D01*
X425200D01*
X425600Y470167D01*
X425867Y470417D01*
X426000Y470750D01*
X425933Y471250D01*
X425667Y471500D01*
X424467Y472000D01*
X424200Y472583D01*
X424333Y473000D01*
X424600Y473250D01*
X425000Y473333D01*
X425400Y473250D01*
X425800Y473000D01*
G01X430433Y468333D02*
X431100Y469167D01*
X431433Y470000D01*
Y473333D01*
X431100Y474167D01*
X430433Y475000D01*
G01X270667Y485000D02*
Y490000D01*
X272267D01*
X272800Y489750D01*
X273200Y489167D01*
X273333Y488500D01*
X273200Y487833D01*
X272867Y487333D01*
X272267Y487083D01*
X270667D01*
G01X277100Y490000D02*
Y485000D01*
G01X275567Y490000D02*
X278633D01*
G01X280800Y485000D02*
Y490000D01*
G01X283600D02*
Y485000D01*
G01Y487500D02*
X280800D01*
G01X286100Y484833D02*
X288500Y490000D01*
G01X290867Y485000D02*
Y490000D01*
X293933Y485000D01*
Y490000D01*
G01X296167Y485000D02*
Y490000D01*
X297767D01*
X298300Y489750D01*
X298700Y489167D01*
X298833Y488500D01*
X298700Y487833D01*
X298367Y487333D01*
X297767Y487083D01*
X296167D01*
G01X302600Y490000D02*
Y485000D01*
G01X301067Y490000D02*
X304133D01*
G01X306300Y485000D02*
Y490000D01*
G01X309100D02*
Y485000D01*
G01Y487500D02*
X306300D01*
G01X316567Y485000D02*
X319233Y486667D01*
X316567Y488333D01*
G01X322133Y485917D02*
X323867D01*
G01Y487417D02*
X322133D01*
G01X326633Y485750D02*
X327033Y485333D01*
X327500Y485083D01*
X328100Y485000D01*
X328700Y485167D01*
X329167Y485500D01*
X329500Y486083D01*
X329567Y486750D01*
X329433Y487417D01*
X329100Y487833D01*
X328633Y488167D01*
X328167Y488250D01*
X327700Y488167D01*
X327100Y487833D01*
X327300Y490000D01*
X329100D01*
G01X336300Y485000D02*
Y488333D01*
G01Y487417D02*
X336500Y487833D01*
X336833Y488167D01*
X337300Y488333D01*
X337767Y488167D01*
X338100Y487833D01*
X338300Y487417D01*
Y485000D01*
G01Y487417D02*
X338500Y487833D01*
X338833Y488167D01*
X339300Y488333D01*
X339767Y488167D01*
X340100Y487833D01*
X340300Y487333D01*
Y485000D01*
G01X341400D02*
Y488333D01*
G01Y487417D02*
X341600Y487833D01*
X341933Y488167D01*
X342400Y488333D01*
X342867Y488167D01*
X343200Y487833D01*
X343400Y487417D01*
Y485000D01*
G01Y487417D02*
X343600Y487833D01*
X343933Y488167D01*
X344400Y488333D01*
X344867Y488167D01*
X345200Y487833D01*
X345400Y487333D01*
Y485000D01*
G01X270467Y498500D02*
Y503500D01*
X273533Y498500D01*
Y503500D01*
G01X275767Y498500D02*
Y503500D01*
X277367D01*
X277900Y503250D01*
X278300Y502667D01*
X278433Y502000D01*
X278300Y501333D01*
X277967Y500833D01*
X277367Y500583D01*
X275767D01*
G01X282200Y503500D02*
Y498500D01*
G01X280667Y503500D02*
X283733D01*
G01X285900Y498500D02*
Y503500D01*
G01X288700D02*
Y498500D01*
G01Y501000D02*
X285900D01*
G01X296100Y499167D02*
X296633Y498750D01*
X297233Y498500D01*
X297767D01*
X298300Y498750D01*
X298700Y499167D01*
X298900Y499750D01*
X298767Y500333D01*
X298433Y500833D01*
X297833Y501167D01*
X297033Y501333D01*
X296567Y501667D01*
X296367Y502250D01*
X296500Y502833D01*
X296833Y503250D01*
X297300Y503500D01*
X297767D01*
X298233Y503333D01*
X298633Y502917D01*
G01X302600Y501833D02*
Y498500D01*
G01Y503167D02*
X302467Y503250D01*
Y503417D01*
X302600Y503500D01*
X302733Y503417D01*
Y503250D01*
X302600Y503167D01*
G01X306700Y501833D02*
X308700D01*
X306700Y498500D01*
X308700D01*
G01X311800Y500750D02*
X313933D01*
X313733Y501333D01*
X313400Y501667D01*
X312933Y501833D01*
X312467Y501750D01*
X312067Y501500D01*
X311800Y500917D01*
X311667Y500417D01*
Y499917D01*
X311800Y499417D01*
X312133Y498917D01*
X312533Y498583D01*
X313000Y498500D01*
X313467Y498667D01*
X313933Y499167D01*
G01X321533Y499500D02*
X321933Y498917D01*
X322467Y498583D01*
X323067Y498500D01*
X323600Y498583D01*
X324133Y499000D01*
X324467Y499500D01*
X324533Y500000D01*
X324400Y500583D01*
X323933Y501000D01*
X323467Y501167D01*
X322867D01*
G01X323467D02*
X323867Y501417D01*
X324200Y501833D01*
X324333Y502333D01*
X324200Y502833D01*
X323867Y503250D01*
X323267Y503500D01*
X322667Y503417D01*
X322067Y503083D01*
G01X328100Y498333D02*
X327967Y498417D01*
Y498583D01*
X328100Y498667D01*
X328233Y498583D01*
Y498417D01*
X328100Y498333D01*
G01X331733Y499250D02*
X332133Y498833D01*
X332600Y498583D01*
X333200Y498500D01*
X333800Y498667D01*
X334267Y499000D01*
X334600Y499583D01*
X334667Y500250D01*
X334533Y500917D01*
X334200Y501333D01*
X333733Y501667D01*
X333267Y501750D01*
X332800Y501667D01*
X332200Y501333D01*
X332400Y503500D01*
X334200D01*
G01X336833Y499250D02*
X337233Y498833D01*
X337700Y498583D01*
X338300Y498500D01*
X338900Y498667D01*
X339367Y499000D01*
X339700Y499583D01*
X339767Y500250D01*
X339633Y500917D01*
X339300Y501333D01*
X338833Y501667D01*
X338367Y501750D01*
X337900Y501667D01*
X337300Y501333D01*
X337500Y503500D01*
X339300D01*
G01X341400Y498500D02*
Y501833D01*
G01Y500917D02*
X341600Y501333D01*
X341933Y501667D01*
X342400Y501833D01*
X342867Y501667D01*
X343200Y501333D01*
X343400Y500917D01*
Y498500D01*
G01Y500917D02*
X343600Y501333D01*
X343933Y501667D01*
X344400Y501833D01*
X344867Y501667D01*
X345200Y501333D01*
X345400Y500833D01*
Y498500D01*
G01X346500D02*
Y501833D01*
G01Y500917D02*
X346700Y501333D01*
X347033Y501667D01*
X347500Y501833D01*
X347967Y501667D01*
X348300Y501333D01*
X348500Y500917D01*
Y498500D01*
G01Y500917D02*
X348700Y501333D01*
X349033Y501667D01*
X349500Y501833D01*
X349967Y501667D01*
X350300Y501333D01*
X350500Y500833D01*
Y498500D01*
G01X270467Y513500D02*
Y518500D01*
X273533Y513500D01*
Y518500D01*
G01X275767Y513500D02*
Y518500D01*
X277367D01*
X277900Y518250D01*
X278300Y517667D01*
X278433Y517000D01*
X278300Y516333D01*
X277967Y515833D01*
X277367Y515583D01*
X275767D01*
G01X282200Y518500D02*
Y513500D01*
G01X280667Y518500D02*
X283733D01*
G01X285900Y513500D02*
Y518500D01*
G01X288700D02*
Y513500D01*
G01Y516000D02*
X285900D01*
G01X296100Y514167D02*
X296633Y513750D01*
X297233Y513500D01*
X297767D01*
X298300Y513750D01*
X298700Y514167D01*
X298900Y514750D01*
X298767Y515333D01*
X298433Y515833D01*
X297833Y516167D01*
X297033Y516333D01*
X296567Y516667D01*
X296367Y517250D01*
X296500Y517833D01*
X296833Y518250D01*
X297300Y518500D01*
X297767D01*
X298233Y518333D01*
X298633Y517917D01*
G01X302600Y516833D02*
Y513500D01*
G01Y518167D02*
X302467Y518250D01*
Y518417D01*
X302600Y518500D01*
X302733Y518417D01*
Y518250D01*
X302600Y518167D01*
G01X306700Y516833D02*
X308700D01*
X306700Y513500D01*
X308700D01*
G01X311800Y515750D02*
X313933D01*
X313733Y516333D01*
X313400Y516667D01*
X312933Y516833D01*
X312467Y516750D01*
X312067Y516500D01*
X311800Y515917D01*
X311667Y515417D01*
Y514917D01*
X311800Y514417D01*
X312133Y513917D01*
X312533Y513583D01*
X313000Y513500D01*
X313467Y513667D01*
X313933Y514167D01*
G01X319233Y513500D02*
X316567Y515167D01*
X319233Y516833D01*
G01X326633Y514250D02*
X327033Y513833D01*
X327500Y513583D01*
X328100Y513500D01*
X328700Y513667D01*
X329167Y514000D01*
X329500Y514583D01*
X329567Y515250D01*
X329433Y515917D01*
X329100Y516333D01*
X328633Y516667D01*
X328167Y516750D01*
X327700Y516667D01*
X327100Y516333D01*
X327300Y518500D01*
X329100D01*
G01X331200Y513500D02*
Y516833D01*
G01Y515917D02*
X331400Y516333D01*
X331733Y516667D01*
X332200Y516833D01*
X332667Y516667D01*
X333000Y516333D01*
X333200Y515917D01*
Y513500D01*
G01Y515917D02*
X333400Y516333D01*
X333733Y516667D01*
X334200Y516833D01*
X334667Y516667D01*
X335000Y516333D01*
X335200Y515833D01*
Y513500D01*
G01X336300D02*
Y516833D01*
G01Y515917D02*
X336500Y516333D01*
X336833Y516667D01*
X337300Y516833D01*
X337767Y516667D01*
X338100Y516333D01*
X338300Y515917D01*
Y513500D01*
G01Y515917D02*
X338500Y516333D01*
X338833Y516667D01*
X339300Y516833D01*
X339767Y516667D01*
X340100Y516333D01*
X340300Y515833D01*
Y513500D01*
G01X262500Y479000D02*
X694500D01*
G01X262500Y494000D02*
X694500D01*
G01X262500Y509000D02*
X694500D01*
G01X262500Y524000D02*
X694500D01*
G01X270333Y588500D02*
X272000Y593500D01*
X273667Y588500D01*
G01X273067Y590250D02*
X270933D01*
G01X275967Y588500D02*
Y591833D01*
G01Y591000D02*
X276233Y591417D01*
X276633Y591750D01*
X277167Y591833D01*
X277633Y591750D01*
X278033Y591417D01*
X278233Y590833D01*
Y588500D01*
G01X280800Y587000D02*
X281200Y586833D01*
X281733Y587000D01*
X282067Y587333D01*
X282333Y587750D01*
X282733Y589083D01*
X283600Y591833D01*
G01X281467D02*
X282733Y589083D01*
G01X291267Y588500D02*
Y593500D01*
G01Y591083D02*
X291600Y591500D01*
X291933Y591750D01*
X292467Y591833D01*
X292867Y591750D01*
X293333Y591417D01*
X293533Y590917D01*
Y588500D01*
G01X297500D02*
X297100Y588583D01*
X296700Y588917D01*
X296433Y589500D01*
X296300Y590167D01*
X296433Y590833D01*
X296700Y591417D01*
X297100Y591750D01*
X297500Y591833D01*
X297900Y591750D01*
X298300Y591417D01*
X298567Y590833D01*
X298633Y590167D01*
X298567Y589500D01*
X298300Y588917D01*
X297900Y588583D01*
X297500Y588500D01*
G01X302600D02*
Y593500D01*
G01X306700Y590750D02*
X308833D01*
X308633Y591333D01*
X308300Y591667D01*
X307833Y591833D01*
X307367Y591750D01*
X306967Y591500D01*
X306700Y590917D01*
X306567Y590417D01*
Y589917D01*
X306700Y589417D01*
X307033Y588917D01*
X307433Y588583D01*
X307900Y588500D01*
X308367Y588667D01*
X308833Y589167D01*
G01X317900Y593500D02*
Y588500D01*
G01X316967Y591833D02*
X318833D01*
G01X323000Y588500D02*
X322600Y588583D01*
X322200Y588917D01*
X321933Y589500D01*
X321800Y590167D01*
X321933Y590833D01*
X322200Y591417D01*
X322600Y591750D01*
X323000Y591833D01*
X323400Y591750D01*
X323800Y591417D01*
X324067Y590833D01*
X324133Y590167D01*
X324067Y589500D01*
X323800Y588917D01*
X323400Y588583D01*
X323000Y588500D01*
G01X332067D02*
Y593500D01*
G01Y591083D02*
X332400Y591500D01*
X332733Y591750D01*
X333267Y591833D01*
X333667Y591750D01*
X334133Y591417D01*
X334333Y590917D01*
Y588500D01*
G01X338300D02*
X337900Y588583D01*
X337500Y588917D01*
X337233Y589500D01*
X337100Y590167D01*
X337233Y590833D01*
X337500Y591417D01*
X337900Y591750D01*
X338300Y591833D01*
X338700Y591750D01*
X339100Y591417D01*
X339367Y590833D01*
X339433Y590167D01*
X339367Y589500D01*
X339100Y588917D01*
X338700Y588583D01*
X338300Y588500D01*
G01X343400D02*
Y593500D01*
G01X347500Y590750D02*
X349633D01*
X349433Y591333D01*
X349100Y591667D01*
X348633Y591833D01*
X348167Y591750D01*
X347767Y591500D01*
X347500Y590917D01*
X347367Y590417D01*
Y589917D01*
X347500Y589417D01*
X347833Y588917D01*
X348233Y588583D01*
X348700Y588500D01*
X349167Y588667D01*
X349633Y589167D01*
G01X270533Y535000D02*
Y531417D01*
X270800Y530667D01*
X271333Y530167D01*
X272000Y530000D01*
X272667Y530167D01*
X273200Y530667D01*
X273467Y531417D01*
Y535000D01*
G01X275967Y530000D02*
Y533333D01*
G01Y532500D02*
X276233Y532917D01*
X276633Y533250D01*
X277167Y533333D01*
X277633Y533250D01*
X278033Y532917D01*
X278233Y532333D01*
Y530000D01*
G01X281333Y531667D02*
X283067D01*
G01X286100Y528333D02*
Y533333D01*
G01Y532583D02*
X286433Y533000D01*
X286767Y533250D01*
X287300Y533333D01*
X287767Y533250D01*
X288233Y532833D01*
X288433Y532250D01*
X288500Y531667D01*
X288433Y531083D01*
X288233Y530500D01*
X287833Y530167D01*
X287300Y530000D01*
X286833Y530083D01*
X286367Y530333D01*
X286100Y530667D01*
G01X292400Y530000D02*
Y535000D01*
G01X296367Y533333D02*
Y531000D01*
X296633Y530417D01*
X297033Y530083D01*
X297500Y530000D01*
X297967Y530083D01*
X298367Y530417D01*
X298633Y531000D01*
G01Y530000D02*
Y533333D01*
G01X301667Y528750D02*
X302133Y528417D01*
X302667Y528333D01*
X303133Y528417D01*
X303533Y528833D01*
X303800Y529417D01*
Y533333D01*
G01Y532667D02*
X303533Y533000D01*
X303133Y533250D01*
X302667Y533333D01*
X302133Y533167D01*
X301800Y532833D01*
X301533Y532250D01*
X301400Y531667D01*
X301467Y531167D01*
X301733Y530583D01*
X302133Y530167D01*
X302667Y530000D01*
X303067Y530083D01*
X303533Y530417D01*
X303800Y530750D01*
G01X306767Y528750D02*
X307233Y528417D01*
X307767Y528333D01*
X308233Y528417D01*
X308633Y528833D01*
X308900Y529417D01*
Y533333D01*
G01Y532667D02*
X308633Y533000D01*
X308233Y533250D01*
X307767Y533333D01*
X307233Y533167D01*
X306900Y532833D01*
X306633Y532250D01*
X306500Y531667D01*
X306567Y531167D01*
X306833Y530583D01*
X307233Y530167D01*
X307767Y530000D01*
X308167Y530083D01*
X308633Y530417D01*
X308900Y530750D01*
G01X311800Y532250D02*
X313933D01*
X313733Y532833D01*
X313400Y533167D01*
X312933Y533333D01*
X312467Y533250D01*
X312067Y533000D01*
X311800Y532417D01*
X311667Y531917D01*
Y531417D01*
X311800Y530917D01*
X312133Y530417D01*
X312533Y530083D01*
X313000Y530000D01*
X313467Y530167D01*
X313933Y530667D01*
G01X319100Y535000D02*
Y530000D01*
G01Y530750D02*
X318833Y530333D01*
X318433Y530083D01*
X317967Y530000D01*
X317433Y530167D01*
X317033Y530583D01*
X316767Y531083D01*
X316700Y531667D01*
X316767Y532250D01*
X317033Y532750D01*
X317433Y533167D01*
X317967Y533333D01*
X318433Y533250D01*
X318767Y533083D01*
X319100Y532750D01*
G01X326767Y530000D02*
Y535000D01*
X328367D01*
X328900Y534750D01*
X329300Y534167D01*
X329433Y533500D01*
X329300Y532833D01*
X328967Y532333D01*
X328367Y532083D01*
X326767D01*
G01X333200Y535000D02*
Y530000D01*
G01X331667Y535000D02*
X334733D01*
G01X336900Y530000D02*
Y535000D01*
G01X339700D02*
Y530000D01*
G01Y532500D02*
X336900D01*
G01X348167Y528333D02*
X347500Y529167D01*
X347167Y530000D01*
Y533333D01*
X347500Y534167D01*
X348167Y535000D01*
G01X352200Y530000D02*
Y535000D01*
G01X355000D02*
Y530000D01*
G01Y532500D02*
X352200D01*
G01X358700Y530000D02*
X358300Y530083D01*
X357900Y530417D01*
X357633Y531000D01*
X357500Y531667D01*
X357633Y532333D01*
X357900Y532917D01*
X358300Y533250D01*
X358700Y533333D01*
X359100Y533250D01*
X359500Y532917D01*
X359767Y532333D01*
X359833Y531667D01*
X359767Y531000D01*
X359500Y530417D01*
X359100Y530083D01*
X358700Y530000D01*
G01X363800D02*
Y535000D01*
G01X367900Y532250D02*
X370033D01*
X369833Y532833D01*
X369500Y533167D01*
X369033Y533333D01*
X368567Y533250D01*
X368167Y533000D01*
X367900Y532417D01*
X367767Y531917D01*
Y531417D01*
X367900Y530917D01*
X368233Y530417D01*
X368633Y530083D01*
X369100Y530000D01*
X369567Y530167D01*
X370033Y530667D01*
G01X377700D02*
X378233Y530250D01*
X378833Y530000D01*
X379367D01*
X379900Y530250D01*
X380300Y530667D01*
X380500Y531250D01*
X380367Y531833D01*
X380033Y532333D01*
X379433Y532667D01*
X378633Y532833D01*
X378167Y533167D01*
X377967Y533750D01*
X378100Y534333D01*
X378433Y534750D01*
X378900Y535000D01*
X379367D01*
X379833Y534833D01*
X380233Y534417D01*
G01X384200Y533333D02*
Y530000D01*
G01Y534667D02*
X384067Y534750D01*
Y534917D01*
X384200Y535000D01*
X384333Y534917D01*
Y534750D01*
X384200Y534667D01*
G01X388300Y533333D02*
X390300D01*
X388300Y530000D01*
X390300D01*
G01X393400Y532250D02*
X395533D01*
X395333Y532833D01*
X395000Y533167D01*
X394533Y533333D01*
X394067Y533250D01*
X393667Y533000D01*
X393400Y532417D01*
X393267Y531917D01*
Y531417D01*
X393400Y530917D01*
X393733Y530417D01*
X394133Y530083D01*
X394600Y530000D01*
X395067Y530167D01*
X395533Y530667D01*
G01X400833Y530000D02*
X398167Y531667D01*
X400833Y533333D01*
G01X404600Y530000D02*
Y535000D01*
X403800Y534000D01*
G01Y530000D02*
X405400D01*
G01X408567Y530583D02*
X409033Y530167D01*
X409567Y530000D01*
X410100Y530167D01*
X410567Y530667D01*
X410900Y531417D01*
X411033Y532167D01*
Y533083D01*
X410900Y533833D01*
X410567Y534500D01*
X410167Y534833D01*
X409700Y535000D01*
X409167Y534833D01*
X408767Y534500D01*
X408500Y534000D01*
X408367Y533333D01*
X408500Y532750D01*
X408833Y532167D01*
X409233Y531833D01*
X409700Y531750D01*
X410233Y531917D01*
X410633Y532333D01*
X411033Y533083D01*
G01X414667Y530000D02*
X414800Y531083D01*
X415000Y532000D01*
X415267Y532833D01*
X415600Y533750D01*
X416133Y535000D01*
X413467D01*
G01X417900Y530000D02*
Y533333D01*
G01Y532417D02*
X418100Y532833D01*
X418433Y533167D01*
X418900Y533333D01*
X419367Y533167D01*
X419700Y532833D01*
X419900Y532417D01*
Y530000D01*
G01Y532417D02*
X420100Y532833D01*
X420433Y533167D01*
X420900Y533333D01*
X421367Y533167D01*
X421700Y532833D01*
X421900Y532333D01*
Y530000D01*
G01X425000Y533333D02*
Y530000D01*
G01Y534667D02*
X424867Y534750D01*
Y534917D01*
X425000Y535000D01*
X425133Y534917D01*
Y534750D01*
X425000Y534667D01*
G01X430100Y530000D02*
Y535000D01*
G01X438633Y533333D02*
X439433Y530000D01*
X440300Y533333D01*
X441167Y530000D01*
X441967Y533333D01*
G01X445400D02*
Y530000D01*
G01Y534667D02*
X445267Y534750D01*
Y534917D01*
X445400Y535000D01*
X445533Y534917D01*
Y534750D01*
X445400Y534667D01*
G01X450500Y535000D02*
Y530000D01*
G01X449567Y533333D02*
X451433D01*
G01X454467Y530000D02*
Y535000D01*
G01Y532583D02*
X454800Y533000D01*
X455133Y533250D01*
X455667Y533333D01*
X456067Y533250D01*
X456533Y532917D01*
X456733Y532417D01*
Y530000D01*
G01X464400D02*
Y535000D01*
G01X467200D02*
Y530000D01*
G01Y532500D02*
X464400D01*
G01X469233Y530000D02*
X470900Y535000D01*
X472567Y530000D01*
G01X471967Y531750D02*
X469833D01*
G01X474600Y530667D02*
X475133Y530250D01*
X475733Y530000D01*
X476267D01*
X476800Y530250D01*
X477200Y530667D01*
X477400Y531250D01*
X477267Y531833D01*
X476933Y532333D01*
X476333Y532667D01*
X475533Y532833D01*
X475067Y533167D01*
X474867Y533750D01*
X475000Y534333D01*
X475333Y534750D01*
X475800Y535000D01*
X476267D01*
X476733Y534833D01*
X477133Y534417D01*
G01X479767Y535000D02*
Y530000D01*
X482433D01*
G01X490100Y528333D02*
Y533333D01*
G01Y532583D02*
X490433Y533000D01*
X490767Y533250D01*
X491300Y533333D01*
X491767Y533250D01*
X492233Y532833D01*
X492433Y532250D01*
X492500Y531667D01*
X492433Y531083D01*
X492233Y530500D01*
X491833Y530167D01*
X491300Y530000D01*
X490833Y530083D01*
X490367Y530333D01*
X490100Y530667D01*
G01X495467Y530000D02*
Y533333D01*
G01Y532667D02*
X495800Y533000D01*
X496133Y533250D01*
X496600Y533333D01*
X496933Y533250D01*
X497333Y533000D01*
G01X501500Y530000D02*
X501100Y530083D01*
X500700Y530417D01*
X500433Y531000D01*
X500300Y531667D01*
X500433Y532333D01*
X500700Y532917D01*
X501100Y533250D01*
X501500Y533333D01*
X501900Y533250D01*
X502300Y532917D01*
X502567Y532333D01*
X502633Y531667D01*
X502567Y531000D01*
X502300Y530417D01*
X501900Y530083D01*
X501500Y530000D01*
G01X507800Y535000D02*
Y530000D01*
G01Y530750D02*
X507533Y530333D01*
X507133Y530083D01*
X506667Y530000D01*
X506133Y530167D01*
X505733Y530583D01*
X505467Y531083D01*
X505400Y531667D01*
X505467Y532250D01*
X505733Y532750D01*
X506133Y533167D01*
X506667Y533333D01*
X507133Y533250D01*
X507467Y533083D01*
X507800Y532750D01*
G01X510567Y533333D02*
Y531000D01*
X510833Y530417D01*
X511233Y530083D01*
X511700Y530000D01*
X512167Y530083D01*
X512567Y530417D01*
X512833Y531000D01*
G01Y530000D02*
Y533333D01*
G01X517867Y532917D02*
X517400Y533250D01*
X517000Y533333D01*
X516467Y533167D01*
X516067Y532833D01*
X515800Y532250D01*
X515733Y531667D01*
X515800Y531083D01*
X516067Y530583D01*
X516467Y530167D01*
X517000Y530000D01*
X517467Y530167D01*
X517867Y530500D01*
G01X521900Y535000D02*
Y530000D01*
G01X520967Y533333D02*
X522833D01*
G01X526000Y530583D02*
X526333Y530250D01*
X526800Y530000D01*
X527200D01*
X527600Y530167D01*
X527867Y530417D01*
X528000Y530750D01*
X527933Y531250D01*
X527667Y531500D01*
X526467Y532000D01*
X526200Y532583D01*
X526333Y533000D01*
X526600Y533250D01*
X527000Y533333D01*
X527400Y533250D01*
X527800Y533000D01*
G01X532433Y528333D02*
X533100Y529167D01*
X533433Y530000D01*
Y533333D01*
X533100Y534167D01*
X532433Y535000D01*
G01X270533Y550000D02*
Y546417D01*
X270800Y545667D01*
X271333Y545167D01*
X272000Y545000D01*
X272667Y545167D01*
X273200Y545667D01*
X273467Y546417D01*
Y550000D01*
G01X275967Y545000D02*
Y548333D01*
G01Y547500D02*
X276233Y547917D01*
X276633Y548250D01*
X277167Y548333D01*
X277633Y548250D01*
X278033Y547917D01*
X278233Y547333D01*
Y545000D01*
G01X281333Y546667D02*
X283067D01*
G01X286100Y543333D02*
Y548333D01*
G01Y547583D02*
X286433Y548000D01*
X286767Y548250D01*
X287300Y548333D01*
X287767Y548250D01*
X288233Y547833D01*
X288433Y547250D01*
X288500Y546667D01*
X288433Y546083D01*
X288233Y545500D01*
X287833Y545167D01*
X287300Y545000D01*
X286833Y545083D01*
X286367Y545333D01*
X286100Y545667D01*
G01X292400Y545000D02*
Y550000D01*
G01X296367Y548333D02*
Y546000D01*
X296633Y545417D01*
X297033Y545083D01*
X297500Y545000D01*
X297967Y545083D01*
X298367Y545417D01*
X298633Y546000D01*
G01Y545000D02*
Y548333D01*
G01X301667Y543750D02*
X302133Y543417D01*
X302667Y543333D01*
X303133Y543417D01*
X303533Y543833D01*
X303800Y544417D01*
Y548333D01*
G01Y547667D02*
X303533Y548000D01*
X303133Y548250D01*
X302667Y548333D01*
X302133Y548167D01*
X301800Y547833D01*
X301533Y547250D01*
X301400Y546667D01*
X301467Y546167D01*
X301733Y545583D01*
X302133Y545167D01*
X302667Y545000D01*
X303067Y545083D01*
X303533Y545417D01*
X303800Y545750D01*
G01X306767Y543750D02*
X307233Y543417D01*
X307767Y543333D01*
X308233Y543417D01*
X308633Y543833D01*
X308900Y544417D01*
Y548333D01*
G01Y547667D02*
X308633Y548000D01*
X308233Y548250D01*
X307767Y548333D01*
X307233Y548167D01*
X306900Y547833D01*
X306633Y547250D01*
X306500Y546667D01*
X306567Y546167D01*
X306833Y545583D01*
X307233Y545167D01*
X307767Y545000D01*
X308167Y545083D01*
X308633Y545417D01*
X308900Y545750D01*
G01X311800Y547250D02*
X313933D01*
X313733Y547833D01*
X313400Y548167D01*
X312933Y548333D01*
X312467Y548250D01*
X312067Y548000D01*
X311800Y547417D01*
X311667Y546917D01*
Y546417D01*
X311800Y545917D01*
X312133Y545417D01*
X312533Y545083D01*
X313000Y545000D01*
X313467Y545167D01*
X313933Y545667D01*
G01X319100Y550000D02*
Y545000D01*
G01Y545750D02*
X318833Y545333D01*
X318433Y545083D01*
X317967Y545000D01*
X317433Y545167D01*
X317033Y545583D01*
X316767Y546083D01*
X316700Y546667D01*
X316767Y547250D01*
X317033Y547750D01*
X317433Y548167D01*
X317967Y548333D01*
X318433Y548250D01*
X318767Y548083D01*
X319100Y547750D01*
G01X326767Y545000D02*
Y550000D01*
X328367D01*
X328900Y549750D01*
X329300Y549167D01*
X329433Y548500D01*
X329300Y547833D01*
X328967Y547333D01*
X328367Y547083D01*
X326767D01*
G01X333200Y550000D02*
Y545000D01*
G01X331667Y550000D02*
X334733D01*
G01X336900Y545000D02*
Y550000D01*
G01X339700D02*
Y545000D01*
G01Y547500D02*
X336900D01*
G01X348167Y543333D02*
X347500Y544167D01*
X347167Y545000D01*
Y548333D01*
X347500Y549167D01*
X348167Y550000D01*
G01X352200Y545000D02*
Y550000D01*
G01X355000D02*
Y545000D01*
G01Y547500D02*
X352200D01*
G01X358700Y545000D02*
X358300Y545083D01*
X357900Y545417D01*
X357633Y546000D01*
X357500Y546667D01*
X357633Y547333D01*
X357900Y547917D01*
X358300Y548250D01*
X358700Y548333D01*
X359100Y548250D01*
X359500Y547917D01*
X359767Y547333D01*
X359833Y546667D01*
X359767Y546000D01*
X359500Y545417D01*
X359100Y545083D01*
X358700Y545000D01*
G01X363800D02*
Y550000D01*
G01X367900Y547250D02*
X370033D01*
X369833Y547833D01*
X369500Y548167D01*
X369033Y548333D01*
X368567Y548250D01*
X368167Y548000D01*
X367900Y547417D01*
X367767Y546917D01*
Y546417D01*
X367900Y545917D01*
X368233Y545417D01*
X368633Y545083D01*
X369100Y545000D01*
X369567Y545167D01*
X370033Y545667D01*
G01X377700D02*
X378233Y545250D01*
X378833Y545000D01*
X379367D01*
X379900Y545250D01*
X380300Y545667D01*
X380500Y546250D01*
X380367Y546833D01*
X380033Y547333D01*
X379433Y547667D01*
X378633Y547833D01*
X378167Y548167D01*
X377967Y548750D01*
X378100Y549333D01*
X378433Y549750D01*
X378900Y550000D01*
X379367D01*
X379833Y549833D01*
X380233Y549417D01*
G01X384200Y548333D02*
Y545000D01*
G01Y549667D02*
X384067Y549750D01*
Y549917D01*
X384200Y550000D01*
X384333Y549917D01*
Y549750D01*
X384200Y549667D01*
G01X388300Y548333D02*
X390300D01*
X388300Y545000D01*
X390300D01*
G01X393400Y547250D02*
X395533D01*
X395333Y547833D01*
X395000Y548167D01*
X394533Y548333D01*
X394067Y548250D01*
X393667Y548000D01*
X393400Y547417D01*
X393267Y546917D01*
Y546417D01*
X393400Y545917D01*
X393733Y545417D01*
X394133Y545083D01*
X394600Y545000D01*
X395067Y545167D01*
X395533Y545667D01*
G01X400833Y545000D02*
X398167Y546667D01*
X400833Y548333D01*
G01X404600Y545000D02*
Y550000D01*
X403800Y549000D01*
G01Y545000D02*
X405400D01*
G01X408567Y545583D02*
X409033Y545167D01*
X409567Y545000D01*
X410100Y545167D01*
X410567Y545667D01*
X410900Y546417D01*
X411033Y547167D01*
Y548083D01*
X410900Y548833D01*
X410567Y549500D01*
X410167Y549833D01*
X409700Y550000D01*
X409167Y549833D01*
X408767Y549500D01*
X408500Y549000D01*
X408367Y548333D01*
X408500Y547750D01*
X408833Y547167D01*
X409233Y546833D01*
X409700Y546750D01*
X410233Y546917D01*
X410633Y547333D01*
X411033Y548083D01*
G01X414667Y545000D02*
X414800Y546083D01*
X415000Y547000D01*
X415267Y547833D01*
X415600Y548750D01*
X416133Y550000D01*
X413467D01*
G01X417900Y545000D02*
Y548333D01*
G01Y547417D02*
X418100Y547833D01*
X418433Y548167D01*
X418900Y548333D01*
X419367Y548167D01*
X419700Y547833D01*
X419900Y547417D01*
Y545000D01*
G01Y547417D02*
X420100Y547833D01*
X420433Y548167D01*
X420900Y548333D01*
X421367Y548167D01*
X421700Y547833D01*
X421900Y547333D01*
Y545000D01*
G01X425000Y548333D02*
Y545000D01*
G01Y549667D02*
X424867Y549750D01*
Y549917D01*
X425000Y550000D01*
X425133Y549917D01*
Y549750D01*
X425000Y549667D01*
G01X430100Y545000D02*
Y550000D01*
G01X438633Y548333D02*
X439433Y545000D01*
X440300Y548333D01*
X441167Y545000D01*
X441967Y548333D01*
G01X445400D02*
Y545000D01*
G01Y549667D02*
X445267Y549750D01*
Y549917D01*
X445400Y550000D01*
X445533Y549917D01*
Y549750D01*
X445400Y549667D01*
G01X450500Y550000D02*
Y545000D01*
G01X449567Y548333D02*
X451433D01*
G01X454467Y545000D02*
Y550000D01*
G01Y547583D02*
X454800Y548000D01*
X455133Y548250D01*
X455667Y548333D01*
X456067Y548250D01*
X456533Y547917D01*
X456733Y547417D01*
Y545000D01*
G01X464667D02*
Y548333D01*
G01Y547500D02*
X464933Y547917D01*
X465333Y548250D01*
X465867Y548333D01*
X466333Y548250D01*
X466733Y547917D01*
X466933Y547333D01*
Y545000D01*
G01X470900D02*
X470500Y545083D01*
X470100Y545417D01*
X469833Y546000D01*
X469700Y546667D01*
X469833Y547333D01*
X470100Y547917D01*
X470500Y548250D01*
X470900Y548333D01*
X471300Y548250D01*
X471700Y547917D01*
X471967Y547333D01*
X472033Y546667D01*
X471967Y546000D01*
X471700Y545417D01*
X471300Y545083D01*
X470900Y545000D01*
G01X474867D02*
Y548333D01*
G01Y547500D02*
X475133Y547917D01*
X475533Y548250D01*
X476067Y548333D01*
X476533Y548250D01*
X476933Y547917D01*
X477133Y547333D01*
Y545000D01*
G01X480233Y546667D02*
X481967D01*
G01X484800Y545000D02*
Y550000D01*
G01X487600D02*
Y545000D01*
G01Y547500D02*
X484800D01*
G01X489633Y545000D02*
X491300Y550000D01*
X492967Y545000D01*
G01X492367Y546750D02*
X490233D01*
G01X495000Y545667D02*
X495533Y545250D01*
X496133Y545000D01*
X496667D01*
X497200Y545250D01*
X497600Y545667D01*
X497800Y546250D01*
X497667Y546833D01*
X497333Y547333D01*
X496733Y547667D01*
X495933Y547833D01*
X495467Y548167D01*
X495267Y548750D01*
X495400Y549333D01*
X495733Y549750D01*
X496200Y550000D01*
X496667D01*
X497133Y549833D01*
X497533Y549417D01*
G01X500167Y550000D02*
Y545000D01*
X502833D01*
G01X510500Y543333D02*
Y548333D01*
G01Y547583D02*
X510833Y548000D01*
X511167Y548250D01*
X511700Y548333D01*
X512167Y548250D01*
X512633Y547833D01*
X512833Y547250D01*
X512900Y546667D01*
X512833Y546083D01*
X512633Y545500D01*
X512233Y545167D01*
X511700Y545000D01*
X511233Y545083D01*
X510767Y545333D01*
X510500Y545667D01*
G01X515867Y545000D02*
Y548333D01*
G01Y547667D02*
X516200Y548000D01*
X516533Y548250D01*
X517000Y548333D01*
X517333Y548250D01*
X517733Y548000D01*
G01X521900Y545000D02*
X521500Y545083D01*
X521100Y545417D01*
X520833Y546000D01*
X520700Y546667D01*
X520833Y547333D01*
X521100Y547917D01*
X521500Y548250D01*
X521900Y548333D01*
X522300Y548250D01*
X522700Y547917D01*
X522967Y547333D01*
X523033Y546667D01*
X522967Y546000D01*
X522700Y545417D01*
X522300Y545083D01*
X521900Y545000D01*
G01X528200Y550000D02*
Y545000D01*
G01Y545750D02*
X527933Y545333D01*
X527533Y545083D01*
X527067Y545000D01*
X526533Y545167D01*
X526133Y545583D01*
X525867Y546083D01*
X525800Y546667D01*
X525867Y547250D01*
X526133Y547750D01*
X526533Y548167D01*
X527067Y548333D01*
X527533Y548250D01*
X527867Y548083D01*
X528200Y547750D01*
G01X530967Y548333D02*
Y546000D01*
X531233Y545417D01*
X531633Y545083D01*
X532100Y545000D01*
X532567Y545083D01*
X532967Y545417D01*
X533233Y546000D01*
G01Y545000D02*
Y548333D01*
G01X538267Y547917D02*
X537800Y548250D01*
X537400Y548333D01*
X536867Y548167D01*
X536467Y547833D01*
X536200Y547250D01*
X536133Y546667D01*
X536200Y546083D01*
X536467Y545583D01*
X536867Y545167D01*
X537400Y545000D01*
X537867Y545167D01*
X538267Y545500D01*
G01X542300Y550000D02*
Y545000D01*
G01X541367Y548333D02*
X543233D01*
G01X546400Y545583D02*
X546733Y545250D01*
X547200Y545000D01*
X547600D01*
X548000Y545167D01*
X548267Y545417D01*
X548400Y545750D01*
X548333Y546250D01*
X548067Y546500D01*
X546867Y547000D01*
X546600Y547583D01*
X546733Y548000D01*
X547000Y548250D01*
X547400Y548333D01*
X547800Y548250D01*
X548200Y548000D01*
G01X552833Y543333D02*
X553500Y544167D01*
X553833Y545000D01*
Y548333D01*
X553500Y549167D01*
X552833Y550000D01*
G01X270667Y575000D02*
Y580000D01*
X272267D01*
X272800Y579750D01*
X273200Y579167D01*
X273333Y578500D01*
X273200Y577833D01*
X272867Y577333D01*
X272267Y577083D01*
X270667D01*
G01X277100Y575000D02*
Y580000D01*
G01X281067Y578333D02*
Y576000D01*
X281333Y575417D01*
X281733Y575083D01*
X282200Y575000D01*
X282667Y575083D01*
X283067Y575417D01*
X283333Y576000D01*
G01Y575000D02*
Y578333D01*
G01X286367Y573750D02*
X286833Y573417D01*
X287367Y573333D01*
X287833Y573417D01*
X288233Y573833D01*
X288500Y574417D01*
Y578333D01*
G01Y577667D02*
X288233Y578000D01*
X287833Y578250D01*
X287367Y578333D01*
X286833Y578167D01*
X286500Y577833D01*
X286233Y577250D01*
X286100Y576667D01*
X286167Y576167D01*
X286433Y575583D01*
X286833Y575167D01*
X287367Y575000D01*
X287767Y575083D01*
X288233Y575417D01*
X288500Y575750D01*
G01X291467Y573750D02*
X291933Y573417D01*
X292467Y573333D01*
X292933Y573417D01*
X293333Y573833D01*
X293600Y574417D01*
Y578333D01*
G01Y577667D02*
X293333Y578000D01*
X292933Y578250D01*
X292467Y578333D01*
X291933Y578167D01*
X291600Y577833D01*
X291333Y577250D01*
X291200Y576667D01*
X291267Y576167D01*
X291533Y575583D01*
X291933Y575167D01*
X292467Y575000D01*
X292867Y575083D01*
X293333Y575417D01*
X293600Y575750D01*
G01X296500Y577250D02*
X298633D01*
X298433Y577833D01*
X298100Y578167D01*
X297633Y578333D01*
X297167Y578250D01*
X296767Y578000D01*
X296500Y577417D01*
X296367Y576917D01*
Y576417D01*
X296500Y575917D01*
X296833Y575417D01*
X297233Y575083D01*
X297700Y575000D01*
X298167Y575167D01*
X298633Y575667D01*
G01X303800Y580000D02*
Y575000D01*
G01Y575750D02*
X303533Y575333D01*
X303133Y575083D01*
X302667Y575000D01*
X302133Y575167D01*
X301733Y575583D01*
X301467Y576083D01*
X301400Y576667D01*
X301467Y577250D01*
X301733Y577750D01*
X302133Y578167D01*
X302667Y578333D01*
X303133Y578250D01*
X303467Y578083D01*
X303800Y577750D01*
G01X311133Y580000D02*
X312800Y575000D01*
X314467Y580000D01*
G01X317900Y578333D02*
Y575000D01*
G01Y579667D02*
X317767Y579750D01*
Y579917D01*
X317900Y580000D01*
X318033Y579917D01*
Y579750D01*
X317900Y579667D01*
G01X324200Y575000D02*
Y578333D01*
G01Y577750D02*
X323933Y578083D01*
X323533Y578250D01*
X323067Y578333D01*
X322600Y578167D01*
X322200Y577833D01*
X321933Y577333D01*
X321800Y576667D01*
X321933Y576000D01*
X322200Y575500D01*
X322600Y575167D01*
X323067Y575000D01*
X323533Y575083D01*
X323933Y575333D01*
X324200Y575667D01*
G01X327767Y573333D02*
X327100Y574167D01*
X326767Y575000D01*
Y578333D01*
X327100Y579167D01*
X327767Y580000D01*
G01X332067Y575000D02*
Y580000D01*
G01Y577583D02*
X332400Y578000D01*
X332733Y578250D01*
X333267Y578333D01*
X333667Y578250D01*
X334133Y577917D01*
X334333Y577417D01*
Y575000D01*
G01X338300D02*
X337900Y575083D01*
X337500Y575417D01*
X337233Y576000D01*
X337100Y576667D01*
X337233Y577333D01*
X337500Y577917D01*
X337900Y578250D01*
X338300Y578333D01*
X338700Y578250D01*
X339100Y577917D01*
X339367Y577333D01*
X339433Y576667D01*
X339367Y576000D01*
X339100Y575417D01*
X338700Y575083D01*
X338300Y575000D01*
G01X343400D02*
Y580000D01*
G01X347500Y577250D02*
X349633D01*
X349433Y577833D01*
X349100Y578167D01*
X348633Y578333D01*
X348167Y578250D01*
X347767Y578000D01*
X347500Y577417D01*
X347367Y576917D01*
Y576417D01*
X347500Y575917D01*
X347833Y575417D01*
X348233Y575083D01*
X348700Y575000D01*
X349167Y575167D01*
X349633Y575667D01*
G01X357700Y575583D02*
X358033Y575250D01*
X358500Y575000D01*
X358900D01*
X359300Y575167D01*
X359567Y575417D01*
X359700Y575750D01*
X359633Y576250D01*
X359367Y576500D01*
X358167Y577000D01*
X357900Y577583D01*
X358033Y578000D01*
X358300Y578250D01*
X358700Y578333D01*
X359100Y578250D01*
X359500Y578000D01*
G01X363800Y578333D02*
Y575000D01*
G01Y579667D02*
X363667Y579750D01*
Y579917D01*
X363800Y580000D01*
X363933Y579917D01*
Y579750D01*
X363800Y579667D01*
G01X367900Y578333D02*
X369900D01*
X367900Y575000D01*
X369900D01*
G01X373000Y577250D02*
X375133D01*
X374933Y577833D01*
X374600Y578167D01*
X374133Y578333D01*
X373667Y578250D01*
X373267Y578000D01*
X373000Y577417D01*
X372867Y576917D01*
Y576417D01*
X373000Y575917D01*
X373333Y575417D01*
X373733Y575083D01*
X374200Y575000D01*
X374667Y575167D01*
X375133Y575667D01*
G01X380433Y575000D02*
X377767Y576667D01*
X380433Y578333D01*
G01X384200Y575000D02*
Y580000D01*
X383400Y579000D01*
G01Y575000D02*
X385000D01*
G01X388033Y577083D02*
X388500Y577667D01*
X388900Y578000D01*
X389433Y578167D01*
X389900Y578000D01*
X390233Y577667D01*
X390500Y577167D01*
X390567Y576583D01*
X390500Y576083D01*
X390233Y575583D01*
X389833Y575167D01*
X389367Y575000D01*
X388833Y575167D01*
X388367Y575667D01*
X388100Y576417D01*
X388033Y577250D01*
X388167Y578333D01*
X388367Y578917D01*
X388700Y579500D01*
X389167Y579917D01*
X389633Y580000D01*
X390100Y579833D01*
X390433Y579417D01*
G01X397500Y575000D02*
Y578333D01*
G01Y577417D02*
X397700Y577833D01*
X398033Y578167D01*
X398500Y578333D01*
X398967Y578167D01*
X399300Y577833D01*
X399500Y577417D01*
Y575000D01*
G01Y577417D02*
X399700Y577833D01*
X400033Y578167D01*
X400500Y578333D01*
X400967Y578167D01*
X401300Y577833D01*
X401500Y577333D01*
Y575000D01*
G01X404600Y578333D02*
Y575000D01*
G01Y579667D02*
X404467Y579750D01*
Y579917D01*
X404600Y580000D01*
X404733Y579917D01*
Y579750D01*
X404600Y579667D01*
G01X409700Y575000D02*
Y580000D01*
G01X415133Y573333D02*
X415800Y574167D01*
X416133Y575000D01*
Y578333D01*
X415800Y579167D01*
X415133Y580000D01*
G01X270667Y560000D02*
Y565000D01*
X272267D01*
X272800Y564750D01*
X273200Y564167D01*
X273333Y563500D01*
X273200Y562833D01*
X272867Y562333D01*
X272267Y562083D01*
X270667D01*
G01X277100Y560000D02*
Y565000D01*
G01X281067Y563333D02*
Y561000D01*
X281333Y560417D01*
X281733Y560083D01*
X282200Y560000D01*
X282667Y560083D01*
X283067Y560417D01*
X283333Y561000D01*
G01Y560000D02*
Y563333D01*
G01X286367Y558750D02*
X286833Y558417D01*
X287367Y558333D01*
X287833Y558417D01*
X288233Y558833D01*
X288500Y559417D01*
Y563333D01*
G01Y562667D02*
X288233Y563000D01*
X287833Y563250D01*
X287367Y563333D01*
X286833Y563167D01*
X286500Y562833D01*
X286233Y562250D01*
X286100Y561667D01*
X286167Y561167D01*
X286433Y560583D01*
X286833Y560167D01*
X287367Y560000D01*
X287767Y560083D01*
X288233Y560417D01*
X288500Y560750D01*
G01X291467Y558750D02*
X291933Y558417D01*
X292467Y558333D01*
X292933Y558417D01*
X293333Y558833D01*
X293600Y559417D01*
Y563333D01*
G01Y562667D02*
X293333Y563000D01*
X292933Y563250D01*
X292467Y563333D01*
X291933Y563167D01*
X291600Y562833D01*
X291333Y562250D01*
X291200Y561667D01*
X291267Y561167D01*
X291533Y560583D01*
X291933Y560167D01*
X292467Y560000D01*
X292867Y560083D01*
X293333Y560417D01*
X293600Y560750D01*
G01X296500Y562250D02*
X298633D01*
X298433Y562833D01*
X298100Y563167D01*
X297633Y563333D01*
X297167Y563250D01*
X296767Y563000D01*
X296500Y562417D01*
X296367Y561917D01*
Y561417D01*
X296500Y560917D01*
X296833Y560417D01*
X297233Y560083D01*
X297700Y560000D01*
X298167Y560167D01*
X298633Y560667D01*
G01X303800Y565000D02*
Y560000D01*
G01Y560750D02*
X303533Y560333D01*
X303133Y560083D01*
X302667Y560000D01*
X302133Y560167D01*
X301733Y560583D01*
X301467Y561083D01*
X301400Y561667D01*
X301467Y562250D01*
X301733Y562750D01*
X302133Y563167D01*
X302667Y563333D01*
X303133Y563250D01*
X303467Y563083D01*
X303800Y562750D01*
G01X311467Y560000D02*
Y565000D01*
X313067D01*
X313600Y564750D01*
X314000Y564167D01*
X314133Y563500D01*
X314000Y562833D01*
X313667Y562333D01*
X313067Y562083D01*
X311467D01*
G01X317900Y565000D02*
Y560000D01*
G01X316367Y565000D02*
X319433D01*
G01X321600Y560000D02*
Y565000D01*
G01X324400D02*
Y560000D01*
G01Y562500D02*
X321600D01*
G01X327767Y558333D02*
X327100Y559167D01*
X326767Y560000D01*
Y563333D01*
X327100Y564167D01*
X327767Y565000D01*
G01X332067Y560000D02*
Y565000D01*
G01Y562583D02*
X332400Y563000D01*
X332733Y563250D01*
X333267Y563333D01*
X333667Y563250D01*
X334133Y562917D01*
X334333Y562417D01*
Y560000D01*
G01X338300D02*
X337900Y560083D01*
X337500Y560417D01*
X337233Y561000D01*
X337100Y561667D01*
X337233Y562333D01*
X337500Y562917D01*
X337900Y563250D01*
X338300Y563333D01*
X338700Y563250D01*
X339100Y562917D01*
X339367Y562333D01*
X339433Y561667D01*
X339367Y561000D01*
X339100Y560417D01*
X338700Y560083D01*
X338300Y560000D01*
G01X343400D02*
Y565000D01*
G01X347500Y562250D02*
X349633D01*
X349433Y562833D01*
X349100Y563167D01*
X348633Y563333D01*
X348167Y563250D01*
X347767Y563000D01*
X347500Y562417D01*
X347367Y561917D01*
Y561417D01*
X347500Y560917D01*
X347833Y560417D01*
X348233Y560083D01*
X348700Y560000D01*
X349167Y560167D01*
X349633Y560667D01*
G01X357700Y560583D02*
X358033Y560250D01*
X358500Y560000D01*
X358900D01*
X359300Y560167D01*
X359567Y560417D01*
X359700Y560750D01*
X359633Y561250D01*
X359367Y561500D01*
X358167Y562000D01*
X357900Y562583D01*
X358033Y563000D01*
X358300Y563250D01*
X358700Y563333D01*
X359100Y563250D01*
X359500Y563000D01*
G01X363800Y563333D02*
Y560000D01*
G01Y564667D02*
X363667Y564750D01*
Y564917D01*
X363800Y565000D01*
X363933Y564917D01*
Y564750D01*
X363800Y564667D01*
G01X367900Y563333D02*
X369900D01*
X367900Y560000D01*
X369900D01*
G01X373000Y562250D02*
X375133D01*
X374933Y562833D01*
X374600Y563167D01*
X374133Y563333D01*
X373667Y563250D01*
X373267Y563000D01*
X373000Y562417D01*
X372867Y561917D01*
Y561417D01*
X373000Y560917D01*
X373333Y560417D01*
X373733Y560083D01*
X374200Y560000D01*
X374667Y560167D01*
X375133Y560667D01*
G01X377767Y560000D02*
X380433Y561667D01*
X377767Y563333D01*
G01X383333Y560917D02*
X385067D01*
G01Y562417D02*
X383333D01*
G01X389300Y560000D02*
Y565000D01*
X388500Y564000D01*
G01Y560000D02*
X390100D01*
G01X393133Y562083D02*
X393600Y562667D01*
X394000Y563000D01*
X394533Y563167D01*
X395000Y563000D01*
X395333Y562667D01*
X395600Y562167D01*
X395667Y561583D01*
X395600Y561083D01*
X395333Y560583D01*
X394933Y560167D01*
X394467Y560000D01*
X393933Y560167D01*
X393467Y560667D01*
X393200Y561417D01*
X393133Y562250D01*
X393267Y563333D01*
X393467Y563917D01*
X393800Y564500D01*
X394267Y564917D01*
X394733Y565000D01*
X395200Y564833D01*
X395533Y564417D01*
G01X402600Y560000D02*
Y563333D01*
G01Y562417D02*
X402800Y562833D01*
X403133Y563167D01*
X403600Y563333D01*
X404067Y563167D01*
X404400Y562833D01*
X404600Y562417D01*
Y560000D01*
G01Y562417D02*
X404800Y562833D01*
X405133Y563167D01*
X405600Y563333D01*
X406067Y563167D01*
X406400Y562833D01*
X406600Y562333D01*
Y560000D01*
G01X409700Y563333D02*
Y560000D01*
G01Y564667D02*
X409567Y564750D01*
Y564917D01*
X409700Y565000D01*
X409833Y564917D01*
Y564750D01*
X409700Y564667D01*
G01X414800Y560000D02*
Y565000D01*
G01X420233Y558333D02*
X420900Y559167D01*
X421233Y560000D01*
Y563333D01*
X420900Y564167D01*
X420233Y565000D01*
G01X262500Y539000D02*
X694500D01*
G01X262500Y554000D02*
X694500D01*
G01X262500Y569000D02*
X694500D01*
G01X272500Y609000D02*
Y604000D01*
G01X270967Y609000D02*
X274033D01*
G01X276467Y604000D02*
Y609000D01*
G01Y606583D02*
X276800Y607000D01*
X277133Y607250D01*
X277667Y607333D01*
X278067Y607250D01*
X278533Y606917D01*
X278733Y606417D01*
Y604000D01*
G01X281700Y606250D02*
X283833D01*
X283633Y606833D01*
X283300Y607167D01*
X282833Y607333D01*
X282367Y607250D01*
X281967Y607000D01*
X281700Y606417D01*
X281567Y605917D01*
Y605417D01*
X281700Y604917D01*
X282033Y604417D01*
X282433Y604083D01*
X282900Y604000D01*
X283367Y604167D01*
X283833Y604667D01*
G01X286867Y604000D02*
Y607333D01*
G01Y606667D02*
X287200Y607000D01*
X287533Y607250D01*
X288000Y607333D01*
X288333Y607250D01*
X288733Y607000D01*
G01X290900Y604000D02*
Y607333D01*
G01Y606417D02*
X291100Y606833D01*
X291433Y607167D01*
X291900Y607333D01*
X292367Y607167D01*
X292700Y606833D01*
X292900Y606417D01*
Y604000D01*
G01Y606417D02*
X293100Y606833D01*
X293433Y607167D01*
X293900Y607333D01*
X294367Y607167D01*
X294700Y606833D01*
X294900Y606333D01*
Y604000D01*
G01X299200D02*
Y607333D01*
G01Y606750D02*
X298933Y607083D01*
X298533Y607250D01*
X298067Y607333D01*
X297600Y607167D01*
X297200Y606833D01*
X296933Y606333D01*
X296800Y605667D01*
X296933Y605000D01*
X297200Y604500D01*
X297600Y604167D01*
X298067Y604000D01*
X298533Y604083D01*
X298933Y604333D01*
X299200Y604667D01*
G01X303100Y604000D02*
Y609000D01*
G01X312100Y602333D02*
Y607333D01*
G01Y606583D02*
X312433Y607000D01*
X312767Y607250D01*
X313300Y607333D01*
X313767Y607250D01*
X314233Y606833D01*
X314433Y606250D01*
X314500Y605667D01*
X314433Y605083D01*
X314233Y604500D01*
X313833Y604167D01*
X313300Y604000D01*
X312833Y604083D01*
X312367Y604333D01*
X312100Y604667D01*
G01X319600Y604000D02*
Y607333D01*
G01Y606750D02*
X319333Y607083D01*
X318933Y607250D01*
X318467Y607333D01*
X318000Y607167D01*
X317600Y606833D01*
X317333Y606333D01*
X317200Y605667D01*
X317333Y605000D01*
X317600Y604500D01*
X318000Y604167D01*
X318467Y604000D01*
X318933Y604083D01*
X319333Y604333D01*
X319600Y604667D01*
G01X324700Y609000D02*
Y604000D01*
G01Y604750D02*
X324433Y604333D01*
X324033Y604083D01*
X323567Y604000D01*
X323033Y604167D01*
X322633Y604583D01*
X322367Y605083D01*
X322300Y605667D01*
X322367Y606250D01*
X322633Y606750D01*
X323033Y607167D01*
X323567Y607333D01*
X324033Y607250D01*
X324367Y607083D01*
X324700Y606750D01*
G01X334767Y606917D02*
X334300Y607250D01*
X333900Y607333D01*
X333367Y607167D01*
X332967Y606833D01*
X332700Y606250D01*
X332633Y605667D01*
X332700Y605083D01*
X332967Y604583D01*
X333367Y604167D01*
X333900Y604000D01*
X334367Y604167D01*
X334767Y604500D01*
G01X340000Y604000D02*
Y607333D01*
G01Y606750D02*
X339733Y607083D01*
X339333Y607250D01*
X338867Y607333D01*
X338400Y607167D01*
X338000Y606833D01*
X337733Y606333D01*
X337600Y605667D01*
X337733Y605000D01*
X338000Y604500D01*
X338400Y604167D01*
X338867Y604000D01*
X339333Y604083D01*
X339733Y604333D01*
X340000Y604667D01*
G01X342767Y604000D02*
Y607333D01*
G01Y606500D02*
X343033Y606917D01*
X343433Y607250D01*
X343967Y607333D01*
X344433Y607250D01*
X344833Y606917D01*
X345033Y606333D01*
Y604000D01*
G01X355167Y606917D02*
X354700Y607250D01*
X354300Y607333D01*
X353767Y607167D01*
X353367Y606833D01*
X353100Y606250D01*
X353033Y605667D01*
X353100Y605083D01*
X353367Y604583D01*
X353767Y604167D01*
X354300Y604000D01*
X354767Y604167D01*
X355167Y604500D01*
G01X358067Y604000D02*
Y609000D01*
G01Y606583D02*
X358400Y607000D01*
X358733Y607250D01*
X359267Y607333D01*
X359667Y607250D01*
X360133Y606917D01*
X360333Y606417D01*
Y604000D01*
G01X365500D02*
Y607333D01*
G01Y606750D02*
X365233Y607083D01*
X364833Y607250D01*
X364367Y607333D01*
X363900Y607167D01*
X363500Y606833D01*
X363233Y606333D01*
X363100Y605667D01*
X363233Y605000D01*
X363500Y604500D01*
X363900Y604167D01*
X364367Y604000D01*
X364833Y604083D01*
X365233Y604333D01*
X365500Y604667D01*
G01X368267Y604000D02*
Y607333D01*
G01Y606500D02*
X368533Y606917D01*
X368933Y607250D01*
X369467Y607333D01*
X369933Y607250D01*
X370333Y606917D01*
X370533Y606333D01*
Y604000D01*
G01X373567Y602750D02*
X374033Y602417D01*
X374567Y602333D01*
X375033Y602417D01*
X375433Y602833D01*
X375700Y603417D01*
Y607333D01*
G01Y606667D02*
X375433Y607000D01*
X375033Y607250D01*
X374567Y607333D01*
X374033Y607167D01*
X373700Y606833D01*
X373433Y606250D01*
X373300Y605667D01*
X373367Y605167D01*
X373633Y604583D01*
X374033Y604167D01*
X374567Y604000D01*
X374967Y604083D01*
X375433Y604417D01*
X375700Y604750D01*
G01X378600Y606250D02*
X380733D01*
X380533Y606833D01*
X380200Y607167D01*
X379733Y607333D01*
X379267Y607250D01*
X378867Y607000D01*
X378600Y606417D01*
X378467Y605917D01*
Y605417D01*
X378600Y604917D01*
X378933Y604417D01*
X379333Y604083D01*
X379800Y604000D01*
X380267Y604167D01*
X380733Y604667D01*
G01X389800Y607333D02*
Y604000D01*
G01Y608667D02*
X389667Y608750D01*
Y608917D01*
X389800Y609000D01*
X389933Y608917D01*
Y608750D01*
X389800Y608667D01*
G01X393767Y604000D02*
Y607333D01*
G01Y606500D02*
X394033Y606917D01*
X394433Y607250D01*
X394967Y607333D01*
X395433Y607250D01*
X395833Y606917D01*
X396033Y606333D01*
Y604000D01*
G01X400000Y609000D02*
Y604000D01*
G01X399067Y607333D02*
X400933D01*
G01X405100Y604000D02*
X404700Y604083D01*
X404300Y604417D01*
X404033Y605000D01*
X403900Y605667D01*
X404033Y606333D01*
X404300Y606917D01*
X404700Y607250D01*
X405100Y607333D01*
X405500Y607250D01*
X405900Y606917D01*
X406167Y606333D01*
X406233Y605667D01*
X406167Y605000D01*
X405900Y604417D01*
X405500Y604083D01*
X405100Y604000D01*
G01X414900D02*
Y608250D01*
X415033Y608667D01*
X415300Y608917D01*
X415700Y609000D01*
X416100Y608833D01*
X416300Y608417D01*
G01X415500Y607000D02*
X414167D01*
G01X419267Y607333D02*
Y605000D01*
X419533Y604417D01*
X419933Y604083D01*
X420400Y604000D01*
X420867Y604083D01*
X421267Y604417D01*
X421533Y605000D01*
G01Y604000D02*
Y607333D01*
G01X425500Y604000D02*
Y609000D01*
G01X430600Y604000D02*
Y609000D01*
G01X441867Y606917D02*
X441400Y607250D01*
X441000Y607333D01*
X440467Y607167D01*
X440067Y606833D01*
X439800Y606250D01*
X439733Y605667D01*
X439800Y605083D01*
X440067Y604583D01*
X440467Y604167D01*
X441000Y604000D01*
X441467Y604167D01*
X441867Y604500D01*
G01X445900Y604000D02*
X445500Y604083D01*
X445100Y604417D01*
X444833Y605000D01*
X444700Y605667D01*
X444833Y606333D01*
X445100Y606917D01*
X445500Y607250D01*
X445900Y607333D01*
X446300Y607250D01*
X446700Y606917D01*
X446967Y606333D01*
X447033Y605667D01*
X446967Y605000D01*
X446700Y604417D01*
X446300Y604083D01*
X445900Y604000D01*
G01X449867D02*
Y607333D01*
G01Y606500D02*
X450133Y606917D01*
X450533Y607250D01*
X451067Y607333D01*
X451533Y607250D01*
X451933Y606917D01*
X452133Y606333D01*
Y604000D01*
G01X456100Y609000D02*
Y604000D01*
G01X455167Y607333D02*
X457033D01*
G01X462400Y604000D02*
Y607333D01*
G01Y606750D02*
X462133Y607083D01*
X461733Y607250D01*
X461267Y607333D01*
X460800Y607167D01*
X460400Y606833D01*
X460133Y606333D01*
X460000Y605667D01*
X460133Y605000D01*
X460400Y604500D01*
X460800Y604167D01*
X461267Y604000D01*
X461733Y604083D01*
X462133Y604333D01*
X462400Y604667D01*
G01X467367Y606917D02*
X466900Y607250D01*
X466500Y607333D01*
X465967Y607167D01*
X465567Y606833D01*
X465300Y606250D01*
X465233Y605667D01*
X465300Y605083D01*
X465567Y604583D01*
X465967Y604167D01*
X466500Y604000D01*
X466967Y604167D01*
X467367Y604500D01*
G01X471400Y609000D02*
Y604000D01*
G01X470467Y607333D02*
X472333D01*
G01X270833Y619000D02*
X272500Y624000D01*
X274167Y619000D01*
G01X273567Y620750D02*
X271433D01*
G01X276467Y619000D02*
Y622333D01*
G01Y621500D02*
X276733Y621917D01*
X277133Y622250D01*
X277667Y622333D01*
X278133Y622250D01*
X278533Y621917D01*
X278733Y621333D01*
Y619000D01*
G01X282700Y624000D02*
Y619000D01*
G01X281767Y622333D02*
X283633D01*
G01X287800D02*
Y619000D01*
G01Y623667D02*
X287667Y623750D01*
Y623917D01*
X287800Y624000D01*
X287933Y623917D01*
Y623750D01*
X287800Y623667D01*
G01X292033Y620667D02*
X293767D01*
G01X296800Y617333D02*
Y622333D01*
G01Y621583D02*
X297133Y622000D01*
X297467Y622250D01*
X298000Y622333D01*
X298467Y622250D01*
X298933Y621833D01*
X299133Y621250D01*
X299200Y620667D01*
X299133Y620083D01*
X298933Y619500D01*
X298533Y619167D01*
X298000Y619000D01*
X297533Y619083D01*
X297067Y619333D01*
X296800Y619667D01*
G01X304300Y619000D02*
Y622333D01*
G01Y621750D02*
X304033Y622083D01*
X303633Y622250D01*
X303167Y622333D01*
X302700Y622167D01*
X302300Y621833D01*
X302033Y621333D01*
X301900Y620667D01*
X302033Y620000D01*
X302300Y619500D01*
X302700Y619167D01*
X303167Y619000D01*
X303633Y619083D01*
X304033Y619333D01*
X304300Y619667D01*
G01X309400Y624000D02*
Y619000D01*
G01Y619750D02*
X309133Y619333D01*
X308733Y619083D01*
X308267Y619000D01*
X307733Y619167D01*
X307333Y619583D01*
X307067Y620083D01*
X307000Y620667D01*
X307067Y621250D01*
X307333Y621750D01*
X307733Y622167D01*
X308267Y622333D01*
X308733Y622250D01*
X309067Y622083D01*
X309400Y621750D01*
G01X317400Y619583D02*
X317733Y619250D01*
X318200Y619000D01*
X318600D01*
X319000Y619167D01*
X319267Y619417D01*
X319400Y619750D01*
X319333Y620250D01*
X319067Y620500D01*
X317867Y621000D01*
X317600Y621583D01*
X317733Y622000D01*
X318000Y622250D01*
X318400Y622333D01*
X318800Y622250D01*
X319200Y622000D01*
G01X323500Y622333D02*
Y619000D01*
G01Y623667D02*
X323367Y623750D01*
Y623917D01*
X323500Y624000D01*
X323633Y623917D01*
Y623750D01*
X323500Y623667D01*
G01X327600Y622333D02*
X329600D01*
X327600Y619000D01*
X329600D01*
G01X332700Y621250D02*
X334833D01*
X334633Y621833D01*
X334300Y622167D01*
X333833Y622333D01*
X333367Y622250D01*
X332967Y622000D01*
X332700Y621417D01*
X332567Y620917D01*
Y620417D01*
X332700Y619917D01*
X333033Y619417D01*
X333433Y619083D01*
X333900Y619000D01*
X334367Y619167D01*
X334833Y619667D01*
G01X269633Y637573D02*
X270433Y634240D01*
X271300Y637573D01*
X272167Y634240D01*
X272967Y637573D01*
G01X276400D02*
Y634240D01*
G01Y638907D02*
X276267Y638990D01*
Y639157D01*
X276400Y639240D01*
X276533Y639157D01*
Y638990D01*
X276400Y638907D01*
G01X281500Y639240D02*
Y634240D01*
G01X280567Y637573D02*
X282433D01*
G01X285467Y634240D02*
Y639240D01*
G01Y636823D02*
X285800Y637240D01*
X286133Y637490D01*
X286667Y637573D01*
X287067Y637490D01*
X287533Y637157D01*
X287733Y636657D01*
Y634240D01*
G01X291700D02*
X291300Y634323D01*
X290900Y634657D01*
X290633Y635240D01*
X290500Y635907D01*
X290633Y636573D01*
X290900Y637157D01*
X291300Y637490D01*
X291700Y637573D01*
X292100Y637490D01*
X292500Y637157D01*
X292767Y636573D01*
X292833Y635907D01*
X292767Y635240D01*
X292500Y634657D01*
X292100Y634323D01*
X291700Y634240D01*
G01X295667Y637573D02*
Y635240D01*
X295933Y634657D01*
X296333Y634323D01*
X296800Y634240D01*
X297267Y634323D01*
X297667Y634657D01*
X297933Y635240D01*
G01Y634240D02*
Y637573D01*
G01X301900Y639240D02*
Y634240D01*
G01X300967Y637573D02*
X302833D01*
G01X313167Y637157D02*
X312700Y637490D01*
X312300Y637573D01*
X311767Y637407D01*
X311367Y637073D01*
X311100Y636490D01*
X311033Y635907D01*
X311100Y635323D01*
X311367Y634823D01*
X311767Y634407D01*
X312300Y634240D01*
X312767Y634407D01*
X313167Y634740D01*
G01X317200Y634240D02*
X316800Y634323D01*
X316400Y634657D01*
X316133Y635240D01*
X316000Y635907D01*
X316133Y636573D01*
X316400Y637157D01*
X316800Y637490D01*
X317200Y637573D01*
X317600Y637490D01*
X318000Y637157D01*
X318267Y636573D01*
X318333Y635907D01*
X318267Y635240D01*
X318000Y634657D01*
X317600Y634323D01*
X317200Y634240D01*
G01X321167D02*
Y637573D01*
G01Y636740D02*
X321433Y637157D01*
X321833Y637490D01*
X322367Y637573D01*
X322833Y637490D01*
X323233Y637157D01*
X323433Y636573D01*
Y634240D01*
G01X326267D02*
Y637573D01*
G01Y636740D02*
X326533Y637157D01*
X326933Y637490D01*
X327467Y637573D01*
X327933Y637490D01*
X328333Y637157D01*
X328533Y636573D01*
Y634240D01*
G01X331500Y636490D02*
X333633D01*
X333433Y637073D01*
X333100Y637407D01*
X332633Y637573D01*
X332167Y637490D01*
X331767Y637240D01*
X331500Y636657D01*
X331367Y636157D01*
Y635657D01*
X331500Y635157D01*
X331833Y634657D01*
X332233Y634323D01*
X332700Y634240D01*
X333167Y634407D01*
X333633Y634907D01*
G01X338667Y637157D02*
X338200Y637490D01*
X337800Y637573D01*
X337267Y637407D01*
X336867Y637073D01*
X336600Y636490D01*
X336533Y635907D01*
X336600Y635323D01*
X336867Y634823D01*
X337267Y634407D01*
X337800Y634240D01*
X338267Y634407D01*
X338667Y634740D01*
G01X342700Y639240D02*
Y634240D01*
G01X341767Y637573D02*
X343633D01*
G01X347800D02*
Y634240D01*
G01Y638907D02*
X347667Y638990D01*
Y639157D01*
X347800Y639240D01*
X347933Y639157D01*
Y638990D01*
X347800Y638907D01*
G01X351767Y634240D02*
Y637573D01*
G01Y636740D02*
X352033Y637157D01*
X352433Y637490D01*
X352967Y637573D01*
X353433Y637490D01*
X353833Y637157D01*
X354033Y636573D01*
Y634240D01*
G01X357067Y632990D02*
X357533Y632657D01*
X358067Y632573D01*
X358533Y632657D01*
X358933Y633073D01*
X359200Y633657D01*
Y637573D01*
G01Y636907D02*
X358933Y637240D01*
X358533Y637490D01*
X358067Y637573D01*
X357533Y637407D01*
X357200Y637073D01*
X356933Y636490D01*
X356800Y635907D01*
X356867Y635407D01*
X357133Y634823D01*
X357533Y634407D01*
X358067Y634240D01*
X358467Y634323D01*
X358933Y634657D01*
X359200Y634990D01*
G01X368200Y639240D02*
Y634240D01*
G01X367267Y637573D02*
X369133D01*
G01X373300Y634240D02*
X372900Y634323D01*
X372500Y634657D01*
X372233Y635240D01*
X372100Y635907D01*
X372233Y636573D01*
X372500Y637157D01*
X372900Y637490D01*
X373300Y637573D01*
X373700Y637490D01*
X374100Y637157D01*
X374367Y636573D01*
X374433Y635907D01*
X374367Y635240D01*
X374100Y634657D01*
X373700Y634323D01*
X373300Y634240D01*
G01X383500D02*
X383100Y634323D01*
X382700Y634657D01*
X382433Y635240D01*
X382300Y635907D01*
X382433Y636573D01*
X382700Y637157D01*
X383100Y637490D01*
X383500Y637573D01*
X383900Y637490D01*
X384300Y637157D01*
X384567Y636573D01*
X384633Y635907D01*
X384567Y635240D01*
X384300Y634657D01*
X383900Y634323D01*
X383500Y634240D01*
G01X388600Y639240D02*
Y634240D01*
G01X387667Y637573D02*
X389533D01*
G01X392567Y634240D02*
Y639240D01*
G01Y636823D02*
X392900Y637240D01*
X393233Y637490D01*
X393767Y637573D01*
X394167Y637490D01*
X394633Y637157D01*
X394833Y636657D01*
Y634240D01*
G01X397800Y636490D02*
X399933D01*
X399733Y637073D01*
X399400Y637407D01*
X398933Y637573D01*
X398467Y637490D01*
X398067Y637240D01*
X397800Y636657D01*
X397667Y636157D01*
Y635657D01*
X397800Y635157D01*
X398133Y634657D01*
X398533Y634323D01*
X399000Y634240D01*
X399467Y634407D01*
X399933Y634907D01*
G01X402967Y634240D02*
Y637573D01*
G01Y636907D02*
X403300Y637240D01*
X403633Y637490D01*
X404100Y637573D01*
X404433Y637490D01*
X404833Y637240D01*
G01X414100Y634240D02*
Y639240D01*
G01X420400Y634240D02*
Y637573D01*
G01Y636990D02*
X420133Y637323D01*
X419733Y637490D01*
X419267Y637573D01*
X418800Y637407D01*
X418400Y637073D01*
X418133Y636573D01*
X418000Y635907D01*
X418133Y635240D01*
X418400Y634740D01*
X418800Y634407D01*
X419267Y634240D01*
X419733Y634323D01*
X420133Y634573D01*
X420400Y634907D01*
G01X422900Y632740D02*
X423300Y632573D01*
X423833Y632740D01*
X424167Y633073D01*
X424433Y633490D01*
X424833Y634823D01*
X425700Y637573D01*
G01X423567D02*
X424833Y634823D01*
G01X428400Y636490D02*
X430533D01*
X430333Y637073D01*
X430000Y637407D01*
X429533Y637573D01*
X429067Y637490D01*
X428667Y637240D01*
X428400Y636657D01*
X428267Y636157D01*
Y635657D01*
X428400Y635157D01*
X428733Y634657D01*
X429133Y634323D01*
X429600Y634240D01*
X430067Y634407D01*
X430533Y634907D01*
G01X433567Y634240D02*
Y637573D01*
G01Y636907D02*
X433900Y637240D01*
X434233Y637490D01*
X434700Y637573D01*
X435033Y637490D01*
X435433Y637240D01*
G01X438600Y634823D02*
X438933Y634490D01*
X439400Y634240D01*
X439800D01*
X440200Y634407D01*
X440467Y634657D01*
X440600Y634990D01*
X440533Y635490D01*
X440267Y635740D01*
X439067Y636240D01*
X438800Y636823D01*
X438933Y637240D01*
X439200Y637490D01*
X439600Y637573D01*
X440000Y637490D01*
X440400Y637240D01*
G01X445033Y632573D02*
X445700Y633407D01*
X446033Y634240D01*
Y637573D01*
X445700Y638407D01*
X445033Y639240D01*
G01X270123Y644950D02*
Y649950D01*
X271457D01*
X271990Y649700D01*
X272390Y649367D01*
X272723Y648867D01*
X272990Y648283D01*
X273057Y647450D01*
X272990Y646617D01*
X272723Y646033D01*
X272390Y645533D01*
X271990Y645200D01*
X271457Y644950D01*
X270123D01*
G01X275690Y647200D02*
X277823D01*
X277623Y647783D01*
X277290Y648117D01*
X276823Y648283D01*
X276357Y648200D01*
X275957Y647950D01*
X275690Y647367D01*
X275557Y646867D01*
Y646367D01*
X275690Y645867D01*
X276023Y645367D01*
X276423Y645033D01*
X276890Y644950D01*
X277357Y645117D01*
X277823Y645617D01*
G01X281790Y644950D02*
Y649950D01*
G01X285890Y647200D02*
X288023D01*
X287823Y647783D01*
X287490Y648117D01*
X287023Y648283D01*
X286557Y648200D01*
X286157Y647950D01*
X285890Y647367D01*
X285757Y646867D01*
Y646367D01*
X285890Y645867D01*
X286223Y645367D01*
X286623Y645033D01*
X287090Y644950D01*
X287557Y645117D01*
X288023Y645617D01*
G01X291990Y649950D02*
Y644950D01*
G01X291057Y648283D02*
X292923D01*
G01X296090Y647200D02*
X298223D01*
X298023Y647783D01*
X297690Y648117D01*
X297223Y648283D01*
X296757Y648200D01*
X296357Y647950D01*
X296090Y647367D01*
X295957Y646867D01*
Y646367D01*
X296090Y645867D01*
X296423Y645367D01*
X296823Y645033D01*
X297290Y644950D01*
X297757Y645117D01*
X298223Y645617D01*
G01X306157Y644950D02*
Y648283D01*
G01Y647450D02*
X306423Y647867D01*
X306823Y648200D01*
X307357Y648283D01*
X307823Y648200D01*
X308223Y647867D01*
X308423Y647283D01*
Y644950D01*
G01X312390D02*
X311990Y645033D01*
X311590Y645367D01*
X311323Y645950D01*
X311190Y646617D01*
X311323Y647283D01*
X311590Y647867D01*
X311990Y648200D01*
X312390Y648283D01*
X312790Y648200D01*
X313190Y647867D01*
X313457Y647283D01*
X313523Y646617D01*
X313457Y645950D01*
X313190Y645367D01*
X312790Y645033D01*
X312390Y644950D01*
G01X316357D02*
Y648283D01*
G01Y647450D02*
X316623Y647867D01*
X317023Y648200D01*
X317557Y648283D01*
X318023Y648200D01*
X318423Y647867D01*
X318623Y647283D01*
Y644950D01*
G01X321723Y646617D02*
X323457D01*
G01X327290Y644950D02*
Y649200D01*
X327423Y649617D01*
X327690Y649867D01*
X328090Y649950D01*
X328490Y649783D01*
X328690Y649367D01*
G01X327890Y647950D02*
X326557D01*
G01X331657Y648283D02*
Y645950D01*
X331923Y645367D01*
X332323Y645033D01*
X332790Y644950D01*
X333257Y645033D01*
X333657Y645367D01*
X333923Y645950D01*
G01Y644950D02*
Y648283D01*
G01X336757Y644950D02*
Y648283D01*
G01Y647450D02*
X337023Y647867D01*
X337423Y648200D01*
X337957Y648283D01*
X338423Y648200D01*
X338823Y647867D01*
X339023Y647283D01*
Y644950D01*
G01X344057Y647867D02*
X343590Y648200D01*
X343190Y648283D01*
X342657Y648117D01*
X342257Y647783D01*
X341990Y647200D01*
X341923Y646617D01*
X341990Y646033D01*
X342257Y645533D01*
X342657Y645117D01*
X343190Y644950D01*
X343657Y645117D01*
X344057Y645450D01*
G01X348090Y649950D02*
Y644950D01*
G01X347157Y648283D02*
X349023D01*
G01X353190D02*
Y644950D01*
G01Y649617D02*
X353057Y649700D01*
Y649867D01*
X353190Y649950D01*
X353323Y649867D01*
Y649700D01*
X353190Y649617D01*
G01X358290Y644950D02*
X357890Y645033D01*
X357490Y645367D01*
X357223Y645950D01*
X357090Y646617D01*
X357223Y647283D01*
X357490Y647867D01*
X357890Y648200D01*
X358290Y648283D01*
X358690Y648200D01*
X359090Y647867D01*
X359357Y647283D01*
X359423Y646617D01*
X359357Y645950D01*
X359090Y645367D01*
X358690Y645033D01*
X358290Y644950D01*
G01X362257D02*
Y648283D01*
G01Y647450D02*
X362523Y647867D01*
X362923Y648200D01*
X363457Y648283D01*
X363923Y648200D01*
X364323Y647867D01*
X364523Y647283D01*
Y644950D01*
G01X369690D02*
Y648283D01*
G01Y647700D02*
X369423Y648033D01*
X369023Y648200D01*
X368557Y648283D01*
X368090Y648117D01*
X367690Y647783D01*
X367423Y647283D01*
X367290Y646617D01*
X367423Y645950D01*
X367690Y645450D01*
X368090Y645117D01*
X368557Y644950D01*
X369023Y645033D01*
X369423Y645283D01*
X369690Y645617D01*
G01X373590Y644950D02*
Y649950D01*
G01X382590Y643283D02*
Y648283D01*
G01Y647533D02*
X382923Y647950D01*
X383257Y648200D01*
X383790Y648283D01*
X384257Y648200D01*
X384723Y647783D01*
X384923Y647200D01*
X384990Y646617D01*
X384923Y646033D01*
X384723Y645450D01*
X384323Y645117D01*
X383790Y644950D01*
X383323Y645033D01*
X382857Y645283D01*
X382590Y645617D01*
G01X390090Y644950D02*
Y648283D01*
G01Y647700D02*
X389823Y648033D01*
X389423Y648200D01*
X388957Y648283D01*
X388490Y648117D01*
X388090Y647783D01*
X387823Y647283D01*
X387690Y646617D01*
X387823Y645950D01*
X388090Y645450D01*
X388490Y645117D01*
X388957Y644950D01*
X389423Y645033D01*
X389823Y645283D01*
X390090Y645617D01*
G01X395190Y649950D02*
Y644950D01*
G01Y645700D02*
X394923Y645283D01*
X394523Y645033D01*
X394057Y644950D01*
X393523Y645117D01*
X393123Y645533D01*
X392857Y646033D01*
X392790Y646617D01*
X392857Y647200D01*
X393123Y647700D01*
X393523Y648117D01*
X394057Y648283D01*
X394523Y648200D01*
X394857Y648033D01*
X395190Y647700D01*
G01X404190Y648283D02*
Y644950D01*
G01Y649617D02*
X404057Y649700D01*
Y649867D01*
X404190Y649950D01*
X404323Y649867D01*
Y649700D01*
X404190Y649617D01*
G01X408157Y644950D02*
Y648283D01*
G01Y647450D02*
X408423Y647867D01*
X408823Y648200D01*
X409357Y648283D01*
X409823Y648200D01*
X410223Y647867D01*
X410423Y647283D01*
Y644950D01*
G01X420690D02*
Y648283D01*
G01Y647700D02*
X420423Y648033D01*
X420023Y648200D01*
X419557Y648283D01*
X419090Y648117D01*
X418690Y647783D01*
X418423Y647283D01*
X418290Y646617D01*
X418423Y645950D01*
X418690Y645450D01*
X419090Y645117D01*
X419557Y644950D01*
X420023Y645033D01*
X420423Y645283D01*
X420690Y645617D01*
G01X424590Y644950D02*
Y649950D01*
G01X429690Y644950D02*
Y649950D01*
G01X438690Y643283D02*
Y648283D01*
G01Y647533D02*
X439023Y647950D01*
X439357Y648200D01*
X439890Y648283D01*
X440357Y648200D01*
X440823Y647783D01*
X441023Y647200D01*
X441090Y646617D01*
X441023Y646033D01*
X440823Y645450D01*
X440423Y645117D01*
X439890Y644950D01*
X439423Y645033D01*
X438957Y645283D01*
X438690Y645617D01*
G01X444057Y644950D02*
Y648283D01*
G01Y647617D02*
X444390Y647950D01*
X444723Y648200D01*
X445190Y648283D01*
X445523Y648200D01*
X445923Y647950D01*
G01X450090Y644950D02*
X449690Y645033D01*
X449290Y645367D01*
X449023Y645950D01*
X448890Y646617D01*
X449023Y647283D01*
X449290Y647867D01*
X449690Y648200D01*
X450090Y648283D01*
X450490Y648200D01*
X450890Y647867D01*
X451157Y647283D01*
X451223Y646617D01*
X451157Y645950D01*
X450890Y645367D01*
X450490Y645033D01*
X450090Y644950D01*
G01X456390Y649950D02*
Y644950D01*
G01Y645700D02*
X456123Y645283D01*
X455723Y645033D01*
X455257Y644950D01*
X454723Y645117D01*
X454323Y645533D01*
X454057Y646033D01*
X453990Y646617D01*
X454057Y647200D01*
X454323Y647700D01*
X454723Y648117D01*
X455257Y648283D01*
X455723Y648200D01*
X456057Y648033D01*
X456390Y647700D01*
G01X459157Y648283D02*
Y645950D01*
X459423Y645367D01*
X459823Y645033D01*
X460290Y644950D01*
X460757Y645033D01*
X461157Y645367D01*
X461423Y645950D01*
G01Y644950D02*
Y648283D01*
G01X466457Y647867D02*
X465990Y648200D01*
X465590Y648283D01*
X465057Y648117D01*
X464657Y647783D01*
X464390Y647200D01*
X464323Y646617D01*
X464390Y646033D01*
X464657Y645533D01*
X465057Y645117D01*
X465590Y644950D01*
X466057Y645117D01*
X466457Y645450D01*
G01X470490Y649950D02*
Y644950D01*
G01X469557Y648283D02*
X471423D01*
G01X474590Y645533D02*
X474923Y645200D01*
X475390Y644950D01*
X475790D01*
X476190Y645117D01*
X476457Y645367D01*
X476590Y645700D01*
X476523Y646200D01*
X476257Y646450D01*
X475057Y646950D01*
X474790Y647533D01*
X474923Y647950D01*
X475190Y648200D01*
X475590Y648283D01*
X475990Y648200D01*
X476390Y647950D01*
G01X480690Y644783D02*
X480557Y644867D01*
Y645033D01*
X480690Y645117D01*
X480823Y645033D01*
Y644867D01*
X480690Y644783D01*
G01X485457Y643283D02*
X484790Y644117D01*
X484457Y644950D01*
Y648283D01*
X484790Y649117D01*
X485457Y649950D01*
G01X490090D02*
X491690D01*
G01X490890D02*
Y644950D01*
G01X490090D02*
X491690D01*
G01X494990Y645533D02*
X495323Y645200D01*
X495790Y644950D01*
X496190D01*
X496590Y645117D01*
X496857Y645367D01*
X496990Y645700D01*
X496923Y646200D01*
X496657Y646450D01*
X495457Y646950D01*
X495190Y647533D01*
X495323Y647950D01*
X495590Y648200D01*
X495990Y648283D01*
X496390Y648200D01*
X496790Y647950D01*
G01X501090Y644950D02*
X500690Y645033D01*
X500290Y645367D01*
X500023Y645950D01*
X499890Y646617D01*
X500023Y647283D01*
X500290Y647867D01*
X500690Y648200D01*
X501090Y648283D01*
X501490Y648200D01*
X501890Y647867D01*
X502157Y647283D01*
X502223Y646617D01*
X502157Y645950D01*
X501890Y645367D01*
X501490Y645033D01*
X501090Y644950D01*
G01X506190D02*
Y649950D01*
G01X512490Y644950D02*
Y648283D01*
G01Y647700D02*
X512223Y648033D01*
X511823Y648200D01*
X511357Y648283D01*
X510890Y648117D01*
X510490Y647783D01*
X510223Y647283D01*
X510090Y646617D01*
X510223Y645950D01*
X510490Y645450D01*
X510890Y645117D01*
X511357Y644950D01*
X511823Y645033D01*
X512223Y645283D01*
X512490Y645617D01*
G01X516390Y649950D02*
Y644950D01*
G01X515457Y648283D02*
X517323D01*
G01X520490Y647200D02*
X522623D01*
X522423Y647783D01*
X522090Y648117D01*
X521623Y648283D01*
X521157Y648200D01*
X520757Y647950D01*
X520490Y647367D01*
X520357Y646867D01*
Y646367D01*
X520490Y645867D01*
X520823Y645367D01*
X521223Y645033D01*
X521690Y644950D01*
X522157Y645117D01*
X522623Y645617D01*
G01X530490Y643283D02*
Y648283D01*
G01Y647533D02*
X530823Y647950D01*
X531157Y648200D01*
X531690Y648283D01*
X532157Y648200D01*
X532623Y647783D01*
X532823Y647200D01*
X532890Y646617D01*
X532823Y646033D01*
X532623Y645450D01*
X532223Y645117D01*
X531690Y644950D01*
X531223Y645033D01*
X530757Y645283D01*
X530490Y645617D01*
G01X537990Y644950D02*
Y648283D01*
G01Y647700D02*
X537723Y648033D01*
X537323Y648200D01*
X536857Y648283D01*
X536390Y648117D01*
X535990Y647783D01*
X535723Y647283D01*
X535590Y646617D01*
X535723Y645950D01*
X535990Y645450D01*
X536390Y645117D01*
X536857Y644950D01*
X537323Y645033D01*
X537723Y645283D01*
X537990Y645617D01*
G01X543090Y649950D02*
Y644950D01*
G01Y645700D02*
X542823Y645283D01*
X542423Y645033D01*
X541957Y644950D01*
X541423Y645117D01*
X541023Y645533D01*
X540757Y646033D01*
X540690Y646617D01*
X540757Y647200D01*
X541023Y647700D01*
X541423Y648117D01*
X541957Y648283D01*
X542423Y648200D01*
X542757Y648033D01*
X543090Y647700D01*
G01X322623Y304497D02*
X322890Y304747D01*
X323090Y305163D01*
X323223Y305747D01*
X323090Y306247D01*
X322823Y306580D01*
X322357Y306830D01*
X320557D01*
Y301830D01*
X322757D01*
X323223Y302163D01*
X323490Y302663D01*
X323623Y303247D01*
X323490Y303830D01*
X323090Y304330D01*
X322623Y304497D01*
X320557D01*
G01X320423Y351330D02*
X322090Y356330D01*
X323757Y351330D01*
G01X323157Y353080D02*
X321023D01*
G01X395000Y364500D02*
Y175500D01*
G01X402343Y229887D02*
X402610Y230137D01*
X402810Y230553D01*
X402943Y231137D01*
X402810Y231637D01*
X402543Y231970D01*
X402077Y232220D01*
X400277D01*
Y227220D01*
X402477D01*
X402943Y227553D01*
X403210Y228053D01*
X403343Y228637D01*
X403210Y229220D01*
X402810Y229720D01*
X402343Y229887D01*
X400277D01*
G01X405777Y230553D02*
Y228220D01*
X406043Y227637D01*
X406443Y227303D01*
X406910Y227220D01*
X407377Y227303D01*
X407777Y227637D01*
X408043Y228220D01*
G01Y227220D02*
Y230553D01*
G01X410010Y227220D02*
Y230553D01*
G01Y229637D02*
X410210Y230053D01*
X410543Y230387D01*
X411010Y230553D01*
X411477Y230387D01*
X411810Y230053D01*
X412010Y229637D01*
Y227220D01*
G01Y229637D02*
X412210Y230053D01*
X412543Y230387D01*
X413010Y230553D01*
X413477Y230387D01*
X413810Y230053D01*
X414010Y229553D01*
Y227220D01*
G01X415910Y225553D02*
Y230553D01*
G01Y229803D02*
X416243Y230220D01*
X416577Y230470D01*
X417110Y230553D01*
X417577Y230470D01*
X418043Y230053D01*
X418243Y229470D01*
X418310Y228887D01*
X418243Y228303D01*
X418043Y227720D01*
X417643Y227387D01*
X417110Y227220D01*
X416643Y227303D01*
X416177Y227553D01*
X415910Y227887D01*
G01X401320Y268213D02*
X402520Y264880D01*
X403720Y268213D01*
G01X407620D02*
Y264880D01*
G01Y269547D02*
X407487Y269630D01*
Y269797D01*
X407620Y269880D01*
X407753Y269797D01*
Y269630D01*
X407620Y269547D01*
G01X413920Y264880D02*
Y268213D01*
G01Y267630D02*
X413653Y267963D01*
X413253Y268130D01*
X412787Y268213D01*
X412320Y268047D01*
X411920Y267713D01*
X411653Y267213D01*
X411520Y266547D01*
X411653Y265880D01*
X411920Y265380D01*
X412320Y265047D01*
X412787Y264880D01*
X413253Y264963D01*
X413653Y265213D01*
X413920Y265547D01*
G01X400933Y277360D02*
Y282360D01*
X402267D01*
X402800Y282110D01*
X403200Y281777D01*
X403533Y281277D01*
X403800Y280693D01*
X403867Y279860D01*
X403800Y279027D01*
X403533Y278443D01*
X403200Y277943D01*
X402800Y277610D01*
X402267Y277360D01*
X400933D01*
G01X407500Y280693D02*
Y277360D01*
G01Y282027D02*
X407367Y282110D01*
Y282277D01*
X407500Y282360D01*
X407633Y282277D01*
Y282110D01*
X407500Y282027D01*
G01X410600Y277360D02*
Y280693D01*
G01Y279777D02*
X410800Y280193D01*
X411133Y280527D01*
X411600Y280693D01*
X412067Y280527D01*
X412400Y280193D01*
X412600Y279777D01*
Y277360D01*
G01Y279777D02*
X412800Y280193D01*
X413133Y280527D01*
X413600Y280693D01*
X414067Y280527D01*
X414400Y280193D01*
X414600Y279693D01*
Y277360D01*
G01X416500Y275693D02*
Y280693D01*
G01Y279943D02*
X416833Y280360D01*
X417167Y280610D01*
X417700Y280693D01*
X418167Y280610D01*
X418633Y280193D01*
X418833Y279610D01*
X418900Y279027D01*
X418833Y278443D01*
X418633Y277860D01*
X418233Y277527D01*
X417700Y277360D01*
X417233Y277443D01*
X416767Y277693D01*
X416500Y278027D01*
G01X422800Y277360D02*
Y282360D01*
G01X426900Y279610D02*
X429033D01*
X428833Y280193D01*
X428500Y280527D01*
X428033Y280693D01*
X427567Y280610D01*
X427167Y280360D01*
X426900Y279777D01*
X426767Y279277D01*
Y278777D01*
X426900Y278277D01*
X427233Y277777D01*
X427633Y277443D01*
X428100Y277360D01*
X428567Y277527D01*
X429033Y278027D01*
G01X437700Y277360D02*
Y281610D01*
X437833Y282027D01*
X438100Y282277D01*
X438500Y282360D01*
X438900Y282193D01*
X439100Y281777D01*
G01X438300Y280360D02*
X436967D01*
G01X443200Y277360D02*
X442800Y277443D01*
X442400Y277777D01*
X442133Y278360D01*
X442000Y279027D01*
X442133Y279693D01*
X442400Y280277D01*
X442800Y280610D01*
X443200Y280693D01*
X443600Y280610D01*
X444000Y280277D01*
X444267Y279693D01*
X444333Y279027D01*
X444267Y278360D01*
X444000Y277777D01*
X443600Y277443D01*
X443200Y277360D01*
G01X447367D02*
Y280693D01*
G01Y280027D02*
X447700Y280360D01*
X448033Y280610D01*
X448500Y280693D01*
X448833Y280610D01*
X449233Y280360D01*
G01X458500Y277360D02*
X458100Y277443D01*
X457700Y277777D01*
X457433Y278360D01*
X457300Y279027D01*
X457433Y279693D01*
X457700Y280277D01*
X458100Y280610D01*
X458500Y280693D01*
X458900Y280610D01*
X459300Y280277D01*
X459567Y279693D01*
X459633Y279027D01*
X459567Y278360D01*
X459300Y277777D01*
X458900Y277443D01*
X458500Y277360D01*
G01X462467Y280693D02*
Y278360D01*
X462733Y277777D01*
X463133Y277443D01*
X463600Y277360D01*
X464067Y277443D01*
X464467Y277777D01*
X464733Y278360D01*
G01Y277360D02*
Y280693D01*
G01X468700Y282360D02*
Y277360D01*
G01X467767Y280693D02*
X469633D01*
G01X472800Y279610D02*
X474933D01*
X474733Y280193D01*
X474400Y280527D01*
X473933Y280693D01*
X473467Y280610D01*
X473067Y280360D01*
X472800Y279777D01*
X472667Y279277D01*
Y278777D01*
X472800Y278277D01*
X473133Y277777D01*
X473533Y277443D01*
X474000Y277360D01*
X474467Y277527D01*
X474933Y278027D01*
G01X477967Y277360D02*
Y280693D01*
G01Y280027D02*
X478300Y280360D01*
X478633Y280610D01*
X479100Y280693D01*
X479433Y280610D01*
X479833Y280360D01*
G01X490300Y277360D02*
Y280693D01*
G01Y280110D02*
X490033Y280443D01*
X489633Y280610D01*
X489167Y280693D01*
X488700Y280527D01*
X488300Y280193D01*
X488033Y279693D01*
X487900Y279027D01*
X488033Y278360D01*
X488300Y277860D01*
X488700Y277527D01*
X489167Y277360D01*
X489633Y277443D01*
X490033Y277693D01*
X490300Y278027D01*
G01X493067Y277360D02*
Y280693D01*
G01Y279860D02*
X493333Y280277D01*
X493733Y280610D01*
X494267Y280693D01*
X494733Y280610D01*
X495133Y280277D01*
X495333Y279693D01*
Y277360D01*
G01X500500Y282360D02*
Y277360D01*
G01Y278110D02*
X500233Y277693D01*
X499833Y277443D01*
X499367Y277360D01*
X498833Y277527D01*
X498433Y277943D01*
X498167Y278443D01*
X498100Y279027D01*
X498167Y279610D01*
X498433Y280110D01*
X498833Y280527D01*
X499367Y280693D01*
X499833Y280610D01*
X500167Y280443D01*
X500500Y280110D01*
G01X509500Y280693D02*
Y277360D01*
G01Y282027D02*
X509367Y282110D01*
Y282277D01*
X509500Y282360D01*
X509633Y282277D01*
Y282110D01*
X509500Y282027D01*
G01X513467Y277360D02*
Y280693D01*
G01Y279860D02*
X513733Y280277D01*
X514133Y280610D01*
X514667Y280693D01*
X515133Y280610D01*
X515533Y280277D01*
X515733Y279693D01*
Y277360D01*
G01X518567D02*
Y280693D01*
G01Y279860D02*
X518833Y280277D01*
X519233Y280610D01*
X519767Y280693D01*
X520233Y280610D01*
X520633Y280277D01*
X520833Y279693D01*
Y277360D01*
G01X523800Y279610D02*
X525933D01*
X525733Y280193D01*
X525400Y280527D01*
X524933Y280693D01*
X524467Y280610D01*
X524067Y280360D01*
X523800Y279777D01*
X523667Y279277D01*
Y278777D01*
X523800Y278277D01*
X524133Y277777D01*
X524533Y277443D01*
X525000Y277360D01*
X525467Y277527D01*
X525933Y278027D01*
G01X528967Y277360D02*
Y280693D01*
G01Y280027D02*
X529300Y280360D01*
X529633Y280610D01*
X530100Y280693D01*
X530433Y280610D01*
X530833Y280360D01*
G01X540100Y277360D02*
Y282360D01*
G01X546400Y277360D02*
Y280693D01*
G01Y280110D02*
X546133Y280443D01*
X545733Y280610D01*
X545267Y280693D01*
X544800Y280527D01*
X544400Y280193D01*
X544133Y279693D01*
X544000Y279027D01*
X544133Y278360D01*
X544400Y277860D01*
X544800Y277527D01*
X545267Y277360D01*
X545733Y277443D01*
X546133Y277693D01*
X546400Y278027D01*
G01X549300Y277943D02*
X549633Y277610D01*
X550100Y277360D01*
X550500D01*
X550900Y277527D01*
X551167Y277777D01*
X551300Y278110D01*
X551233Y278610D01*
X550967Y278860D01*
X549767Y279360D01*
X549500Y279943D01*
X549633Y280360D01*
X549900Y280610D01*
X550300Y280693D01*
X550700Y280610D01*
X551100Y280360D01*
G01X554400Y279610D02*
X556533D01*
X556333Y280193D01*
X556000Y280527D01*
X555533Y280693D01*
X555067Y280610D01*
X554667Y280360D01*
X554400Y279777D01*
X554267Y279277D01*
Y278777D01*
X554400Y278277D01*
X554733Y277777D01*
X555133Y277443D01*
X555600Y277360D01*
X556067Y277527D01*
X556533Y278027D01*
G01X559567Y277360D02*
Y280693D01*
G01Y280027D02*
X559900Y280360D01*
X560233Y280610D01*
X560700Y280693D01*
X561033Y280610D01*
X561433Y280360D01*
G01X361117Y329453D02*
X360717Y329703D01*
X360250Y329870D01*
X359717D01*
X359117Y329620D01*
X358650Y329203D01*
X358317Y328703D01*
X358050Y327870D01*
X357983Y327120D01*
X358117Y326370D01*
X358317Y325870D01*
X358717Y325370D01*
X359183Y325037D01*
X359650Y324870D01*
X360117D01*
X360583Y325037D01*
X360983Y325287D01*
X361317Y325620D01*
G01X401743Y295540D02*
X403410Y300540D01*
X405077Y295540D01*
G01X404477Y297290D02*
X402343D01*
G01X407377Y295540D02*
Y298873D01*
G01Y298040D02*
X407643Y298457D01*
X408043Y298790D01*
X408577Y298873D01*
X409043Y298790D01*
X409443Y298457D01*
X409643Y297873D01*
Y295540D01*
G01X412677Y294290D02*
X413143Y293957D01*
X413677Y293873D01*
X414143Y293957D01*
X414543Y294373D01*
X414810Y294957D01*
Y298873D01*
G01Y298207D02*
X414543Y298540D01*
X414143Y298790D01*
X413677Y298873D01*
X413143Y298707D01*
X412810Y298373D01*
X412543Y297790D01*
X412410Y297207D01*
X412477Y296707D01*
X412743Y296123D01*
X413143Y295707D01*
X413677Y295540D01*
X414077Y295623D01*
X414543Y295957D01*
X414810Y296290D01*
G01X418710Y295540D02*
Y300540D01*
G01X422810Y297790D02*
X424943D01*
X424743Y298373D01*
X424410Y298707D01*
X423943Y298873D01*
X423477Y298790D01*
X423077Y298540D01*
X422810Y297957D01*
X422677Y297457D01*
Y296957D01*
X422810Y296457D01*
X423143Y295957D01*
X423543Y295623D01*
X424010Y295540D01*
X424477Y295707D01*
X424943Y296207D01*
G01X428577Y293873D02*
X427910Y294707D01*
X427577Y295540D01*
Y298873D01*
X427910Y299707D01*
X428577Y300540D01*
G01X444543Y293873D02*
X445210Y294707D01*
X445543Y295540D01*
Y298873D01*
X445210Y299707D01*
X444543Y300540D01*
G01X401143Y331927D02*
X401410Y332177D01*
X401610Y332593D01*
X401743Y333177D01*
X401610Y333677D01*
X401343Y334010D01*
X400877Y334260D01*
X399077D01*
Y329260D01*
X401277D01*
X401743Y329593D01*
X402010Y330093D01*
X402143Y330677D01*
X402010Y331260D01*
X401610Y331760D01*
X401143Y331927D01*
X399077D01*
G01X404510Y329093D02*
X406910Y334260D01*
G01X409143Y329260D02*
X410810Y334260D01*
X412477Y329260D01*
G01X411877Y331010D02*
X409743D01*
G01X395000Y305500D02*
X694500D01*
G01X395000Y337500D02*
X694500D01*
G01X400467Y358960D02*
Y353960D01*
X403133D01*
G01X408100D02*
Y357293D01*
G01Y356710D02*
X407833Y357043D01*
X407433Y357210D01*
X406967Y357293D01*
X406500Y357127D01*
X406100Y356793D01*
X405833Y356293D01*
X405700Y355627D01*
X405833Y354960D01*
X406100Y354460D01*
X406500Y354127D01*
X406967Y353960D01*
X407433Y354043D01*
X407833Y354293D01*
X408100Y354627D01*
G01X411000Y354543D02*
X411333Y354210D01*
X411800Y353960D01*
X412200D01*
X412600Y354127D01*
X412867Y354377D01*
X413000Y354710D01*
X412933Y355210D01*
X412667Y355460D01*
X411467Y355960D01*
X411200Y356543D01*
X411333Y356960D01*
X411600Y357210D01*
X412000Y357293D01*
X412400Y357210D01*
X412800Y356960D01*
G01X416100Y356210D02*
X418233D01*
X418033Y356793D01*
X417700Y357127D01*
X417233Y357293D01*
X416767Y357210D01*
X416367Y356960D01*
X416100Y356377D01*
X415967Y355877D01*
Y355377D01*
X416100Y354877D01*
X416433Y354377D01*
X416833Y354043D01*
X417300Y353960D01*
X417767Y354127D01*
X418233Y354627D01*
G01X421267Y353960D02*
Y357293D01*
G01Y356627D02*
X421600Y356960D01*
X421933Y357210D01*
X422400Y357293D01*
X422733Y357210D01*
X423133Y356960D01*
G01X431200Y357293D02*
X432400Y353960D01*
X433600Y357293D01*
G01X437500D02*
Y353960D01*
G01Y358627D02*
X437367Y358710D01*
Y358877D01*
X437500Y358960D01*
X437633Y358877D01*
Y358710D01*
X437500Y358627D01*
G01X443800Y353960D02*
Y357293D01*
G01Y356710D02*
X443533Y357043D01*
X443133Y357210D01*
X442667Y357293D01*
X442200Y357127D01*
X441800Y356793D01*
X441533Y356293D01*
X441400Y355627D01*
X441533Y354960D01*
X441800Y354460D01*
X442200Y354127D01*
X442667Y353960D01*
X443133Y354043D01*
X443533Y354293D01*
X443800Y354627D01*
G01X451800Y354543D02*
X452133Y354210D01*
X452600Y353960D01*
X453000D01*
X453400Y354127D01*
X453667Y354377D01*
X453800Y354710D01*
X453733Y355210D01*
X453467Y355460D01*
X452267Y355960D01*
X452000Y356543D01*
X452133Y356960D01*
X452400Y357210D01*
X452800Y357293D01*
X453200Y357210D01*
X453600Y356960D01*
G01X457900Y357293D02*
Y353960D01*
G01Y358627D02*
X457767Y358710D01*
Y358877D01*
X457900Y358960D01*
X458033Y358877D01*
Y358710D01*
X457900Y358627D01*
G01X462000Y357293D02*
X464000D01*
X462000Y353960D01*
X464000D01*
G01X467100Y356210D02*
X469233D01*
X469033Y356793D01*
X468700Y357127D01*
X468233Y357293D01*
X467767Y357210D01*
X467367Y356960D01*
X467100Y356377D01*
X466967Y355877D01*
Y355377D01*
X467100Y354877D01*
X467433Y354377D01*
X467833Y354043D01*
X468300Y353960D01*
X468767Y354127D01*
X469233Y354627D01*
G01X476633Y357293D02*
X477433Y353960D01*
X478300Y357293D01*
X479167Y353960D01*
X479967Y357293D01*
G01X483400D02*
Y353960D01*
G01Y358627D02*
X483267Y358710D01*
Y358877D01*
X483400Y358960D01*
X483533Y358877D01*
Y358710D01*
X483400Y358627D01*
G01X488500Y358960D02*
Y353960D01*
G01X487567Y357293D02*
X489433D01*
G01X492467Y353960D02*
Y358960D01*
G01Y356543D02*
X492800Y356960D01*
X493133Y357210D01*
X493667Y357293D01*
X494067Y357210D01*
X494533Y356877D01*
X494733Y356377D01*
Y353960D01*
G01X498700D02*
X498300Y354043D01*
X497900Y354377D01*
X497633Y354960D01*
X497500Y355627D01*
X497633Y356293D01*
X497900Y356877D01*
X498300Y357210D01*
X498700Y357293D01*
X499100Y357210D01*
X499500Y356877D01*
X499767Y356293D01*
X499833Y355627D01*
X499767Y354960D01*
X499500Y354377D01*
X499100Y354043D01*
X498700Y353960D01*
G01X502667Y357293D02*
Y354960D01*
X502933Y354377D01*
X503333Y354043D01*
X503800Y353960D01*
X504267Y354043D01*
X504667Y354377D01*
X504933Y354960D01*
G01Y353960D02*
Y357293D01*
G01X508900Y358960D02*
Y353960D01*
G01X507967Y357293D02*
X509833D01*
G01X517900Y352293D02*
Y357293D01*
G01Y356543D02*
X518233Y356960D01*
X518567Y357210D01*
X519100Y357293D01*
X519567Y357210D01*
X520033Y356793D01*
X520233Y356210D01*
X520300Y355627D01*
X520233Y355043D01*
X520033Y354460D01*
X519633Y354127D01*
X519100Y353960D01*
X518633Y354043D01*
X518167Y354293D01*
X517900Y354627D01*
G01X524200Y353960D02*
Y358960D01*
G01X530500Y353960D02*
Y357293D01*
G01Y356710D02*
X530233Y357043D01*
X529833Y357210D01*
X529367Y357293D01*
X528900Y357127D01*
X528500Y356793D01*
X528233Y356293D01*
X528100Y355627D01*
X528233Y354960D01*
X528500Y354460D01*
X528900Y354127D01*
X529367Y353960D01*
X529833Y354043D01*
X530233Y354293D01*
X530500Y354627D01*
G01X534400Y358960D02*
Y353960D01*
G01X533467Y357293D02*
X535333D01*
G01X539500D02*
Y353960D01*
G01Y358627D02*
X539367Y358710D01*
Y358877D01*
X539500Y358960D01*
X539633Y358877D01*
Y358710D01*
X539500Y358627D01*
G01X543467Y353960D02*
Y357293D01*
G01Y356460D02*
X543733Y356877D01*
X544133Y357210D01*
X544667Y357293D01*
X545133Y357210D01*
X545533Y356877D01*
X545733Y356293D01*
Y353960D01*
G01X548767Y352710D02*
X549233Y352377D01*
X549767Y352293D01*
X550233Y352377D01*
X550633Y352793D01*
X550900Y353377D01*
Y357293D01*
G01Y356627D02*
X550633Y356960D01*
X550233Y357210D01*
X549767Y357293D01*
X549233Y357127D01*
X548900Y356793D01*
X548633Y356210D01*
X548500Y355627D01*
X548567Y355127D01*
X548833Y354543D01*
X549233Y354127D01*
X549767Y353960D01*
X550167Y354043D01*
X550633Y354377D01*
X550900Y354710D01*
G01X559567Y352293D02*
X558900Y353127D01*
X558567Y353960D01*
Y357293D01*
X558900Y358127D01*
X559567Y358960D01*
G01X565533Y356627D02*
X565800Y356877D01*
X566000Y357293D01*
X566133Y357877D01*
X566000Y358377D01*
X565733Y358710D01*
X565267Y358960D01*
X563467D01*
Y353960D01*
X565667D01*
X566133Y354293D01*
X566400Y354793D01*
X566533Y355377D01*
X566400Y355960D01*
X566000Y356460D01*
X565533Y356627D01*
X563467D01*
G01X570433Y352293D02*
X571100Y353127D01*
X571433Y353960D01*
Y357293D01*
X571100Y358127D01*
X570433Y358960D01*
G01X404000Y666833D02*
Y663500D01*
G01Y668167D02*
X403867Y668250D01*
Y668417D01*
X404000Y668500D01*
X404133Y668417D01*
Y668250D01*
X404000Y668167D01*
G01X409100Y668500D02*
Y663500D01*
G01X408167Y666833D02*
X410033D01*
G01X413200Y665750D02*
X415333D01*
X415133Y666333D01*
X414800Y666667D01*
X414333Y666833D01*
X413867Y666750D01*
X413467Y666500D01*
X413200Y665917D01*
X413067Y665417D01*
Y664917D01*
X413200Y664417D01*
X413533Y663917D01*
X413933Y663583D01*
X414400Y663500D01*
X414867Y663667D01*
X415333Y664167D01*
G01X417300Y663500D02*
Y666833D01*
G01Y665917D02*
X417500Y666333D01*
X417833Y666667D01*
X418300Y666833D01*
X418767Y666667D01*
X419100Y666333D01*
X419300Y665917D01*
Y663500D01*
G01Y665917D02*
X419500Y666333D01*
X419833Y666667D01*
X420300Y666833D01*
X420767Y666667D01*
X421100Y666333D01*
X421300Y665833D01*
Y663500D01*
G01X444197Y300843D02*
X443797Y301093D01*
X443330Y301260D01*
X442797D01*
X442197Y301010D01*
X441730Y300593D01*
X441397Y300093D01*
X441130Y299260D01*
X441063Y298510D01*
X441197Y297760D01*
X441397Y297260D01*
X441797Y296760D01*
X442263Y296427D01*
X442730Y296260D01*
X443197D01*
X443663Y296427D01*
X444063Y296677D01*
X444397Y297010D01*
G01X595500Y-69500D02*
Y438000D01*
G01Y679000D02*
Y396000D01*
G01X590333Y860000D02*
X592000Y855000D01*
X593667Y860000D01*
G01X595633Y856000D02*
X596033Y855417D01*
X596567Y855083D01*
X597167Y855000D01*
X597700Y855083D01*
X598233Y855500D01*
X598567Y856000D01*
X598633Y856500D01*
X598500Y857083D01*
X598033Y857500D01*
X597567Y857667D01*
X596967D01*
G01X597567D02*
X597967Y857917D01*
X598300Y858333D01*
X598433Y858833D01*
X598300Y859333D01*
X597967Y859750D01*
X597367Y860000D01*
X596767Y859917D01*
X596167Y859583D01*
G01X602200Y854833D02*
X602067Y854917D01*
Y855083D01*
X602200Y855167D01*
X602333Y855083D01*
Y854917D01*
X602200Y854833D01*
G01X608100Y855000D02*
Y860000D01*
X605633Y856417D01*
X608967D01*
G01X612400Y854833D02*
X612267Y854917D01*
Y855083D01*
X612400Y855167D01*
X612533Y855083D01*
Y854917D01*
X612400Y854833D01*
G01X617500Y855000D02*
Y860000D01*
X616700Y859000D01*
G01Y855000D02*
X618300D01*
G01X636633Y859167D02*
X637033Y859667D01*
X637500Y859917D01*
X638033Y860000D01*
X638700Y859833D01*
X639167Y859417D01*
X639300Y858917D01*
X639233Y858417D01*
X638967Y858000D01*
X637633Y857167D01*
X637033Y856583D01*
X636633Y855750D01*
X636500Y855000D01*
X639300D01*
G01X643000Y860000D02*
X642467Y859833D01*
X642067Y859417D01*
X641800Y858917D01*
X641600Y858250D01*
X641533Y857500D01*
X641600Y856750D01*
X641800Y856083D01*
X642067Y855583D01*
X642467Y855167D01*
X643000Y855000D01*
X643533Y855167D01*
X643933Y855583D01*
X644200Y856083D01*
X644400Y856750D01*
X644467Y857500D01*
X644400Y858250D01*
X644200Y858917D01*
X643933Y859417D01*
X643533Y859833D01*
X643000Y860000D01*
G01X648100Y855000D02*
Y860000D01*
X647300Y859000D01*
G01Y855000D02*
X648900D01*
G01X651733Y855750D02*
X652133Y855333D01*
X652600Y855083D01*
X653200Y855000D01*
X653800Y855167D01*
X654267Y855500D01*
X654600Y856083D01*
X654667Y856750D01*
X654533Y857417D01*
X654200Y857833D01*
X653733Y858167D01*
X653267Y858250D01*
X652800Y858167D01*
X652200Y857833D01*
X652400Y860000D01*
X654200D01*
G01X657100Y854833D02*
X659500Y860000D01*
G01X663400D02*
X662867Y859833D01*
X662467Y859417D01*
X662200Y858917D01*
X662000Y858250D01*
X661933Y857500D01*
X662000Y856750D01*
X662200Y856083D01*
X662467Y855583D01*
X662867Y855167D01*
X663400Y855000D01*
X663933Y855167D01*
X664333Y855583D01*
X664600Y856083D01*
X664800Y856750D01*
X664867Y857500D01*
X664800Y858250D01*
X664600Y858917D01*
X664333Y859417D01*
X663933Y859833D01*
X663400Y860000D01*
G01X667233Y857083D02*
X667700Y857667D01*
X668100Y858000D01*
X668633Y858167D01*
X669100Y858000D01*
X669433Y857667D01*
X669700Y857167D01*
X669767Y856583D01*
X669700Y856083D01*
X669433Y855583D01*
X669033Y855167D01*
X668567Y855000D01*
X668033Y855167D01*
X667567Y855667D01*
X667300Y856417D01*
X667233Y857250D01*
X667367Y858333D01*
X667567Y858917D01*
X667900Y859500D01*
X668367Y859917D01*
X668833Y860000D01*
X669300Y859833D01*
X669633Y859417D01*
G01X607000Y-28500D02*
X606467Y-28667D01*
X606067Y-29083D01*
X605800Y-29583D01*
X605600Y-30250D01*
X605533Y-31000D01*
X605600Y-31750D01*
X605800Y-32417D01*
X606067Y-32917D01*
X606467Y-33333D01*
X607000Y-33500D01*
X607533Y-33333D01*
X607933Y-32917D01*
X608200Y-32417D01*
X608400Y-31750D01*
X608467Y-31000D01*
X608400Y-30250D01*
X608200Y-29583D01*
X607933Y-29083D01*
X607533Y-28667D01*
X607000Y-28500D01*
G01X612100Y-33667D02*
X611967Y-33583D01*
Y-33417D01*
X612100Y-33333D01*
X612233Y-33417D01*
Y-33583D01*
X612100Y-33667D01*
G01X615733Y-32500D02*
X616133Y-33083D01*
X616667Y-33417D01*
X617267Y-33500D01*
X617800Y-33417D01*
X618333Y-33000D01*
X618667Y-32500D01*
X618733Y-32000D01*
X618600Y-31417D01*
X618133Y-31000D01*
X617667Y-30833D01*
X617067D01*
G01X617667D02*
X618067Y-30583D01*
X618400Y-30167D01*
X618533Y-29667D01*
X618400Y-29167D01*
X618067Y-28750D01*
X617467Y-28500D01*
X616867Y-28583D01*
X616267Y-28917D01*
G01X620300Y-31833D02*
X620967Y-30167D01*
X621633D01*
X622967Y-33500D01*
X623633D01*
X624300Y-31833D01*
G01X627400Y-28500D02*
X626867Y-28667D01*
X626467Y-29083D01*
X626200Y-29583D01*
X626000Y-30250D01*
X625933Y-31000D01*
X626000Y-31750D01*
X626200Y-32417D01*
X626467Y-32917D01*
X626867Y-33333D01*
X627400Y-33500D01*
X627933Y-33333D01*
X628333Y-32917D01*
X628600Y-32417D01*
X628800Y-31750D01*
X628867Y-31000D01*
X628800Y-30250D01*
X628600Y-29583D01*
X628333Y-29083D01*
X627933Y-28667D01*
X627400Y-28500D01*
G01X632500Y-33667D02*
X632367Y-33583D01*
Y-33417D01*
X632500Y-33333D01*
X632633Y-33417D01*
Y-33583D01*
X632500Y-33667D01*
G01X637467Y-33500D02*
X637600Y-32417D01*
X637800Y-31500D01*
X638067Y-30667D01*
X638400Y-29750D01*
X638933Y-28500D01*
X636267D01*
G01X640700Y-33500D02*
Y-30167D01*
G01Y-31083D02*
X640900Y-30667D01*
X641233Y-30333D01*
X641700Y-30167D01*
X642167Y-30333D01*
X642500Y-30667D01*
X642700Y-31083D01*
Y-33500D01*
G01Y-31083D02*
X642900Y-30667D01*
X643233Y-30333D01*
X643700Y-30167D01*
X644167Y-30333D01*
X644500Y-30667D01*
X644700Y-31167D01*
Y-33500D01*
G01X647800Y-30167D02*
Y-33500D01*
G01Y-28833D02*
X647667Y-28750D01*
Y-28583D01*
X647800Y-28500D01*
X647933Y-28583D01*
Y-28750D01*
X647800Y-28833D01*
G01X652900Y-33500D02*
Y-28500D01*
G01X608333Y-48500D02*
X605667Y-46833D01*
X608333Y-45167D01*
G01X611233Y-47583D02*
X612967D01*
G01Y-46083D02*
X611233D01*
G01X617200Y-48500D02*
Y-43500D01*
X616400Y-44500D01*
G01Y-48500D02*
X618000D01*
G01X622300Y-48667D02*
X622167Y-48583D01*
Y-48417D01*
X622300Y-48333D01*
X622433Y-48417D01*
Y-48583D01*
X622300Y-48667D01*
G01X628200Y-48500D02*
Y-43500D01*
X625733Y-47083D01*
X629067D01*
G01X630500Y-48500D02*
Y-45167D01*
G01Y-46083D02*
X630700Y-45667D01*
X631033Y-45333D01*
X631500Y-45167D01*
X631967Y-45333D01*
X632300Y-45667D01*
X632500Y-46083D01*
Y-48500D01*
G01Y-46083D02*
X632700Y-45667D01*
X633033Y-45333D01*
X633500Y-45167D01*
X633967Y-45333D01*
X634300Y-45667D01*
X634500Y-46167D01*
Y-48500D01*
G01X637600Y-45167D02*
Y-48500D01*
G01Y-43833D02*
X637467Y-43750D01*
Y-43583D01*
X637600Y-43500D01*
X637733Y-43583D01*
Y-43750D01*
X637600Y-43833D01*
G01X642700Y-48500D02*
Y-43500D01*
G01X605267Y-65000D02*
Y-60000D01*
X607000Y-64167D01*
X608733Y-60000D01*
Y-65000D01*
G01X610967Y-61667D02*
Y-64000D01*
X611233Y-64583D01*
X611633Y-64917D01*
X612100Y-65000D01*
X612567Y-64917D01*
X612967Y-64583D01*
X613233Y-64000D01*
G01Y-65000D02*
Y-61667D01*
G01X616200Y-64417D02*
X616533Y-64750D01*
X617000Y-65000D01*
X617400D01*
X617800Y-64833D01*
X618067Y-64583D01*
X618200Y-64250D01*
X618133Y-63750D01*
X617867Y-63500D01*
X616667Y-63000D01*
X616400Y-62417D01*
X616533Y-62000D01*
X616800Y-61750D01*
X617200Y-61667D01*
X617600Y-61750D01*
X618000Y-62000D01*
G01X622300Y-60000D02*
Y-65000D01*
G01X621367Y-61667D02*
X623233D01*
G01X632100Y-65000D02*
Y-60750D01*
X632233Y-60333D01*
X632500Y-60083D01*
X632900Y-60000D01*
X633300Y-60167D01*
X633500Y-60583D01*
G01X632700Y-62000D02*
X631367D01*
G01X637600Y-65000D02*
X637200Y-64917D01*
X636800Y-64583D01*
X636533Y-64000D01*
X636400Y-63333D01*
X636533Y-62667D01*
X636800Y-62083D01*
X637200Y-61750D01*
X637600Y-61667D01*
X638000Y-61750D01*
X638400Y-62083D01*
X638667Y-62667D01*
X638733Y-63333D01*
X638667Y-64000D01*
X638400Y-64583D01*
X638000Y-64917D01*
X637600Y-65000D01*
G01X642700D02*
Y-60000D01*
G01X647800Y-65000D02*
Y-60000D01*
G01X652900Y-65000D02*
X652500Y-64917D01*
X652100Y-64583D01*
X651833Y-64000D01*
X651700Y-63333D01*
X651833Y-62667D01*
X652100Y-62083D01*
X652500Y-61750D01*
X652900Y-61667D01*
X653300Y-61750D01*
X653700Y-62083D01*
X653967Y-62667D01*
X654033Y-63333D01*
X653967Y-64000D01*
X653700Y-64583D01*
X653300Y-64917D01*
X652900Y-65000D01*
G01X656333Y-61667D02*
X657133Y-65000D01*
X658000Y-61667D01*
X658867Y-65000D01*
X659667Y-61667D01*
G01X606267Y-1833D02*
X607867D01*
G01X607000Y-750D02*
Y-2917D01*
G01X610900Y-3667D02*
X613300Y1500D01*
G01X616333Y-1833D02*
X618067D01*
G01X622300Y-3500D02*
Y1500D01*
X621500Y500D01*
G01Y-3500D02*
X623100D01*
G01X625400D02*
Y-167D01*
G01Y-1083D02*
X625600Y-667D01*
X625933Y-333D01*
X626400Y-167D01*
X626867Y-333D01*
X627200Y-667D01*
X627400Y-1083D01*
Y-3500D01*
G01Y-1083D02*
X627600Y-667D01*
X627933Y-333D01*
X628400Y-167D01*
X628867Y-333D01*
X629200Y-667D01*
X629400Y-1167D01*
Y-3500D01*
G01X632500Y-167D02*
Y-3500D01*
G01Y1167D02*
X632367Y1250D01*
Y1417D01*
X632500Y1500D01*
X632633Y1417D01*
Y1250D01*
X632500Y1167D01*
G01X637600Y-3500D02*
Y1500D01*
G01X607000Y-15000D02*
X606467Y-15167D01*
X606067Y-15583D01*
X605800Y-16083D01*
X605600Y-16750D01*
X605533Y-17500D01*
X605600Y-18250D01*
X605800Y-18917D01*
X606067Y-19417D01*
X606467Y-19833D01*
X607000Y-20000D01*
X607533Y-19833D01*
X607933Y-19417D01*
X608200Y-18917D01*
X608400Y-18250D01*
X608467Y-17500D01*
X608400Y-16750D01*
X608200Y-16083D01*
X607933Y-15583D01*
X607533Y-15167D01*
X607000Y-15000D01*
G01X612100Y-20167D02*
X611967Y-20083D01*
Y-19917D01*
X612100Y-19833D01*
X612233Y-19917D01*
Y-20083D01*
X612100Y-20167D01*
G01X615733Y-19000D02*
X616133Y-19583D01*
X616667Y-19917D01*
X617267Y-20000D01*
X617800Y-19917D01*
X618333Y-19500D01*
X618667Y-19000D01*
X618733Y-18500D01*
X618600Y-17917D01*
X618133Y-17500D01*
X617667Y-17333D01*
X617067D01*
G01X617667D02*
X618067Y-17083D01*
X618400Y-16667D01*
X618533Y-16167D01*
X618400Y-15667D01*
X618067Y-15250D01*
X617467Y-15000D01*
X616867Y-15083D01*
X616267Y-15417D01*
G01X620300Y-18333D02*
X620967Y-16667D01*
X621633D01*
X622967Y-20000D01*
X623633D01*
X624300Y-18333D01*
G01X627400Y-15000D02*
X626867Y-15167D01*
X626467Y-15583D01*
X626200Y-16083D01*
X626000Y-16750D01*
X625933Y-17500D01*
X626000Y-18250D01*
X626200Y-18917D01*
X626467Y-19417D01*
X626867Y-19833D01*
X627400Y-20000D01*
X627933Y-19833D01*
X628333Y-19417D01*
X628600Y-18917D01*
X628800Y-18250D01*
X628867Y-17500D01*
X628800Y-16750D01*
X628600Y-16083D01*
X628333Y-15583D01*
X627933Y-15167D01*
X627400Y-15000D01*
G01X632500Y-20167D02*
X632367Y-20083D01*
Y-19917D01*
X632500Y-19833D01*
X632633Y-19917D01*
Y-20083D01*
X632500Y-20167D01*
G01X637467Y-20000D02*
X637600Y-18917D01*
X637800Y-18000D01*
X638067Y-17167D01*
X638400Y-16250D01*
X638933Y-15000D01*
X636267D01*
G01X640700Y-20000D02*
Y-16667D01*
G01Y-17583D02*
X640900Y-17167D01*
X641233Y-16833D01*
X641700Y-16667D01*
X642167Y-16833D01*
X642500Y-17167D01*
X642700Y-17583D01*
Y-20000D01*
G01Y-17583D02*
X642900Y-17167D01*
X643233Y-16833D01*
X643700Y-16667D01*
X644167Y-16833D01*
X644500Y-17167D01*
X644700Y-17667D01*
Y-20000D01*
G01X647800Y-16667D02*
Y-20000D01*
G01Y-15333D02*
X647667Y-15250D01*
Y-15083D01*
X647800Y-15000D01*
X647933Y-15083D01*
Y-15250D01*
X647800Y-15333D01*
G01X652900Y-20000D02*
Y-15000D01*
G01X606267Y24667D02*
X607867D01*
G01X607000Y25750D02*
Y23583D01*
G01X610900Y22833D02*
X613300Y28000D01*
G01X616333Y24667D02*
X618067D01*
G01X622300Y23000D02*
Y28000D01*
X621500Y27000D01*
G01Y23000D02*
X623100D01*
G01X625400D02*
Y26333D01*
G01Y25417D02*
X625600Y25833D01*
X625933Y26167D01*
X626400Y26333D01*
X626867Y26167D01*
X627200Y25833D01*
X627400Y25417D01*
Y23000D01*
G01Y25417D02*
X627600Y25833D01*
X627933Y26167D01*
X628400Y26333D01*
X628867Y26167D01*
X629200Y25833D01*
X629400Y25333D01*
Y23000D01*
G01X632500Y26333D02*
Y23000D01*
G01Y27667D02*
X632367Y27750D01*
Y27917D01*
X632500Y28000D01*
X632633Y27917D01*
Y27750D01*
X632500Y27667D01*
G01X637600Y23000D02*
Y28000D01*
G01X606267Y13167D02*
X607867D01*
G01X607000Y14250D02*
Y12083D01*
G01X610900Y11333D02*
X613300Y16500D01*
G01X616333Y13167D02*
X618067D01*
G01X621033Y15667D02*
X621433Y16167D01*
X621900Y16417D01*
X622433Y16500D01*
X623100Y16333D01*
X623567Y15917D01*
X623700Y15417D01*
X623633Y14917D01*
X623367Y14500D01*
X622033Y13667D01*
X621433Y13083D01*
X621033Y12250D01*
X620900Y11500D01*
X623700D01*
G01X625400D02*
Y14833D01*
G01Y13917D02*
X625600Y14333D01*
X625933Y14667D01*
X626400Y14833D01*
X626867Y14667D01*
X627200Y14333D01*
X627400Y13917D01*
Y11500D01*
G01Y13917D02*
X627600Y14333D01*
X627933Y14667D01*
X628400Y14833D01*
X628867Y14667D01*
X629200Y14333D01*
X629400Y13833D01*
Y11500D01*
G01X632500Y14833D02*
Y11500D01*
G01Y16167D02*
X632367Y16250D01*
Y16417D01*
X632500Y16500D01*
X632633Y16417D01*
Y16250D01*
X632500Y16167D01*
G01X637600Y11500D02*
Y16500D01*
G01X606267Y68167D02*
X607867D01*
G01X607000Y69250D02*
Y67083D01*
G01X610900Y66333D02*
X613300Y71500D01*
G01X616333Y68167D02*
X618067D01*
G01X622300Y66500D02*
Y71500D01*
X621500Y70500D01*
G01Y66500D02*
X623100D01*
G01X625933Y67250D02*
X626333Y66833D01*
X626800Y66583D01*
X627400Y66500D01*
X628000Y66667D01*
X628467Y67000D01*
X628800Y67583D01*
X628867Y68250D01*
X628733Y68917D01*
X628400Y69333D01*
X627933Y69667D01*
X627467Y69750D01*
X627000Y69667D01*
X626400Y69333D01*
X626600Y71500D01*
X628400D01*
G01X631300Y66333D02*
X633700Y71500D01*
G01X631300D02*
X630900Y71333D01*
X630700Y71083D01*
X630567Y70583D01*
X630700Y70083D01*
X630900Y69833D01*
X631300Y69667D01*
X631700Y69833D01*
X631900Y70083D01*
X632033Y70583D01*
X631900Y71083D01*
X631700Y71333D01*
X631300Y71500D01*
G01X633700Y68167D02*
X633300Y68000D01*
X633100Y67750D01*
X632967Y67250D01*
X633100Y66750D01*
X633300Y66500D01*
X633700Y66333D01*
X634100Y66500D01*
X634300Y66750D01*
X634433Y67250D01*
X634300Y67750D01*
X634100Y68000D01*
X633700Y68167D01*
G01X606267Y83167D02*
X607867D01*
G01X607000Y84250D02*
Y82083D01*
G01X610900Y81333D02*
X613300Y86500D01*
G01X616333Y83167D02*
X618067D01*
G01X622300Y81500D02*
Y86500D01*
X621500Y85500D01*
G01Y81500D02*
X623100D01*
G01X625400D02*
Y84833D01*
G01Y83917D02*
X625600Y84333D01*
X625933Y84667D01*
X626400Y84833D01*
X626867Y84667D01*
X627200Y84333D01*
X627400Y83917D01*
Y81500D01*
G01Y83917D02*
X627600Y84333D01*
X627933Y84667D01*
X628400Y84833D01*
X628867Y84667D01*
X629200Y84333D01*
X629400Y83833D01*
Y81500D01*
G01X632500Y84833D02*
Y81500D01*
G01Y86167D02*
X632367Y86250D01*
Y86417D01*
X632500Y86500D01*
X632633Y86417D01*
Y86250D01*
X632500Y86167D01*
G01X637600Y81500D02*
Y86500D01*
G01X606267Y48667D02*
X607867D01*
G01X607000Y49750D02*
Y47583D01*
G01X610900Y46833D02*
X613300Y52000D01*
G01X616333Y48667D02*
X618067D01*
G01X621033Y51167D02*
X621433Y51667D01*
X621900Y51917D01*
X622433Y52000D01*
X623100Y51833D01*
X623567Y51417D01*
X623700Y50917D01*
X623633Y50417D01*
X623367Y50000D01*
X622033Y49167D01*
X621433Y48583D01*
X621033Y47750D01*
X620900Y47000D01*
X623700D01*
G01X625400D02*
Y50333D01*
G01Y49417D02*
X625600Y49833D01*
X625933Y50167D01*
X626400Y50333D01*
X626867Y50167D01*
X627200Y49833D01*
X627400Y49417D01*
Y47000D01*
G01Y49417D02*
X627600Y49833D01*
X627933Y50167D01*
X628400Y50333D01*
X628867Y50167D01*
X629200Y49833D01*
X629400Y49333D01*
Y47000D01*
G01X632500Y50333D02*
Y47000D01*
G01Y51667D02*
X632367Y51750D01*
Y51917D01*
X632500Y52000D01*
X632633Y51917D01*
Y51750D01*
X632500Y51667D01*
G01X637600Y47000D02*
Y52000D01*
G01X605667Y144000D02*
X608333Y145667D01*
X605667Y147333D01*
G01X611233Y144917D02*
X612967D01*
G01Y146417D02*
X611233D01*
G01X617200Y144000D02*
Y149000D01*
X616400Y148000D01*
G01Y144000D02*
X618000D01*
G01X622300Y143833D02*
X622167Y143917D01*
Y144083D01*
X622300Y144167D01*
X622433Y144083D01*
Y143917D01*
X622300Y143833D01*
G01X625933Y144750D02*
X626333Y144333D01*
X626800Y144083D01*
X627400Y144000D01*
X628000Y144167D01*
X628467Y144500D01*
X628800Y145083D01*
X628867Y145750D01*
X628733Y146417D01*
X628400Y146833D01*
X627933Y147167D01*
X627467Y147250D01*
X627000Y147167D01*
X626400Y146833D01*
X626600Y149000D01*
X628400D01*
G01X630500Y144000D02*
Y147333D01*
G01Y146417D02*
X630700Y146833D01*
X631033Y147167D01*
X631500Y147333D01*
X631967Y147167D01*
X632300Y146833D01*
X632500Y146417D01*
Y144000D01*
G01Y146417D02*
X632700Y146833D01*
X633033Y147167D01*
X633500Y147333D01*
X633967Y147167D01*
X634300Y146833D01*
X634500Y146333D01*
Y144000D01*
G01X637600Y147333D02*
Y144000D01*
G01Y148667D02*
X637467Y148750D01*
Y148917D01*
X637600Y149000D01*
X637733Y148917D01*
Y148750D01*
X637600Y148667D01*
G01X642700Y144000D02*
Y149000D01*
G01X605667Y126500D02*
X608333Y128167D01*
X605667Y129833D01*
G01X611233Y127417D02*
X612967D01*
G01Y128917D02*
X611233D01*
G01X617200Y126500D02*
Y131500D01*
X616400Y130500D01*
G01Y126500D02*
X618000D01*
G01X622300Y126333D02*
X622167Y126417D01*
Y126583D01*
X622300Y126667D01*
X622433Y126583D01*
Y126417D01*
X622300Y126333D01*
G01X627400Y131500D02*
X626867Y131333D01*
X626467Y130917D01*
X626200Y130417D01*
X626000Y129750D01*
X625933Y129000D01*
X626000Y128250D01*
X626200Y127583D01*
X626467Y127083D01*
X626867Y126667D01*
X627400Y126500D01*
X627933Y126667D01*
X628333Y127083D01*
X628600Y127583D01*
X628800Y128250D01*
X628867Y129000D01*
X628800Y129750D01*
X628600Y130417D01*
X628333Y130917D01*
X627933Y131333D01*
X627400Y131500D01*
G01X630500Y126500D02*
Y129833D01*
G01Y128917D02*
X630700Y129333D01*
X631033Y129667D01*
X631500Y129833D01*
X631967Y129667D01*
X632300Y129333D01*
X632500Y128917D01*
Y126500D01*
G01Y128917D02*
X632700Y129333D01*
X633033Y129667D01*
X633500Y129833D01*
X633967Y129667D01*
X634300Y129333D01*
X634500Y128833D01*
Y126500D01*
G01X637600Y129833D02*
Y126500D01*
G01Y131167D02*
X637467Y131250D01*
Y131417D01*
X637600Y131500D01*
X637733Y131417D01*
Y131250D01*
X637600Y131167D01*
G01X642700Y126500D02*
Y131500D01*
G01X606267Y98167D02*
X607867D01*
G01X607000Y99250D02*
Y97083D01*
G01X610900Y96333D02*
X613300Y101500D01*
G01X616333Y98167D02*
X618067D01*
G01X621033Y100667D02*
X621433Y101167D01*
X621900Y101417D01*
X622433Y101500D01*
X623100Y101333D01*
X623567Y100917D01*
X623700Y100417D01*
X623633Y99917D01*
X623367Y99500D01*
X622033Y98667D01*
X621433Y98083D01*
X621033Y97250D01*
X620900Y96500D01*
X623700D01*
G01X627400Y101500D02*
X626867Y101333D01*
X626467Y100917D01*
X626200Y100417D01*
X626000Y99750D01*
X625933Y99000D01*
X626000Y98250D01*
X626200Y97583D01*
X626467Y97083D01*
X626867Y96667D01*
X627400Y96500D01*
X627933Y96667D01*
X628333Y97083D01*
X628600Y97583D01*
X628800Y98250D01*
X628867Y99000D01*
X628800Y99750D01*
X628600Y100417D01*
X628333Y100917D01*
X627933Y101333D01*
X627400Y101500D01*
G01X631300Y96333D02*
X633700Y101500D01*
G01X631300D02*
X630900Y101333D01*
X630700Y101083D01*
X630567Y100583D01*
X630700Y100083D01*
X630900Y99833D01*
X631300Y99667D01*
X631700Y99833D01*
X631900Y100083D01*
X632033Y100583D01*
X631900Y101083D01*
X631700Y101333D01*
X631300Y101500D01*
G01X633700Y98167D02*
X633300Y98000D01*
X633100Y97750D01*
X632967Y97250D01*
X633100Y96750D01*
X633300Y96500D01*
X633700Y96333D01*
X634100Y96500D01*
X634300Y96750D01*
X634433Y97250D01*
X634300Y97750D01*
X634100Y98000D01*
X633700Y98167D01*
G01X606267Y113167D02*
X607867D01*
G01X607000Y114250D02*
Y112083D01*
G01X610900Y111333D02*
X613300Y116500D01*
G01X616333Y113167D02*
X618067D01*
G01X620833Y112500D02*
X621233Y111917D01*
X621767Y111583D01*
X622367Y111500D01*
X622900Y111583D01*
X623433Y112000D01*
X623767Y112500D01*
X623833Y113000D01*
X623700Y113583D01*
X623233Y114000D01*
X622767Y114167D01*
X622167D01*
G01X622767D02*
X623167Y114417D01*
X623500Y114833D01*
X623633Y115333D01*
X623500Y115833D01*
X623167Y116250D01*
X622567Y116500D01*
X621967Y116417D01*
X621367Y116083D01*
G01X625400Y111500D02*
Y114833D01*
G01Y113917D02*
X625600Y114333D01*
X625933Y114667D01*
X626400Y114833D01*
X626867Y114667D01*
X627200Y114333D01*
X627400Y113917D01*
Y111500D01*
G01Y113917D02*
X627600Y114333D01*
X627933Y114667D01*
X628400Y114833D01*
X628867Y114667D01*
X629200Y114333D01*
X629400Y113833D01*
Y111500D01*
G01X632500Y114833D02*
Y111500D01*
G01Y116167D02*
X632367Y116250D01*
Y116417D01*
X632500Y116500D01*
X632633Y116417D01*
Y116250D01*
X632500Y116167D01*
G01X637600Y111500D02*
Y116500D01*
G01X612143Y200490D02*
X609477Y202157D01*
X612143Y203823D01*
G01X615910Y205490D02*
X615377Y205323D01*
X614977Y204907D01*
X614710Y204407D01*
X614510Y203740D01*
X614443Y202990D01*
X614510Y202240D01*
X614710Y201573D01*
X614977Y201073D01*
X615377Y200657D01*
X615910Y200490D01*
X616443Y200657D01*
X616843Y201073D01*
X617110Y201573D01*
X617310Y202240D01*
X617377Y202990D01*
X617310Y203740D01*
X617110Y204407D01*
X616843Y204907D01*
X616443Y205323D01*
X615910Y205490D01*
G01X621010Y200323D02*
X620877Y200407D01*
Y200573D01*
X621010Y200657D01*
X621143Y200573D01*
Y200407D01*
X621010Y200323D01*
G01X624643Y201490D02*
X625043Y200907D01*
X625577Y200573D01*
X626177Y200490D01*
X626710Y200573D01*
X627243Y200990D01*
X627577Y201490D01*
X627643Y201990D01*
X627510Y202573D01*
X627043Y202990D01*
X626577Y203157D01*
X625977D01*
G01X626577D02*
X626977Y203407D01*
X627310Y203823D01*
X627443Y204323D01*
X627310Y204823D01*
X626977Y205240D01*
X626377Y205490D01*
X625777Y205407D01*
X625177Y205073D01*
G01X629210Y200490D02*
Y203823D01*
G01Y202907D02*
X629410Y203323D01*
X629743Y203657D01*
X630210Y203823D01*
X630677Y203657D01*
X631010Y203323D01*
X631210Y202907D01*
Y200490D01*
G01Y202907D02*
X631410Y203323D01*
X631743Y203657D01*
X632210Y203823D01*
X632677Y203657D01*
X633010Y203323D01*
X633210Y202823D01*
Y200490D01*
G01X636310Y203823D02*
Y200490D01*
G01Y205157D02*
X636177Y205240D01*
Y205407D01*
X636310Y205490D01*
X636443Y205407D01*
Y205240D01*
X636310Y205157D01*
G01X641410Y200490D02*
Y205490D01*
G01X605667Y166500D02*
X608333Y168167D01*
X605667Y169833D01*
G01X611233Y167417D02*
X612967D01*
G01Y168917D02*
X611233D01*
G01X617200Y166500D02*
Y171500D01*
X616400Y170500D01*
G01Y166500D02*
X618000D01*
G01X622300Y166333D02*
X622167Y166417D01*
Y166583D01*
X622300Y166667D01*
X622433Y166583D01*
Y166417D01*
X622300Y166333D01*
G01X625933Y167500D02*
X626333Y166917D01*
X626867Y166583D01*
X627467Y166500D01*
X628000Y166583D01*
X628533Y167000D01*
X628867Y167500D01*
X628933Y168000D01*
X628800Y168583D01*
X628333Y169000D01*
X627867Y169167D01*
X627267D01*
G01X627867D02*
X628267Y169417D01*
X628600Y169833D01*
X628733Y170333D01*
X628600Y170833D01*
X628267Y171250D01*
X627667Y171500D01*
X627067Y171417D01*
X626467Y171083D01*
G01X630500Y166500D02*
Y169833D01*
G01Y168917D02*
X630700Y169333D01*
X631033Y169667D01*
X631500Y169833D01*
X631967Y169667D01*
X632300Y169333D01*
X632500Y168917D01*
Y166500D01*
G01Y168917D02*
X632700Y169333D01*
X633033Y169667D01*
X633500Y169833D01*
X633967Y169667D01*
X634300Y169333D01*
X634500Y168833D01*
Y166500D01*
G01X637600Y169833D02*
Y166500D01*
G01Y171167D02*
X637467Y171250D01*
Y171417D01*
X637600Y171500D01*
X637733Y171417D01*
Y171250D01*
X637600Y171167D01*
G01X642700Y166500D02*
Y171500D01*
G01X611543Y255680D02*
X608877Y257347D01*
X611543Y259013D01*
G01X615310Y255680D02*
Y260680D01*
X614510Y259680D01*
G01Y255680D02*
X616110D01*
G01X618410D02*
Y259013D01*
G01Y258097D02*
X618610Y258513D01*
X618943Y258847D01*
X619410Y259013D01*
X619877Y258847D01*
X620210Y258513D01*
X620410Y258097D01*
Y255680D01*
G01Y258097D02*
X620610Y258513D01*
X620943Y258847D01*
X621410Y259013D01*
X621877Y258847D01*
X622210Y258513D01*
X622410Y258013D01*
Y255680D01*
G01X625510Y259013D02*
Y255680D01*
G01Y260347D02*
X625377Y260430D01*
Y260597D01*
X625510Y260680D01*
X625643Y260597D01*
Y260430D01*
X625510Y260347D01*
G01X630610Y255680D02*
Y260680D01*
G01X602120Y310470D02*
Y313803D01*
G01Y312887D02*
X602320Y313303D01*
X602653Y313637D01*
X603120Y313803D01*
X603587Y313637D01*
X603920Y313303D01*
X604120Y312887D01*
Y310470D01*
G01Y312887D02*
X604320Y313303D01*
X604653Y313637D01*
X605120Y313803D01*
X605587Y313637D01*
X605920Y313303D01*
X606120Y312803D01*
Y310470D01*
G01X608087Y313803D02*
Y311470D01*
X608353Y310887D01*
X608753Y310553D01*
X609220Y310470D01*
X609687Y310553D01*
X610087Y310887D01*
X610353Y311470D01*
G01Y310470D02*
Y313803D01*
G01X613320Y311053D02*
X613653Y310720D01*
X614120Y310470D01*
X614520D01*
X614920Y310637D01*
X615187Y310887D01*
X615320Y311220D01*
X615253Y311720D01*
X614987Y311970D01*
X613787Y312470D01*
X613520Y313053D01*
X613653Y313470D01*
X613920Y313720D01*
X614320Y313803D01*
X614720Y313720D01*
X615120Y313470D01*
G01X619420Y315470D02*
Y310470D01*
G01X618487Y313803D02*
X620353D01*
G01X625853Y310470D02*
X623187Y312137D01*
X625853Y313803D01*
G01X627953Y310470D02*
X629620Y315470D01*
X631287Y310470D01*
G01X630687Y312220D02*
X628553D01*
G01X641020Y315470D02*
Y310470D01*
G01Y311220D02*
X640753Y310803D01*
X640353Y310553D01*
X639887Y310470D01*
X639353Y310637D01*
X638953Y311053D01*
X638687Y311553D01*
X638620Y312137D01*
X638687Y312720D01*
X638953Y313220D01*
X639353Y313637D01*
X639887Y313803D01*
X640353Y313720D01*
X640687Y313553D01*
X641020Y313220D01*
G01X644920Y313803D02*
Y310470D01*
G01Y315137D02*
X644787Y315220D01*
Y315387D01*
X644920Y315470D01*
X645053Y315387D01*
Y315220D01*
X644920Y315137D01*
G01X651220Y310470D02*
Y313803D01*
G01Y313220D02*
X650953Y313553D01*
X650553Y313720D01*
X650087Y313803D01*
X649620Y313637D01*
X649220Y313303D01*
X648953Y312803D01*
X648820Y312137D01*
X648953Y311470D01*
X649220Y310970D01*
X649620Y310637D01*
X650087Y310470D01*
X650553Y310553D01*
X650953Y310803D01*
X651220Y311137D01*
G01X653120Y310470D02*
Y313803D01*
G01Y312887D02*
X653320Y313303D01*
X653653Y313637D01*
X654120Y313803D01*
X654587Y313637D01*
X654920Y313303D01*
X655120Y312887D01*
Y310470D01*
G01Y312887D02*
X655320Y313303D01*
X655653Y313637D01*
X656120Y313803D01*
X656587Y313637D01*
X656920Y313303D01*
X657120Y312803D01*
Y310470D01*
G01X659220Y312720D02*
X661353D01*
X661153Y313303D01*
X660820Y313637D01*
X660353Y313803D01*
X659887Y313720D01*
X659487Y313470D01*
X659220Y312887D01*
X659087Y312387D01*
Y311887D01*
X659220Y311387D01*
X659553Y310887D01*
X659953Y310553D01*
X660420Y310470D01*
X660887Y310637D01*
X661353Y311137D01*
G01X665320Y315470D02*
Y310470D01*
G01X664387Y313803D02*
X666253D01*
G01X669420Y312720D02*
X671553D01*
X671353Y313303D01*
X671020Y313637D01*
X670553Y313803D01*
X670087Y313720D01*
X669687Y313470D01*
X669420Y312887D01*
X669287Y312387D01*
Y311887D01*
X669420Y311387D01*
X669753Y310887D01*
X670153Y310553D01*
X670620Y310470D01*
X671087Y310637D01*
X671553Y311137D01*
G01X674587Y310470D02*
Y313803D01*
G01Y313137D02*
X674920Y313470D01*
X675253Y313720D01*
X675720Y313803D01*
X676053Y313720D01*
X676453Y313470D01*
G01X602500Y319240D02*
Y324240D01*
G01Y321740D02*
X602833Y322240D01*
X603233Y322490D01*
X603633Y322573D01*
X604233Y322407D01*
X604633Y322073D01*
X604900Y321490D01*
Y320823D01*
X604767Y320157D01*
X604500Y319657D01*
X604033Y319323D01*
X603633Y319240D01*
X603233Y319323D01*
X602833Y319573D01*
X602500Y319990D01*
G01X607667Y322573D02*
Y320240D01*
X607933Y319657D01*
X608333Y319323D01*
X608800Y319240D01*
X609267Y319323D01*
X609667Y319657D01*
X609933Y320240D01*
G01Y319240D02*
Y322573D01*
G01X613900Y324240D02*
Y319240D01*
G01X612967Y322573D02*
X614833D01*
G01X624633Y321907D02*
X624900Y322157D01*
X625100Y322573D01*
X625233Y323157D01*
X625100Y323657D01*
X624833Y323990D01*
X624367Y324240D01*
X622567D01*
Y319240D01*
X624767D01*
X625233Y319573D01*
X625500Y320073D01*
X625633Y320657D01*
X625500Y321240D01*
X625100Y321740D01*
X624633Y321907D01*
X622567D01*
G01X635500Y324240D02*
Y319240D01*
G01Y319990D02*
X635233Y319573D01*
X634833Y319323D01*
X634367Y319240D01*
X633833Y319407D01*
X633433Y319823D01*
X633167Y320323D01*
X633100Y320907D01*
X633167Y321490D01*
X633433Y321990D01*
X633833Y322407D01*
X634367Y322573D01*
X634833Y322490D01*
X635167Y322323D01*
X635500Y321990D01*
G01X639400Y322573D02*
Y319240D01*
G01Y323907D02*
X639267Y323990D01*
Y324157D01*
X639400Y324240D01*
X639533Y324157D01*
Y323990D01*
X639400Y323907D01*
G01X645700Y319240D02*
Y322573D01*
G01Y321990D02*
X645433Y322323D01*
X645033Y322490D01*
X644567Y322573D01*
X644100Y322407D01*
X643700Y322073D01*
X643433Y321573D01*
X643300Y320907D01*
X643433Y320240D01*
X643700Y319740D01*
X644100Y319407D01*
X644567Y319240D01*
X645033Y319323D01*
X645433Y319573D01*
X645700Y319907D01*
G01X647600Y319240D02*
Y322573D01*
G01Y321657D02*
X647800Y322073D01*
X648133Y322407D01*
X648600Y322573D01*
X649067Y322407D01*
X649400Y322073D01*
X649600Y321657D01*
Y319240D01*
G01Y321657D02*
X649800Y322073D01*
X650133Y322407D01*
X650600Y322573D01*
X651067Y322407D01*
X651400Y322073D01*
X651600Y321573D01*
Y319240D01*
G01X653700Y321490D02*
X655833D01*
X655633Y322073D01*
X655300Y322407D01*
X654833Y322573D01*
X654367Y322490D01*
X653967Y322240D01*
X653700Y321657D01*
X653567Y321157D01*
Y320657D01*
X653700Y320157D01*
X654033Y319657D01*
X654433Y319323D01*
X654900Y319240D01*
X655367Y319407D01*
X655833Y319907D01*
G01X659800Y324240D02*
Y319240D01*
G01X658867Y322573D02*
X660733D01*
G01X663900Y321490D02*
X666033D01*
X665833Y322073D01*
X665500Y322407D01*
X665033Y322573D01*
X664567Y322490D01*
X664167Y322240D01*
X663900Y321657D01*
X663767Y321157D01*
Y320657D01*
X663900Y320157D01*
X664233Y319657D01*
X664633Y319323D01*
X665100Y319240D01*
X665567Y319407D01*
X666033Y319907D01*
G01X669067Y319240D02*
Y322573D01*
G01Y321907D02*
X669400Y322240D01*
X669733Y322490D01*
X670200Y322573D01*
X670533Y322490D01*
X670933Y322240D01*
G01X607563Y295230D02*
X604897Y296897D01*
X607563Y298563D01*
G01X610197Y295813D02*
X610663Y295397D01*
X611197Y295230D01*
X611730Y295397D01*
X612197Y295897D01*
X612530Y296647D01*
X612663Y297397D01*
Y298313D01*
X612530Y299063D01*
X612197Y299730D01*
X611797Y300063D01*
X611330Y300230D01*
X610797Y300063D01*
X610397Y299730D01*
X610130Y299230D01*
X609997Y298563D01*
X610130Y297980D01*
X610463Y297397D01*
X610863Y297063D01*
X611330Y296980D01*
X611863Y297147D01*
X612263Y297563D01*
X612663Y298313D01*
G01X616430Y300230D02*
X615897Y300063D01*
X615497Y299647D01*
X615230Y299147D01*
X615030Y298480D01*
X614963Y297730D01*
X615030Y296980D01*
X615230Y296313D01*
X615497Y295813D01*
X615897Y295397D01*
X616430Y295230D01*
X616963Y295397D01*
X617363Y295813D01*
X617630Y296313D01*
X617830Y296980D01*
X617897Y297730D01*
X617830Y298480D01*
X617630Y299147D01*
X617363Y299647D01*
X616963Y300063D01*
X616430Y300230D01*
G01X627830D02*
Y295230D01*
G01Y295980D02*
X627563Y295563D01*
X627163Y295313D01*
X626697Y295230D01*
X626163Y295397D01*
X625763Y295813D01*
X625497Y296313D01*
X625430Y296897D01*
X625497Y297480D01*
X625763Y297980D01*
X626163Y298397D01*
X626697Y298563D01*
X627163Y298480D01*
X627497Y298313D01*
X627830Y297980D01*
G01X630730Y297480D02*
X632863D01*
X632663Y298063D01*
X632330Y298397D01*
X631863Y298563D01*
X631397Y298480D01*
X630997Y298230D01*
X630730Y297647D01*
X630597Y297147D01*
Y296647D01*
X630730Y296147D01*
X631063Y295647D01*
X631463Y295313D01*
X631930Y295230D01*
X632397Y295397D01*
X632863Y295897D01*
G01X635897Y293980D02*
X636363Y293647D01*
X636897Y293563D01*
X637363Y293647D01*
X637763Y294063D01*
X638030Y294647D01*
Y298563D01*
G01Y297897D02*
X637763Y298230D01*
X637363Y298480D01*
X636897Y298563D01*
X636363Y298397D01*
X636030Y298063D01*
X635763Y297480D01*
X635630Y296897D01*
X635697Y296397D01*
X635963Y295813D01*
X636363Y295397D01*
X636897Y295230D01*
X637297Y295313D01*
X637763Y295647D01*
X638030Y295980D01*
G01X640997Y295230D02*
Y298563D01*
G01Y297897D02*
X641330Y298230D01*
X641663Y298480D01*
X642130Y298563D01*
X642463Y298480D01*
X642863Y298230D01*
G01X646030Y297480D02*
X648163D01*
X647963Y298063D01*
X647630Y298397D01*
X647163Y298563D01*
X646697Y298480D01*
X646297Y298230D01*
X646030Y297647D01*
X645897Y297147D01*
Y296647D01*
X646030Y296147D01*
X646363Y295647D01*
X646763Y295313D01*
X647230Y295230D01*
X647697Y295397D01*
X648163Y295897D01*
G01X651130Y297480D02*
X653263D01*
X653063Y298063D01*
X652730Y298397D01*
X652263Y298563D01*
X651797Y298480D01*
X651397Y298230D01*
X651130Y297647D01*
X650997Y297147D01*
Y296647D01*
X651130Y296147D01*
X651463Y295647D01*
X651863Y295313D01*
X652330Y295230D01*
X652797Y295397D01*
X653263Y295897D01*
G01X603617Y329260D02*
X606283Y330927D01*
X603617Y332593D01*
G01X609183Y330177D02*
X610917D01*
G01Y331677D02*
X609183D01*
G01X615017Y329260D02*
X615150Y330343D01*
X615350Y331260D01*
X615617Y332093D01*
X615950Y333010D01*
X616483Y334260D01*
X613817D01*
G01X620250D02*
X619717Y334093D01*
X619317Y333677D01*
X619050Y333177D01*
X618850Y332510D01*
X618783Y331760D01*
X618850Y331010D01*
X619050Y330343D01*
X619317Y329843D01*
X619717Y329427D01*
X620250Y329260D01*
X620783Y329427D01*
X621183Y329843D01*
X621450Y330343D01*
X621650Y331010D01*
X621717Y331760D01*
X621650Y332510D01*
X621450Y333177D01*
X621183Y333677D01*
X620783Y334093D01*
X620250Y334260D01*
G01X624150Y329093D02*
X626550Y334260D01*
G01X624150D02*
X623750Y334093D01*
X623550Y333843D01*
X623417Y333343D01*
X623550Y332843D01*
X623750Y332593D01*
X624150Y332427D01*
X624550Y332593D01*
X624750Y332843D01*
X624883Y333343D01*
X624750Y333843D01*
X624550Y334093D01*
X624150Y334260D01*
G01X626550Y330927D02*
X626150Y330760D01*
X625950Y330510D01*
X625817Y330010D01*
X625950Y329510D01*
X626150Y329260D01*
X626550Y329093D01*
X626950Y329260D01*
X627150Y329510D01*
X627283Y330010D01*
X627150Y330510D01*
X626950Y330760D01*
X626550Y330927D01*
G01X630317Y328343D02*
X630583Y329427D01*
G01X605447Y349687D02*
X607047D01*
G01X606180Y350770D02*
Y348603D01*
G01X610080Y347853D02*
X612480Y353020D01*
G01X615513Y349687D02*
X617247D01*
G01X621480Y348020D02*
Y353020D01*
X620680Y352020D01*
G01Y348020D02*
X622280D01*
G01X624580D02*
Y351353D01*
G01Y350437D02*
X624780Y350853D01*
X625113Y351187D01*
X625580Y351353D01*
X626047Y351187D01*
X626380Y350853D01*
X626580Y350437D01*
Y348020D01*
G01Y350437D02*
X626780Y350853D01*
X627113Y351187D01*
X627580Y351353D01*
X628047Y351187D01*
X628380Y350853D01*
X628580Y350353D01*
Y348020D01*
G01X631680Y351353D02*
Y348020D01*
G01Y352687D02*
X631547Y352770D01*
Y352937D01*
X631680Y353020D01*
X631813Y352937D01*
Y352770D01*
X631680Y352687D01*
G01X636780Y348020D02*
Y353020D01*
G01X608267Y393000D02*
Y398000D01*
X610000Y393833D01*
X611733Y398000D01*
Y393000D01*
G01X613967Y396333D02*
Y394000D01*
X614233Y393417D01*
X614633Y393083D01*
X615100Y393000D01*
X615567Y393083D01*
X615967Y393417D01*
X616233Y394000D01*
G01Y393000D02*
Y396333D01*
G01X619200Y393583D02*
X619533Y393250D01*
X620000Y393000D01*
X620400D01*
X620800Y393167D01*
X621067Y393417D01*
X621200Y393750D01*
X621133Y394250D01*
X620867Y394500D01*
X619667Y395000D01*
X619400Y395583D01*
X619533Y396000D01*
X619800Y396250D01*
X620200Y396333D01*
X620600Y396250D01*
X621000Y396000D01*
G01X625300Y398000D02*
Y393000D01*
G01X624367Y396333D02*
X626233D01*
G01X635100Y393000D02*
Y397250D01*
X635233Y397667D01*
X635500Y397917D01*
X635900Y398000D01*
X636300Y397833D01*
X636500Y397417D01*
G01X635700Y396000D02*
X634367D01*
G01X640600Y393000D02*
X640200Y393083D01*
X639800Y393417D01*
X639533Y394000D01*
X639400Y394667D01*
X639533Y395333D01*
X639800Y395917D01*
X640200Y396250D01*
X640600Y396333D01*
X641000Y396250D01*
X641400Y395917D01*
X641667Y395333D01*
X641733Y394667D01*
X641667Y394000D01*
X641400Y393417D01*
X641000Y393083D01*
X640600Y393000D01*
G01X645700D02*
Y398000D01*
G01X650800Y393000D02*
Y398000D01*
G01X655900Y393000D02*
X655500Y393083D01*
X655100Y393417D01*
X654833Y394000D01*
X654700Y394667D01*
X654833Y395333D01*
X655100Y395917D01*
X655500Y396250D01*
X655900Y396333D01*
X656300Y396250D01*
X656700Y395917D01*
X656967Y395333D01*
X657033Y394667D01*
X656967Y394000D01*
X656700Y393417D01*
X656300Y393083D01*
X655900Y393000D01*
G01X659333Y396333D02*
X660133Y393000D01*
X661000Y396333D01*
X661867Y393000D01*
X662667Y396333D01*
G01X605410Y429990D02*
Y434240D01*
X605543Y434657D01*
X605810Y434907D01*
X606210Y434990D01*
X606610Y434823D01*
X606810Y434407D01*
G01X606010Y432990D02*
X604677D01*
G01X610910Y429990D02*
X610510Y430073D01*
X610110Y430407D01*
X609843Y430990D01*
X609710Y431657D01*
X609843Y432323D01*
X610110Y432907D01*
X610510Y433240D01*
X610910Y433323D01*
X611310Y433240D01*
X611710Y432907D01*
X611977Y432323D01*
X612043Y431657D01*
X611977Y430990D01*
X611710Y430407D01*
X611310Y430073D01*
X610910Y429990D01*
G01X616010D02*
Y434990D01*
G01X621110Y429990D02*
Y434990D01*
G01X626210Y429990D02*
X625810Y430073D01*
X625410Y430407D01*
X625143Y430990D01*
X625010Y431657D01*
X625143Y432323D01*
X625410Y432907D01*
X625810Y433240D01*
X626210Y433323D01*
X626610Y433240D01*
X627010Y432907D01*
X627277Y432323D01*
X627343Y431657D01*
X627277Y430990D01*
X627010Y430407D01*
X626610Y430073D01*
X626210Y429990D01*
G01X629643Y433323D02*
X630443Y429990D01*
X631310Y433323D01*
X632177Y429990D01*
X632977Y433323D01*
G01X642710Y434990D02*
Y429990D01*
G01Y430740D02*
X642443Y430323D01*
X642043Y430073D01*
X641577Y429990D01*
X641043Y430157D01*
X640643Y430573D01*
X640377Y431073D01*
X640310Y431657D01*
X640377Y432240D01*
X640643Y432740D01*
X641043Y433157D01*
X641577Y433323D01*
X642043Y433240D01*
X642377Y433073D01*
X642710Y432740D01*
G01X645677Y429990D02*
Y433323D01*
G01Y432657D02*
X646010Y432990D01*
X646343Y433240D01*
X646810Y433323D01*
X647143Y433240D01*
X647543Y432990D01*
G01X652910Y429990D02*
Y433323D01*
G01Y432740D02*
X652643Y433073D01*
X652243Y433240D01*
X651777Y433323D01*
X651310Y433157D01*
X650910Y432823D01*
X650643Y432323D01*
X650510Y431657D01*
X650643Y430990D01*
X650910Y430490D01*
X651310Y430157D01*
X651777Y429990D01*
X652243Y430073D01*
X652643Y430323D01*
X652910Y430657D01*
G01X655143Y433323D02*
X655943Y429990D01*
X656810Y433323D01*
X657677Y429990D01*
X658477Y433323D01*
G01X661910D02*
Y429990D01*
G01Y434657D02*
X661777Y434740D01*
Y434907D01*
X661910Y434990D01*
X662043Y434907D01*
Y434740D01*
X661910Y434657D01*
G01X665877Y429990D02*
Y433323D01*
G01Y432490D02*
X666143Y432907D01*
X666543Y433240D01*
X667077Y433323D01*
X667543Y433240D01*
X667943Y432907D01*
X668143Y432323D01*
Y429990D01*
G01X671177Y428740D02*
X671643Y428407D01*
X672177Y428323D01*
X672643Y428407D01*
X673043Y428823D01*
X673310Y429407D01*
Y433323D01*
G01Y432657D02*
X673043Y432990D01*
X672643Y433240D01*
X672177Y433323D01*
X671643Y433157D01*
X671310Y432823D01*
X671043Y432240D01*
X670910Y431657D01*
X670977Y431157D01*
X671243Y430573D01*
X671643Y430157D01*
X672177Y429990D01*
X672577Y430073D01*
X673043Y430407D01*
X673310Y430740D01*
G01X677543Y428323D02*
X678210Y429157D01*
X678543Y429990D01*
Y433323D01*
X678210Y434157D01*
X677543Y434990D01*
G01X650437Y438153D02*
X649770Y438987D01*
X649437Y439820D01*
Y443153D01*
X649770Y443987D01*
X650437Y444820D01*
G01X655870Y439820D02*
X655470Y439903D01*
X655070Y440237D01*
X654803Y440820D01*
X654670Y441487D01*
X654803Y442153D01*
X655070Y442737D01*
X655470Y443070D01*
X655870Y443153D01*
X656270Y443070D01*
X656670Y442737D01*
X656937Y442153D01*
X657003Y441487D01*
X656937Y440820D01*
X656670Y440237D01*
X656270Y439903D01*
X655870Y439820D01*
G01X660037D02*
Y443153D01*
G01Y442487D02*
X660370Y442820D01*
X660703Y443070D01*
X661170Y443153D01*
X661503Y443070D01*
X661903Y442820D01*
G01X606587Y440587D02*
X608187D01*
G01X607320Y441670D02*
Y439503D01*
G01X611220Y438753D02*
X613620Y443920D01*
G01X616653Y440587D02*
X618387D01*
G01X621153Y439670D02*
X621553Y439253D01*
X622020Y439003D01*
X622620Y438920D01*
X623220Y439087D01*
X623687Y439420D01*
X624020Y440003D01*
X624087Y440670D01*
X623953Y441337D01*
X623620Y441753D01*
X623153Y442087D01*
X622687Y442170D01*
X622220Y442087D01*
X621620Y441753D01*
X621820Y443920D01*
X623620D01*
G01X625720Y438920D02*
Y442253D01*
G01Y441337D02*
X625920Y441753D01*
X626253Y442087D01*
X626720Y442253D01*
X627187Y442087D01*
X627520Y441753D01*
X627720Y441337D01*
Y438920D01*
G01Y441337D02*
X627920Y441753D01*
X628253Y442087D01*
X628720Y442253D01*
X629187Y442087D01*
X629520Y441753D01*
X629720Y441253D01*
Y438920D01*
G01X632820Y442253D02*
Y438920D01*
G01Y443587D02*
X632687Y443670D01*
Y443837D01*
X632820Y443920D01*
X632953Y443837D01*
Y443670D01*
X632820Y443587D01*
G01X637920Y438920D02*
Y443920D01*
G01X607000Y452000D02*
Y457000D01*
X606200Y456000D01*
G01Y452000D02*
X607800D01*
G01X612100Y451833D02*
X611967Y451917D01*
Y452083D01*
X612100Y452167D01*
X612233Y452083D01*
Y451917D01*
X612100Y451833D01*
G01X617200Y457000D02*
X616667Y456833D01*
X616267Y456417D01*
X616000Y455917D01*
X615800Y455250D01*
X615733Y454500D01*
X615800Y453750D01*
X616000Y453083D01*
X616267Y452583D01*
X616667Y452167D01*
X617200Y452000D01*
X617733Y452167D01*
X618133Y452583D01*
X618400Y453083D01*
X618600Y453750D01*
X618667Y454500D01*
X618600Y455250D01*
X618400Y455917D01*
X618133Y456417D01*
X617733Y456833D01*
X617200Y457000D01*
G01X620300Y452000D02*
Y455333D01*
G01Y454417D02*
X620500Y454833D01*
X620833Y455167D01*
X621300Y455333D01*
X621767Y455167D01*
X622100Y454833D01*
X622300Y454417D01*
Y452000D01*
G01Y454417D02*
X622500Y454833D01*
X622833Y455167D01*
X623300Y455333D01*
X623767Y455167D01*
X624100Y454833D01*
X624300Y454333D01*
Y452000D01*
G01X627400Y455333D02*
Y452000D01*
G01Y456667D02*
X627267Y456750D01*
Y456917D01*
X627400Y457000D01*
X627533Y456917D01*
Y456750D01*
X627400Y456667D01*
G01X632500Y452000D02*
Y457000D01*
G01X640700Y452000D02*
Y455333D01*
G01Y454417D02*
X640900Y454833D01*
X641233Y455167D01*
X641700Y455333D01*
X642167Y455167D01*
X642500Y454833D01*
X642700Y454417D01*
Y452000D01*
G01Y454417D02*
X642900Y454833D01*
X643233Y455167D01*
X643700Y455333D01*
X644167Y455167D01*
X644500Y454833D01*
X644700Y454333D01*
Y452000D01*
G01X649000D02*
Y455333D01*
G01Y454750D02*
X648733Y455083D01*
X648333Y455250D01*
X647867Y455333D01*
X647400Y455167D01*
X647000Y454833D01*
X646733Y454333D01*
X646600Y453667D01*
X646733Y453000D01*
X647000Y452500D01*
X647400Y452167D01*
X647867Y452000D01*
X648333Y452083D01*
X648733Y452333D01*
X649000Y452667D01*
G01X651900Y455333D02*
X653900Y452000D01*
G01Y455333D02*
X651900Y452000D01*
G01X606267Y471667D02*
X607867D01*
G01X607000Y472750D02*
Y470583D01*
G01X610900Y469833D02*
X613300Y475000D01*
G01X616333Y471667D02*
X618067D01*
G01X620833Y470750D02*
X621233Y470333D01*
X621700Y470083D01*
X622300Y470000D01*
X622900Y470167D01*
X623367Y470500D01*
X623700Y471083D01*
X623767Y471750D01*
X623633Y472417D01*
X623300Y472833D01*
X622833Y473167D01*
X622367Y473250D01*
X621900Y473167D01*
X621300Y472833D01*
X621500Y475000D01*
X623300D01*
G01X625400Y470000D02*
Y473333D01*
G01Y472417D02*
X625600Y472833D01*
X625933Y473167D01*
X626400Y473333D01*
X626867Y473167D01*
X627200Y472833D01*
X627400Y472417D01*
Y470000D01*
G01Y472417D02*
X627600Y472833D01*
X627933Y473167D01*
X628400Y473333D01*
X628867Y473167D01*
X629200Y472833D01*
X629400Y472333D01*
Y470000D01*
G01X632500Y473333D02*
Y470000D01*
G01Y474667D02*
X632367Y474750D01*
Y474917D01*
X632500Y475000D01*
X632633Y474917D01*
Y474750D01*
X632500Y474667D01*
G01X637600Y470000D02*
Y475000D01*
G01X606267Y486667D02*
X607867D01*
G01X607000Y487750D02*
Y485583D01*
G01X610900Y484833D02*
X613300Y490000D01*
G01X616333Y486667D02*
X618067D01*
G01X620833Y485750D02*
X621233Y485333D01*
X621700Y485083D01*
X622300Y485000D01*
X622900Y485167D01*
X623367Y485500D01*
X623700Y486083D01*
X623767Y486750D01*
X623633Y487417D01*
X623300Y487833D01*
X622833Y488167D01*
X622367Y488250D01*
X621900Y488167D01*
X621300Y487833D01*
X621500Y490000D01*
X623300D01*
G01X625400Y485000D02*
Y488333D01*
G01Y487417D02*
X625600Y487833D01*
X625933Y488167D01*
X626400Y488333D01*
X626867Y488167D01*
X627200Y487833D01*
X627400Y487417D01*
Y485000D01*
G01Y487417D02*
X627600Y487833D01*
X627933Y488167D01*
X628400Y488333D01*
X628867Y488167D01*
X629200Y487833D01*
X629400Y487333D01*
Y485000D01*
G01X632500Y488333D02*
Y485000D01*
G01Y489667D02*
X632367Y489750D01*
Y489917D01*
X632500Y490000D01*
X632633Y489917D01*
Y489750D01*
X632500Y489667D01*
G01X637600Y485000D02*
Y490000D01*
G01X606267Y501667D02*
X607867D01*
G01X607000Y502750D02*
Y500583D01*
G01X610633Y501000D02*
X611033Y500417D01*
X611567Y500083D01*
X612167Y500000D01*
X612700Y500083D01*
X613233Y500500D01*
X613567Y501000D01*
X613633Y501500D01*
X613500Y502083D01*
X613033Y502500D01*
X612567Y502667D01*
X611967D01*
G01X612567D02*
X612967Y502917D01*
X613300Y503333D01*
X613433Y503833D01*
X613300Y504333D01*
X612967Y504750D01*
X612367Y505000D01*
X611767Y504917D01*
X611167Y504583D01*
G01X616000Y499833D02*
X618400Y505000D01*
G01X621433Y501667D02*
X623167D01*
G01X627400Y505000D02*
X626867Y504833D01*
X626467Y504417D01*
X626200Y503917D01*
X626000Y503250D01*
X625933Y502500D01*
X626000Y501750D01*
X626200Y501083D01*
X626467Y500583D01*
X626867Y500167D01*
X627400Y500000D01*
X627933Y500167D01*
X628333Y500583D01*
X628600Y501083D01*
X628800Y501750D01*
X628867Y502500D01*
X628800Y503250D01*
X628600Y503917D01*
X628333Y504417D01*
X627933Y504833D01*
X627400Y505000D01*
G01X630500Y500000D02*
Y503333D01*
G01Y502417D02*
X630700Y502833D01*
X631033Y503167D01*
X631500Y503333D01*
X631967Y503167D01*
X632300Y502833D01*
X632500Y502417D01*
Y500000D01*
G01Y502417D02*
X632700Y502833D01*
X633033Y503167D01*
X633500Y503333D01*
X633967Y503167D01*
X634300Y502833D01*
X634500Y502333D01*
Y500000D01*
G01X637600Y503333D02*
Y500000D01*
G01Y504667D02*
X637467Y504750D01*
Y504917D01*
X637600Y505000D01*
X637733Y504917D01*
Y504750D01*
X637600Y504667D01*
G01X642700Y500000D02*
Y505000D01*
G01X606267Y516667D02*
X607867D01*
G01X607000Y517750D02*
Y515583D01*
G01X610900Y514833D02*
X613300Y520000D01*
G01X616333Y516667D02*
X618067D01*
G01X621033Y519167D02*
X621433Y519667D01*
X621900Y519917D01*
X622433Y520000D01*
X623100Y519833D01*
X623567Y519417D01*
X623700Y518917D01*
X623633Y518417D01*
X623367Y518000D01*
X622033Y517167D01*
X621433Y516583D01*
X621033Y515750D01*
X620900Y515000D01*
X623700D01*
G01X625400D02*
Y518333D01*
G01Y517417D02*
X625600Y517833D01*
X625933Y518167D01*
X626400Y518333D01*
X626867Y518167D01*
X627200Y517833D01*
X627400Y517417D01*
Y515000D01*
G01Y517417D02*
X627600Y517833D01*
X627933Y518167D01*
X628400Y518333D01*
X628867Y518167D01*
X629200Y517833D01*
X629400Y517333D01*
Y515000D01*
G01X632500Y518333D02*
Y515000D01*
G01Y519667D02*
X632367Y519750D01*
Y519917D01*
X632500Y520000D01*
X632633Y519917D01*
Y519750D01*
X632500Y519667D01*
G01X637600Y515000D02*
Y520000D01*
G01X606267Y546667D02*
X607867D01*
G01X607000Y547750D02*
Y545583D01*
G01X610900Y544833D02*
X613300Y550000D01*
G01X616333Y546667D02*
X618067D01*
G01X621033Y549167D02*
X621433Y549667D01*
X621900Y549917D01*
X622433Y550000D01*
X623100Y549833D01*
X623567Y549417D01*
X623700Y548917D01*
X623633Y548417D01*
X623367Y548000D01*
X622033Y547167D01*
X621433Y546583D01*
X621033Y545750D01*
X620900Y545000D01*
X623700D01*
G01X625400D02*
Y548333D01*
G01Y547417D02*
X625600Y547833D01*
X625933Y548167D01*
X626400Y548333D01*
X626867Y548167D01*
X627200Y547833D01*
X627400Y547417D01*
Y545000D01*
G01Y547417D02*
X627600Y547833D01*
X627933Y548167D01*
X628400Y548333D01*
X628867Y548167D01*
X629200Y547833D01*
X629400Y547333D01*
Y545000D01*
G01X632500Y548333D02*
Y545000D01*
G01Y549667D02*
X632367Y549750D01*
Y549917D01*
X632500Y550000D01*
X632633Y549917D01*
Y549750D01*
X632500Y549667D01*
G01X637600Y545000D02*
Y550000D01*
G01X606267Y530167D02*
X607867D01*
G01X607000Y531250D02*
Y529083D01*
G01X610900Y528333D02*
X613300Y533500D01*
G01X616333Y530167D02*
X618067D01*
G01X620833Y529500D02*
X621233Y528917D01*
X621767Y528583D01*
X622367Y528500D01*
X622900Y528583D01*
X623433Y529000D01*
X623767Y529500D01*
X623833Y530000D01*
X623700Y530583D01*
X623233Y531000D01*
X622767Y531167D01*
X622167D01*
G01X622767D02*
X623167Y531417D01*
X623500Y531833D01*
X623633Y532333D01*
X623500Y532833D01*
X623167Y533250D01*
X622567Y533500D01*
X621967Y533417D01*
X621367Y533083D01*
G01X625400Y528500D02*
Y531833D01*
G01Y530917D02*
X625600Y531333D01*
X625933Y531667D01*
X626400Y531833D01*
X626867Y531667D01*
X627200Y531333D01*
X627400Y530917D01*
Y528500D01*
G01Y530917D02*
X627600Y531333D01*
X627933Y531667D01*
X628400Y531833D01*
X628867Y531667D01*
X629200Y531333D01*
X629400Y530833D01*
Y528500D01*
G01X632500Y531833D02*
Y528500D01*
G01Y533167D02*
X632367Y533250D01*
Y533417D01*
X632500Y533500D01*
X632633Y533417D01*
Y533250D01*
X632500Y533167D01*
G01X637600Y528500D02*
Y533500D01*
G01X606267Y575167D02*
X607867D01*
G01X607000Y576250D02*
Y574083D01*
G01X610833Y577667D02*
X611233Y578167D01*
X611700Y578417D01*
X612233Y578500D01*
X612900Y578333D01*
X613367Y577917D01*
X613500Y577417D01*
X613433Y576917D01*
X613167Y576500D01*
X611833Y575667D01*
X611233Y575083D01*
X610833Y574250D01*
X610700Y573500D01*
X613500D01*
G01X616000Y573333D02*
X618400Y578500D01*
G01X621433Y575167D02*
X623167D01*
G01X628200Y573500D02*
Y578500D01*
X625733Y574917D01*
X629067D01*
G01X630500Y573500D02*
Y576833D01*
G01Y575917D02*
X630700Y576333D01*
X631033Y576667D01*
X631500Y576833D01*
X631967Y576667D01*
X632300Y576333D01*
X632500Y575917D01*
Y573500D01*
G01Y575917D02*
X632700Y576333D01*
X633033Y576667D01*
X633500Y576833D01*
X633967Y576667D01*
X634300Y576333D01*
X634500Y575833D01*
Y573500D01*
G01X637600Y576833D02*
Y573500D01*
G01Y578167D02*
X637467Y578250D01*
Y578417D01*
X637600Y578500D01*
X637733Y578417D01*
Y578250D01*
X637600Y578167D01*
G01X642700Y573500D02*
Y578500D01*
G01X606267Y561667D02*
X607867D01*
G01X607000Y562750D02*
Y560583D01*
G01X610900Y559833D02*
X613300Y565000D01*
G01X616333Y561667D02*
X618067D01*
G01X621033Y564167D02*
X621433Y564667D01*
X621900Y564917D01*
X622433Y565000D01*
X623100Y564833D01*
X623567Y564417D01*
X623700Y563917D01*
X623633Y563417D01*
X623367Y563000D01*
X622033Y562167D01*
X621433Y561583D01*
X621033Y560750D01*
X620900Y560000D01*
X623700D01*
G01X625400D02*
Y563333D01*
G01Y562417D02*
X625600Y562833D01*
X625933Y563167D01*
X626400Y563333D01*
X626867Y563167D01*
X627200Y562833D01*
X627400Y562417D01*
Y560000D01*
G01Y562417D02*
X627600Y562833D01*
X627933Y563167D01*
X628400Y563333D01*
X628867Y563167D01*
X629200Y562833D01*
X629400Y562333D01*
Y560000D01*
G01X632500Y563333D02*
Y560000D01*
G01Y564667D02*
X632367Y564750D01*
Y564917D01*
X632500Y565000D01*
X632633Y564917D01*
Y564750D01*
X632500Y564667D01*
G01X637600Y560000D02*
Y565000D01*
G01X606267Y620167D02*
X607867D01*
G01X607000Y621250D02*
Y619083D01*
G01X610900Y618333D02*
X613300Y623500D01*
G01X616333Y620167D02*
X618067D01*
G01X621033Y622667D02*
X621433Y623167D01*
X621900Y623417D01*
X622433Y623500D01*
X623100Y623333D01*
X623567Y622917D01*
X623700Y622417D01*
X623633Y621917D01*
X623367Y621500D01*
X622033Y620667D01*
X621433Y620083D01*
X621033Y619250D01*
X620900Y618500D01*
X623700D01*
G01X625400D02*
Y621833D01*
G01Y620917D02*
X625600Y621333D01*
X625933Y621667D01*
X626400Y621833D01*
X626867Y621667D01*
X627200Y621333D01*
X627400Y620917D01*
Y618500D01*
G01Y620917D02*
X627600Y621333D01*
X627933Y621667D01*
X628400Y621833D01*
X628867Y621667D01*
X629200Y621333D01*
X629400Y620833D01*
Y618500D01*
G01X632500Y621833D02*
Y618500D01*
G01Y623167D02*
X632367Y623250D01*
Y623417D01*
X632500Y623500D01*
X632633Y623417D01*
Y623250D01*
X632500Y623167D01*
G01X637600Y618500D02*
Y623500D01*
G01X606267Y591667D02*
X607867D01*
G01X607000Y592750D02*
Y590583D01*
G01X610900Y589833D02*
X613300Y595000D01*
G01X616333Y591667D02*
X618067D01*
G01X620833Y591000D02*
X621233Y590417D01*
X621767Y590083D01*
X622367Y590000D01*
X622900Y590083D01*
X623433Y590500D01*
X623767Y591000D01*
X623833Y591500D01*
X623700Y592083D01*
X623233Y592500D01*
X622767Y592667D01*
X622167D01*
G01X622767D02*
X623167Y592917D01*
X623500Y593333D01*
X623633Y593833D01*
X623500Y594333D01*
X623167Y594750D01*
X622567Y595000D01*
X621967Y594917D01*
X621367Y594583D01*
G01X625400Y590000D02*
Y593333D01*
G01Y592417D02*
X625600Y592833D01*
X625933Y593167D01*
X626400Y593333D01*
X626867Y593167D01*
X627200Y592833D01*
X627400Y592417D01*
Y590000D01*
G01Y592417D02*
X627600Y592833D01*
X627933Y593167D01*
X628400Y593333D01*
X628867Y593167D01*
X629200Y592833D01*
X629400Y592333D01*
Y590000D01*
G01X632500Y593333D02*
Y590000D01*
G01Y594667D02*
X632367Y594750D01*
Y594917D01*
X632500Y595000D01*
X632633Y594917D01*
Y594750D01*
X632500Y594667D01*
G01X637600Y590000D02*
Y595000D01*
G01X605333Y603500D02*
X607000Y608500D01*
X608667Y603500D01*
G01X608067Y605250D02*
X605933D01*
G01X612100Y603500D02*
Y608500D01*
G01X617200Y603500D02*
Y608500D01*
G01X622300Y603500D02*
X621900Y603583D01*
X621500Y603917D01*
X621233Y604500D01*
X621100Y605167D01*
X621233Y605833D01*
X621500Y606417D01*
X621900Y606750D01*
X622300Y606833D01*
X622700Y606750D01*
X623100Y606417D01*
X623367Y605833D01*
X623433Y605167D01*
X623367Y604500D01*
X623100Y603917D01*
X622700Y603583D01*
X622300Y603500D01*
G01X625733Y606833D02*
X626533Y603500D01*
X627400Y606833D01*
X628267Y603500D01*
X629067Y606833D01*
G01X605287Y638700D02*
Y643700D01*
X607020Y639533D01*
X608753Y643700D01*
Y638700D01*
G01X610987Y642033D02*
Y639700D01*
X611253Y639117D01*
X611653Y638783D01*
X612120Y638700D01*
X612587Y638783D01*
X612987Y639117D01*
X613253Y639700D01*
G01Y638700D02*
Y642033D01*
G01X616220Y639283D02*
X616553Y638950D01*
X617020Y638700D01*
X617420D01*
X617820Y638867D01*
X618087Y639117D01*
X618220Y639450D01*
X618153Y639950D01*
X617887Y640200D01*
X616687Y640700D01*
X616420Y641283D01*
X616553Y641700D01*
X616820Y641950D01*
X617220Y642033D01*
X617620Y641950D01*
X618020Y641700D01*
G01X622320Y643700D02*
Y638700D01*
G01X621387Y642033D02*
X623253D01*
G01X632120Y638700D02*
Y642950D01*
X632253Y643367D01*
X632520Y643617D01*
X632920Y643700D01*
X633320Y643533D01*
X633520Y643117D01*
G01X632720Y641700D02*
X631387D01*
G01X637620Y638700D02*
X637220Y638783D01*
X636820Y639117D01*
X636553Y639700D01*
X636420Y640367D01*
X636553Y641033D01*
X636820Y641617D01*
X637220Y641950D01*
X637620Y642033D01*
X638020Y641950D01*
X638420Y641617D01*
X638687Y641033D01*
X638753Y640367D01*
X638687Y639700D01*
X638420Y639117D01*
X638020Y638783D01*
X637620Y638700D01*
G01X642720D02*
Y643700D01*
G01X647820Y638700D02*
Y643700D01*
G01X652920Y638700D02*
X652520Y638783D01*
X652120Y639117D01*
X651853Y639700D01*
X651720Y640367D01*
X651853Y641033D01*
X652120Y641617D01*
X652520Y641950D01*
X652920Y642033D01*
X653320Y641950D01*
X653720Y641617D01*
X653987Y641033D01*
X654053Y640367D01*
X653987Y639700D01*
X653720Y639117D01*
X653320Y638783D01*
X652920Y638700D01*
G01X656353Y642033D02*
X657153Y638700D01*
X658020Y642033D01*
X658887Y638700D01*
X659687Y642033D01*
G01X617000Y668500D02*
Y663500D01*
G01X615467Y668500D02*
X618533D01*
G01X622100Y663500D02*
X621700Y663583D01*
X621300Y663917D01*
X621033Y664500D01*
X620900Y665167D01*
X621033Y665833D01*
X621300Y666417D01*
X621700Y666750D01*
X622100Y666833D01*
X622500Y666750D01*
X622900Y666417D01*
X623167Y665833D01*
X623233Y665167D01*
X623167Y664500D01*
X622900Y663917D01*
X622500Y663583D01*
X622100Y663500D01*
G01X627200D02*
Y668500D01*
G01X631300Y665750D02*
X633433D01*
X633233Y666333D01*
X632900Y666667D01*
X632433Y666833D01*
X631967Y666750D01*
X631567Y666500D01*
X631300Y665917D01*
X631167Y665417D01*
Y664917D01*
X631300Y664417D01*
X631633Y663917D01*
X632033Y663583D01*
X632500Y663500D01*
X632967Y663667D01*
X633433Y664167D01*
G01X636467Y663500D02*
Y666833D01*
G01Y666167D02*
X636800Y666500D01*
X637133Y666750D01*
X637600Y666833D01*
X637933Y666750D01*
X638333Y666500D01*
G01X643700Y663500D02*
Y666833D01*
G01Y666250D02*
X643433Y666583D01*
X643033Y666750D01*
X642567Y666833D01*
X642100Y666667D01*
X641700Y666333D01*
X641433Y665833D01*
X641300Y665167D01*
X641433Y664500D01*
X641700Y664000D01*
X642100Y663667D01*
X642567Y663500D01*
X643033Y663583D01*
X643433Y663833D01*
X643700Y664167D01*
G01X646467Y663500D02*
Y666833D01*
G01Y666000D02*
X646733Y666417D01*
X647133Y666750D01*
X647667Y666833D01*
X648133Y666750D01*
X648533Y666417D01*
X648733Y665833D01*
Y663500D01*
G01X653767Y666417D02*
X653300Y666750D01*
X652900Y666833D01*
X652367Y666667D01*
X651967Y666333D01*
X651700Y665750D01*
X651633Y665167D01*
X651700Y664583D01*
X651967Y664083D01*
X652367Y663667D01*
X652900Y663500D01*
X653367Y663667D01*
X653767Y664000D01*
G01X656800Y665750D02*
X658933D01*
X658733Y666333D01*
X658400Y666667D01*
X657933Y666833D01*
X657467Y666750D01*
X657067Y666500D01*
X656800Y665917D01*
X656667Y665417D01*
Y664917D01*
X656800Y664417D01*
X657133Y663917D01*
X657533Y663583D01*
X658000Y663500D01*
X658467Y663667D01*
X658933Y664167D01*
G01X722533Y-38250D02*
X722933Y-38667D01*
X723400Y-38917D01*
X724000Y-39000D01*
X724600Y-38833D01*
X725067Y-38500D01*
X725400Y-37917D01*
X725467Y-37250D01*
X725333Y-36583D01*
X725000Y-36167D01*
X724533Y-35833D01*
X724067Y-35750D01*
X723600Y-35833D01*
X723000Y-36167D01*
X723200Y-34000D01*
X725000D01*
G01X729100Y-39167D02*
X728967Y-39083D01*
Y-38917D01*
X729100Y-38833D01*
X729233Y-38917D01*
Y-39083D01*
X729100Y-39167D01*
G01X737967Y-39000D02*
Y-34000D01*
X739633D01*
X740167Y-34250D01*
X740500Y-34583D01*
X740633Y-35250D01*
X740500Y-35917D01*
X740100Y-36333D01*
X739633Y-36583D01*
X737967D01*
G01X739633D02*
X740633Y-39000D01*
G01X743400Y-36750D02*
X745533D01*
X745333Y-36167D01*
X745000Y-35833D01*
X744533Y-35667D01*
X744067Y-35750D01*
X743667Y-36000D01*
X743400Y-36583D01*
X743267Y-37083D01*
Y-37583D01*
X743400Y-38083D01*
X743733Y-38583D01*
X744133Y-38917D01*
X744600Y-39000D01*
X745067Y-38833D01*
X745533Y-38333D01*
G01X747500Y-39000D02*
Y-35667D01*
G01Y-36583D02*
X747700Y-36167D01*
X748033Y-35833D01*
X748500Y-35667D01*
X748967Y-35833D01*
X749300Y-36167D01*
X749500Y-36583D01*
Y-39000D01*
G01Y-36583D02*
X749700Y-36167D01*
X750033Y-35833D01*
X750500Y-35667D01*
X750967Y-35833D01*
X751300Y-36167D01*
X751500Y-36667D01*
Y-39000D01*
G01X755800D02*
Y-35667D01*
G01Y-36250D02*
X755533Y-35917D01*
X755133Y-35750D01*
X754667Y-35667D01*
X754200Y-35833D01*
X753800Y-36167D01*
X753533Y-36667D01*
X753400Y-37333D01*
X753533Y-38000D01*
X753800Y-38500D01*
X754200Y-38833D01*
X754667Y-39000D01*
X755133Y-38917D01*
X755533Y-38667D01*
X755800Y-38333D01*
G01X758767Y-39000D02*
Y-35667D01*
G01Y-36333D02*
X759100Y-36000D01*
X759433Y-35750D01*
X759900Y-35667D01*
X760233Y-35750D01*
X760633Y-36000D01*
G01X763667Y-39000D02*
Y-34000D01*
G01X765800Y-35667D02*
X763667Y-37583D01*
G01X764533Y-36833D02*
X765933Y-39000D01*
G01X768433Y-39167D02*
X771367Y-35500D01*
G01X769900Y-34833D02*
Y-39833D01*
G01X771367Y-39167D02*
X768433Y-35500D01*
G01X767900Y-37333D02*
X771900D01*
G01X713000Y-53000D02*
X1343000D01*
G01X713000Y850500D02*
Y-73000D01*
X1343000D01*
Y782000D01*
X713000D01*
G01X694500Y716000D02*
Y-69500D01*
G01X713000Y-23000D02*
X1343000D01*
G01X713000Y85500D02*
X1343000D01*
G01X713000Y335500D02*
X1343000D01*
G01X720773Y374673D02*
X723707Y378340D01*
G01X722240Y379007D02*
Y374007D01*
G01X723707Y374673D02*
X720773Y378340D01*
G01X720240Y376507D02*
X724240D01*
G01X727007Y373173D02*
X726340Y374007D01*
X726007Y374840D01*
Y378173D01*
X726340Y379007D01*
X727007Y379840D01*
G01X730973Y375590D02*
X731373Y375173D01*
X731840Y374923D01*
X732440Y374840D01*
X733040Y375007D01*
X733507Y375340D01*
X733840Y375923D01*
X733907Y376590D01*
X733773Y377257D01*
X733440Y377673D01*
X732973Y378007D01*
X732507Y378090D01*
X732040Y378007D01*
X731440Y377673D01*
X731640Y379840D01*
X733440D01*
G01X737540Y374673D02*
X737407Y374757D01*
Y374923D01*
X737540Y375007D01*
X737673Y374923D01*
Y374757D01*
X737540Y374673D01*
G01X742640Y374840D02*
Y379840D01*
X741840Y378840D01*
G01Y374840D02*
X743440D01*
G01X748073Y373173D02*
X748740Y374007D01*
X749073Y374840D01*
Y378173D01*
X748740Y379007D01*
X748073Y379840D01*
G01X724800Y349500D02*
Y354500D01*
X722333Y350917D01*
X725667D01*
G01X729100Y349333D02*
X728967Y349417D01*
Y349583D01*
X729100Y349667D01*
X729233Y349583D01*
Y349417D01*
X729100Y349333D01*
G01X738100Y349500D02*
Y354500D01*
G01Y352000D02*
X738433Y352500D01*
X738833Y352750D01*
X739233Y352833D01*
X739833Y352667D01*
X740233Y352333D01*
X740500Y351750D01*
Y351083D01*
X740367Y350417D01*
X740100Y349917D01*
X739633Y349583D01*
X739233Y349500D01*
X738833Y349583D01*
X738433Y349833D01*
X738100Y350250D01*
G01X745600Y349500D02*
Y352833D01*
G01Y352250D02*
X745333Y352583D01*
X744933Y352750D01*
X744467Y352833D01*
X744000Y352667D01*
X743600Y352333D01*
X743333Y351833D01*
X743200Y351167D01*
X743333Y350500D01*
X743600Y350000D01*
X744000Y349667D01*
X744467Y349500D01*
X744933Y349583D01*
X745333Y349833D01*
X745600Y350167D01*
G01X750567Y352417D02*
X750100Y352750D01*
X749700Y352833D01*
X749167Y352667D01*
X748767Y352333D01*
X748500Y351750D01*
X748433Y351167D01*
X748500Y350583D01*
X748767Y350083D01*
X749167Y349667D01*
X749700Y349500D01*
X750167Y349667D01*
X750567Y350000D01*
G01X753467Y349500D02*
Y354500D01*
G01X755600Y352833D02*
X753467Y350917D01*
G01X754333Y351667D02*
X755733Y349500D01*
G01X760900Y354500D02*
Y349500D01*
G01Y350250D02*
X760633Y349833D01*
X760233Y349583D01*
X759767Y349500D01*
X759233Y349667D01*
X758833Y350083D01*
X758567Y350583D01*
X758500Y351167D01*
X758567Y351750D01*
X758833Y352250D01*
X759233Y352667D01*
X759767Y352833D01*
X760233Y352750D01*
X760567Y352583D01*
X760900Y352250D01*
G01X763867Y349500D02*
Y352833D01*
G01Y352167D02*
X764200Y352500D01*
X764533Y352750D01*
X765000Y352833D01*
X765333Y352750D01*
X765733Y352500D01*
G01X769900Y352833D02*
Y349500D01*
G01Y354167D02*
X769767Y354250D01*
Y354417D01*
X769900Y354500D01*
X770033Y354417D01*
Y354250D01*
X769900Y354167D01*
G01X775000Y349500D02*
Y354500D01*
G01X780100Y349500D02*
Y354500D01*
G01X791500Y349500D02*
Y352833D01*
G01Y352250D02*
X791233Y352583D01*
X790833Y352750D01*
X790367Y352833D01*
X789900Y352667D01*
X789500Y352333D01*
X789233Y351833D01*
X789100Y351167D01*
X789233Y350500D01*
X789500Y350000D01*
X789900Y349667D01*
X790367Y349500D01*
X790833Y349583D01*
X791233Y349833D01*
X791500Y350167D01*
G01X794267Y349500D02*
Y352833D01*
G01Y352000D02*
X794533Y352417D01*
X794933Y352750D01*
X795467Y352833D01*
X795933Y352750D01*
X796333Y352417D01*
X796533Y351833D01*
Y349500D01*
G01X801700Y354500D02*
Y349500D01*
G01Y350250D02*
X801433Y349833D01*
X801033Y349583D01*
X800567Y349500D01*
X800033Y349667D01*
X799633Y350083D01*
X799367Y350583D01*
X799300Y351167D01*
X799367Y351750D01*
X799633Y352250D01*
X800033Y352667D01*
X800567Y352833D01*
X801033Y352750D01*
X801367Y352583D01*
X801700Y352250D01*
G01X809700Y350083D02*
X810033Y349750D01*
X810500Y349500D01*
X810900D01*
X811300Y349667D01*
X811567Y349917D01*
X811700Y350250D01*
X811633Y350750D01*
X811367Y351000D01*
X810167Y351500D01*
X809900Y352083D01*
X810033Y352500D01*
X810300Y352750D01*
X810700Y352833D01*
X811100Y352750D01*
X811500Y352500D01*
G01X817000Y347833D02*
Y352833D01*
G01Y352083D02*
X816667Y352500D01*
X816267Y352750D01*
X815800Y352833D01*
X815400Y352750D01*
X814933Y352333D01*
X814667Y351750D01*
X814600Y351167D01*
X814667Y350583D01*
X814933Y350000D01*
X815400Y349583D01*
X815800Y349500D01*
X816267Y349583D01*
X816667Y349833D01*
X817000Y350250D01*
G01X819767Y352833D02*
Y350500D01*
X820033Y349917D01*
X820433Y349583D01*
X820900Y349500D01*
X821367Y349583D01*
X821767Y349917D01*
X822033Y350500D01*
G01Y349500D02*
Y352833D01*
G01X827200Y349500D02*
Y352833D01*
G01Y352250D02*
X826933Y352583D01*
X826533Y352750D01*
X826067Y352833D01*
X825600Y352667D01*
X825200Y352333D01*
X824933Y351833D01*
X824800Y351167D01*
X824933Y350500D01*
X825200Y350000D01*
X825600Y349667D01*
X826067Y349500D01*
X826533Y349583D01*
X826933Y349833D01*
X827200Y350167D01*
G01X830167Y349500D02*
Y352833D01*
G01Y352167D02*
X830500Y352500D01*
X830833Y352750D01*
X831300Y352833D01*
X831633Y352750D01*
X832033Y352500D01*
G01X835200Y351750D02*
X837333D01*
X837133Y352333D01*
X836800Y352667D01*
X836333Y352833D01*
X835867Y352750D01*
X835467Y352500D01*
X835200Y351917D01*
X835067Y351417D01*
Y350917D01*
X835200Y350417D01*
X835533Y349917D01*
X835933Y349583D01*
X836400Y349500D01*
X836867Y349667D01*
X837333Y350167D01*
G01X845267Y349500D02*
Y354500D01*
G01Y352083D02*
X845600Y352500D01*
X845933Y352750D01*
X846467Y352833D01*
X846867Y352750D01*
X847333Y352417D01*
X847533Y351917D01*
Y349500D01*
G01X851500D02*
X851100Y349583D01*
X850700Y349917D01*
X850433Y350500D01*
X850300Y351167D01*
X850433Y351833D01*
X850700Y352417D01*
X851100Y352750D01*
X851500Y352833D01*
X851900Y352750D01*
X852300Y352417D01*
X852567Y351833D01*
X852633Y351167D01*
X852567Y350500D01*
X852300Y349917D01*
X851900Y349583D01*
X851500Y349500D01*
G01X856600D02*
Y354500D01*
G01X860700Y351750D02*
X862833D01*
X862633Y352333D01*
X862300Y352667D01*
X861833Y352833D01*
X861367Y352750D01*
X860967Y352500D01*
X860700Y351917D01*
X860567Y351417D01*
Y350917D01*
X860700Y350417D01*
X861033Y349917D01*
X861433Y349583D01*
X861900Y349500D01*
X862367Y349667D01*
X862833Y350167D01*
G01X866800Y349333D02*
X866667Y349417D01*
Y349583D01*
X866800Y349667D01*
X866933Y349583D01*
Y349417D01*
X866800Y349333D01*
G01Y351583D02*
X866667Y351667D01*
Y351833D01*
X866800Y351917D01*
X866933Y351833D01*
Y351667D01*
X866800Y351583D01*
G01X721133Y391740D02*
X722800Y386740D01*
X724467Y391740D01*
G01X727900Y390073D02*
Y386740D01*
G01Y391407D02*
X727767Y391490D01*
Y391657D01*
X727900Y391740D01*
X728033Y391657D01*
Y391490D01*
X727900Y391407D01*
G01X734200Y386740D02*
Y390073D01*
G01Y389490D02*
X733933Y389823D01*
X733533Y389990D01*
X733067Y390073D01*
X732600Y389907D01*
X732200Y389573D01*
X731933Y389073D01*
X731800Y388407D01*
X731933Y387740D01*
X732200Y387240D01*
X732600Y386907D01*
X733067Y386740D01*
X733533Y386823D01*
X733933Y387073D01*
X734200Y387407D01*
G01X742400Y391740D02*
X744000D01*
G01X743200D02*
Y386740D01*
G01X742400D02*
X744000D01*
G01X747167D02*
Y390073D01*
G01Y389240D02*
X747433Y389657D01*
X747833Y389990D01*
X748367Y390073D01*
X748833Y389990D01*
X749233Y389657D01*
X749433Y389073D01*
Y386740D01*
G01X757167D02*
Y391740D01*
X758767D01*
X759300Y391490D01*
X759700Y390907D01*
X759833Y390240D01*
X759700Y389573D01*
X759367Y389073D01*
X758767Y388823D01*
X757167D01*
G01X764800Y386740D02*
Y390073D01*
G01Y389490D02*
X764533Y389823D01*
X764133Y389990D01*
X763667Y390073D01*
X763200Y389907D01*
X762800Y389573D01*
X762533Y389073D01*
X762400Y388407D01*
X762533Y387740D01*
X762800Y387240D01*
X763200Y386907D01*
X763667Y386740D01*
X764133Y386823D01*
X764533Y387073D01*
X764800Y387407D01*
G01X769900Y391740D02*
Y386740D01*
G01Y387490D02*
X769633Y387073D01*
X769233Y386823D01*
X768767Y386740D01*
X768233Y386907D01*
X767833Y387323D01*
X767567Y387823D01*
X767500Y388407D01*
X767567Y388990D01*
X767833Y389490D01*
X768233Y389907D01*
X768767Y390073D01*
X769233Y389990D01*
X769567Y389823D01*
X769900Y389490D01*
G01X773467Y385073D02*
X772800Y385907D01*
X772467Y386740D01*
Y390073D01*
X772800Y390907D01*
X773467Y391740D01*
G01X777233D02*
X778900Y386740D01*
X780567Y391740D01*
G01X783200D02*
X784800D01*
G01X784000D02*
Y386740D01*
G01X783200D02*
X784800D01*
G01X787767D02*
Y391740D01*
X789367D01*
X789900Y391490D01*
X790300Y390907D01*
X790433Y390240D01*
X790300Y389573D01*
X789967Y389073D01*
X789367Y388823D01*
X787767D01*
G01X794533Y385073D02*
X795200Y385907D01*
X795533Y386740D01*
Y390073D01*
X795200Y390907D01*
X794533Y391740D01*
G01X713000Y365500D02*
X1343000D01*
G01X713000Y400500D02*
X1343000D01*
G01X720473Y408303D02*
X723407Y411970D01*
G01X721940Y412637D02*
Y407637D01*
G01X723407Y408303D02*
X720473Y411970D01*
G01X719940Y410137D02*
X723940D01*
G01X726707Y406803D02*
X726040Y407637D01*
X725707Y408470D01*
Y411803D01*
X726040Y412637D01*
X726707Y413470D01*
G01X730673Y409220D02*
X731073Y408803D01*
X731540Y408553D01*
X732140Y408470D01*
X732740Y408637D01*
X733207Y408970D01*
X733540Y409553D01*
X733607Y410220D01*
X733473Y410887D01*
X733140Y411303D01*
X732673Y411637D01*
X732207Y411720D01*
X731740Y411637D01*
X731140Y411303D01*
X731340Y413470D01*
X733140D01*
G01X737240Y408303D02*
X737107Y408387D01*
Y408553D01*
X737240Y408637D01*
X737373Y408553D01*
Y408387D01*
X737240Y408303D01*
G01X742340Y408470D02*
Y413470D01*
X741540Y412470D01*
G01Y408470D02*
X743140D01*
G01X747773Y406803D02*
X748440Y407637D01*
X748773Y408470D01*
Y411803D01*
X748440Y412637D01*
X747773Y413470D01*
G01X720833Y424500D02*
X722500Y419500D01*
X724167Y424500D01*
G01X727600Y422833D02*
Y419500D01*
G01Y424167D02*
X727467Y424250D01*
Y424417D01*
X727600Y424500D01*
X727733Y424417D01*
Y424250D01*
X727600Y424167D01*
G01X733900Y419500D02*
Y422833D01*
G01Y422250D02*
X733633Y422583D01*
X733233Y422750D01*
X732767Y422833D01*
X732300Y422667D01*
X731900Y422333D01*
X731633Y421833D01*
X731500Y421167D01*
X731633Y420500D01*
X731900Y420000D01*
X732300Y419667D01*
X732767Y419500D01*
X733233Y419583D01*
X733633Y419833D01*
X733900Y420167D01*
G01X742900Y419500D02*
X742367Y419583D01*
X741900Y419917D01*
X741500Y420417D01*
X741233Y421000D01*
X741100Y421667D01*
Y422333D01*
X741233Y423000D01*
X741500Y423583D01*
X741900Y424083D01*
X742367Y424417D01*
X742900Y424500D01*
X743433Y424417D01*
X743900Y424083D01*
X744300Y423583D01*
X744567Y423000D01*
X744700Y422333D01*
Y421667D01*
X744567Y421000D01*
X744300Y420417D01*
X743900Y419917D01*
X743433Y419583D01*
X742900Y419500D01*
G01X746867D02*
Y422833D01*
G01Y422000D02*
X747133Y422417D01*
X747533Y422750D01*
X748067Y422833D01*
X748533Y422750D01*
X748933Y422417D01*
X749133Y421833D01*
Y419500D01*
G01X756867D02*
Y424500D01*
X758467D01*
X759000Y424250D01*
X759400Y423667D01*
X759533Y423000D01*
X759400Y422333D01*
X759067Y421833D01*
X758467Y421583D01*
X756867D01*
G01X764500Y419500D02*
Y422833D01*
G01Y422250D02*
X764233Y422583D01*
X763833Y422750D01*
X763367Y422833D01*
X762900Y422667D01*
X762500Y422333D01*
X762233Y421833D01*
X762100Y421167D01*
X762233Y420500D01*
X762500Y420000D01*
X762900Y419667D01*
X763367Y419500D01*
X763833Y419583D01*
X764233Y419833D01*
X764500Y420167D01*
G01X769600Y424500D02*
Y419500D01*
G01Y420250D02*
X769333Y419833D01*
X768933Y419583D01*
X768467Y419500D01*
X767933Y419667D01*
X767533Y420083D01*
X767267Y420583D01*
X767200Y421167D01*
X767267Y421750D01*
X767533Y422250D01*
X767933Y422667D01*
X768467Y422833D01*
X768933Y422750D01*
X769267Y422583D01*
X769600Y422250D01*
G01X773167Y417833D02*
X772500Y418667D01*
X772167Y419500D01*
Y422833D01*
X772500Y423667D01*
X773167Y424500D01*
G01X776933D02*
X778600Y419500D01*
X780267Y424500D01*
G01X783700Y419500D02*
X783167Y419583D01*
X782700Y419917D01*
X782300Y420417D01*
X782033Y421000D01*
X781900Y421667D01*
Y422333D01*
X782033Y423000D01*
X782300Y423583D01*
X782700Y424083D01*
X783167Y424417D01*
X783700Y424500D01*
X784233Y424417D01*
X784700Y424083D01*
X785100Y423583D01*
X785367Y423000D01*
X785500Y422333D01*
Y421667D01*
X785367Y421000D01*
X785100Y420417D01*
X784700Y419917D01*
X784233Y419583D01*
X783700Y419500D01*
G01X787467D02*
Y424500D01*
X789067D01*
X789600Y424250D01*
X790000Y423667D01*
X790133Y423000D01*
X790000Y422333D01*
X789667Y421833D01*
X789067Y421583D01*
X787467D01*
G01X794233Y417833D02*
X794900Y418667D01*
X795233Y419500D01*
Y422833D01*
X794900Y423667D01*
X794233Y424500D01*
G01X723033Y443167D02*
X723300Y443417D01*
X723500Y443833D01*
X723633Y444417D01*
X723500Y444917D01*
X723233Y445250D01*
X722767Y445500D01*
X720967D01*
Y440500D01*
X723167D01*
X723633Y440833D01*
X723900Y441333D01*
X724033Y441917D01*
X723900Y442500D01*
X723500Y443000D01*
X723033Y443167D01*
X720967D01*
G01X726467Y443833D02*
Y441500D01*
X726733Y440917D01*
X727133Y440583D01*
X727600Y440500D01*
X728067Y440583D01*
X728467Y440917D01*
X728733Y441500D01*
G01Y440500D02*
Y443833D01*
G01X731767Y440500D02*
Y443833D01*
G01Y443167D02*
X732100Y443500D01*
X732433Y443750D01*
X732900Y443833D01*
X733233Y443750D01*
X733633Y443500D01*
G01X737800Y443833D02*
Y440500D01*
G01Y445167D02*
X737667Y445250D01*
Y445417D01*
X737800Y445500D01*
X737933Y445417D01*
Y445250D01*
X737800Y445167D01*
G01X741900Y442750D02*
X744033D01*
X743833Y443333D01*
X743500Y443667D01*
X743033Y443833D01*
X742567Y443750D01*
X742167Y443500D01*
X741900Y442917D01*
X741767Y442417D01*
Y441917D01*
X741900Y441417D01*
X742233Y440917D01*
X742633Y440583D01*
X743100Y440500D01*
X743567Y440667D01*
X744033Y441167D01*
G01X749200Y445500D02*
Y440500D01*
G01Y441250D02*
X748933Y440833D01*
X748533Y440583D01*
X748067Y440500D01*
X747533Y440667D01*
X747133Y441083D01*
X746867Y441583D01*
X746800Y442167D01*
X746867Y442750D01*
X747133Y443250D01*
X747533Y443667D01*
X748067Y443833D01*
X748533Y443750D01*
X748867Y443583D01*
X749200Y443250D01*
G01X757067Y440500D02*
Y445500D01*
G01Y443083D02*
X757400Y443500D01*
X757733Y443750D01*
X758267Y443833D01*
X758667Y443750D01*
X759133Y443417D01*
X759333Y442917D01*
Y440500D01*
G01X763300D02*
X762900Y440583D01*
X762500Y440917D01*
X762233Y441500D01*
X762100Y442167D01*
X762233Y442833D01*
X762500Y443417D01*
X762900Y443750D01*
X763300Y443833D01*
X763700Y443750D01*
X764100Y443417D01*
X764367Y442833D01*
X764433Y442167D01*
X764367Y441500D01*
X764100Y440917D01*
X763700Y440583D01*
X763300Y440500D01*
G01X768400D02*
Y445500D01*
G01X772500Y442750D02*
X774633D01*
X774433Y443333D01*
X774100Y443667D01*
X773633Y443833D01*
X773167Y443750D01*
X772767Y443500D01*
X772500Y442917D01*
X772367Y442417D01*
Y441917D01*
X772500Y441417D01*
X772833Y440917D01*
X773233Y440583D01*
X773700Y440500D01*
X774167Y440667D01*
X774633Y441167D01*
G01X721233Y461500D02*
Y466500D01*
X723767D01*
G01X722833Y464083D02*
X721233D01*
G01X726467Y464833D02*
Y462500D01*
X726733Y461917D01*
X727133Y461583D01*
X727600Y461500D01*
X728067Y461583D01*
X728467Y461917D01*
X728733Y462500D01*
G01Y461500D02*
Y464833D01*
G01X732700Y461500D02*
Y466500D01*
G01X737800Y461500D02*
Y466500D01*
G01X746800Y459833D02*
Y464833D01*
G01Y464083D02*
X747133Y464500D01*
X747467Y464750D01*
X748000Y464833D01*
X748467Y464750D01*
X748933Y464333D01*
X749133Y463750D01*
X749200Y463167D01*
X749133Y462583D01*
X748933Y462000D01*
X748533Y461667D01*
X748000Y461500D01*
X747533Y461583D01*
X747067Y461833D01*
X746800Y462167D01*
G01X753100Y461500D02*
Y466500D01*
G01X757067Y464833D02*
Y462500D01*
X757333Y461917D01*
X757733Y461583D01*
X758200Y461500D01*
X758667Y461583D01*
X759067Y461917D01*
X759333Y462500D01*
G01Y461500D02*
Y464833D01*
G01X762367Y460250D02*
X762833Y459917D01*
X763367Y459833D01*
X763833Y459917D01*
X764233Y460333D01*
X764500Y460917D01*
Y464833D01*
G01Y464167D02*
X764233Y464500D01*
X763833Y464750D01*
X763367Y464833D01*
X762833Y464667D01*
X762500Y464333D01*
X762233Y463750D01*
X762100Y463167D01*
X762167Y462667D01*
X762433Y462083D01*
X762833Y461667D01*
X763367Y461500D01*
X763767Y461583D01*
X764233Y461917D01*
X764500Y462250D01*
G01X767467Y460250D02*
X767933Y459917D01*
X768467Y459833D01*
X768933Y459917D01*
X769333Y460333D01*
X769600Y460917D01*
Y464833D01*
G01Y464167D02*
X769333Y464500D01*
X768933Y464750D01*
X768467Y464833D01*
X767933Y464667D01*
X767600Y464333D01*
X767333Y463750D01*
X767200Y463167D01*
X767267Y462667D01*
X767533Y462083D01*
X767933Y461667D01*
X768467Y461500D01*
X768867Y461583D01*
X769333Y461917D01*
X769600Y462250D01*
G01X773500Y464833D02*
Y461500D01*
G01Y466167D02*
X773367Y466250D01*
Y466417D01*
X773500Y466500D01*
X773633Y466417D01*
Y466250D01*
X773500Y466167D01*
G01X777467Y461500D02*
Y464833D01*
G01Y464000D02*
X777733Y464417D01*
X778133Y464750D01*
X778667Y464833D01*
X779133Y464750D01*
X779533Y464417D01*
X779733Y463833D01*
Y461500D01*
G01X782767Y460250D02*
X783233Y459917D01*
X783767Y459833D01*
X784233Y459917D01*
X784633Y460333D01*
X784900Y460917D01*
Y464833D01*
G01Y464167D02*
X784633Y464500D01*
X784233Y464750D01*
X783767Y464833D01*
X783233Y464667D01*
X782900Y464333D01*
X782633Y463750D01*
X782500Y463167D01*
X782567Y462667D01*
X782833Y462083D01*
X783233Y461667D01*
X783767Y461500D01*
X784167Y461583D01*
X784633Y461917D01*
X784900Y462250D01*
G01X713000Y435500D02*
X1343000D01*
G01X713000Y450500D02*
X1343000D01*
G01X713000Y477500D02*
X1343000D01*
G01X721100Y530000D02*
Y535000D01*
G01X723900D02*
Y530000D01*
G01Y532500D02*
X721100D01*
G01X728800Y530000D02*
Y533333D01*
G01Y532750D02*
X728533Y533083D01*
X728133Y533250D01*
X727667Y533333D01*
X727200Y533167D01*
X726800Y532833D01*
X726533Y532333D01*
X726400Y531667D01*
X726533Y531000D01*
X726800Y530500D01*
X727200Y530167D01*
X727667Y530000D01*
X728133Y530083D01*
X728533Y530333D01*
X728800Y530667D01*
G01X732700Y530000D02*
Y535000D01*
G01X737400Y530000D02*
Y534250D01*
X737533Y534667D01*
X737800Y534917D01*
X738200Y535000D01*
X738600Y534833D01*
X738800Y534417D01*
G01X738000Y533000D02*
X736667D01*
G01X746667Y530000D02*
Y535000D01*
X748267D01*
X748800Y534750D01*
X749200Y534167D01*
X749333Y533500D01*
X749200Y532833D01*
X748867Y532333D01*
X748267Y532083D01*
X746667D01*
G01X753100Y530000D02*
Y535000D01*
G01X757067Y533333D02*
Y531000D01*
X757333Y530417D01*
X757733Y530083D01*
X758200Y530000D01*
X758667Y530083D01*
X759067Y530417D01*
X759333Y531000D01*
G01Y530000D02*
Y533333D01*
G01X762367Y528750D02*
X762833Y528417D01*
X763367Y528333D01*
X763833Y528417D01*
X764233Y528833D01*
X764500Y529417D01*
Y533333D01*
G01Y532667D02*
X764233Y533000D01*
X763833Y533250D01*
X763367Y533333D01*
X762833Y533167D01*
X762500Y532833D01*
X762233Y532250D01*
X762100Y531667D01*
X762167Y531167D01*
X762433Y530583D01*
X762833Y530167D01*
X763367Y530000D01*
X763767Y530083D01*
X764233Y530417D01*
X764500Y530750D01*
G01X767467Y528750D02*
X767933Y528417D01*
X768467Y528333D01*
X768933Y528417D01*
X769333Y528833D01*
X769600Y529417D01*
Y533333D01*
G01Y532667D02*
X769333Y533000D01*
X768933Y533250D01*
X768467Y533333D01*
X767933Y533167D01*
X767600Y532833D01*
X767333Y532250D01*
X767200Y531667D01*
X767267Y531167D01*
X767533Y530583D01*
X767933Y530167D01*
X768467Y530000D01*
X768867Y530083D01*
X769333Y530417D01*
X769600Y530750D01*
G01X773500Y533333D02*
Y530000D01*
G01Y534667D02*
X773367Y534750D01*
Y534917D01*
X773500Y535000D01*
X773633Y534917D01*
Y534750D01*
X773500Y534667D01*
G01X777467Y530000D02*
Y533333D01*
G01Y532500D02*
X777733Y532917D01*
X778133Y533250D01*
X778667Y533333D01*
X779133Y533250D01*
X779533Y532917D01*
X779733Y532333D01*
Y530000D01*
G01X782767Y528750D02*
X783233Y528417D01*
X783767Y528333D01*
X784233Y528417D01*
X784633Y528833D01*
X784900Y529417D01*
Y533333D01*
G01Y532667D02*
X784633Y533000D01*
X784233Y533250D01*
X783767Y533333D01*
X783233Y533167D01*
X782900Y532833D01*
X782633Y532250D01*
X782500Y531667D01*
X782567Y531167D01*
X782833Y530583D01*
X783233Y530167D01*
X783767Y530000D01*
X784167Y530083D01*
X784633Y530417D01*
X784900Y530750D01*
G01X722667Y589000D02*
Y594000D01*
X724267D01*
X724800Y593750D01*
X725200Y593167D01*
X725333Y592500D01*
X725200Y591833D01*
X724867Y591333D01*
X724267Y591083D01*
X722667D01*
G01X729100Y589000D02*
Y594000D01*
G01X733067Y592333D02*
Y590000D01*
X733333Y589417D01*
X733733Y589083D01*
X734200Y589000D01*
X734667Y589083D01*
X735067Y589417D01*
X735333Y590000D01*
G01Y589000D02*
Y592333D01*
G01X738367Y587750D02*
X738833Y587417D01*
X739367Y587333D01*
X739833Y587417D01*
X740233Y587833D01*
X740500Y588417D01*
Y592333D01*
G01Y591667D02*
X740233Y592000D01*
X739833Y592250D01*
X739367Y592333D01*
X738833Y592167D01*
X738500Y591833D01*
X738233Y591250D01*
X738100Y590667D01*
X738167Y590167D01*
X738433Y589583D01*
X738833Y589167D01*
X739367Y589000D01*
X739767Y589083D01*
X740233Y589417D01*
X740500Y589750D01*
G01X743467Y587750D02*
X743933Y587417D01*
X744467Y587333D01*
X744933Y587417D01*
X745333Y587833D01*
X745600Y588417D01*
Y592333D01*
G01Y591667D02*
X745333Y592000D01*
X744933Y592250D01*
X744467Y592333D01*
X743933Y592167D01*
X743600Y591833D01*
X743333Y591250D01*
X743200Y590667D01*
X743267Y590167D01*
X743533Y589583D01*
X743933Y589167D01*
X744467Y589000D01*
X744867Y589083D01*
X745333Y589417D01*
X745600Y589750D01*
G01X749500Y592333D02*
Y589000D01*
G01Y593667D02*
X749367Y593750D01*
Y593917D01*
X749500Y594000D01*
X749633Y593917D01*
Y593750D01*
X749500Y593667D01*
G01X753467Y589000D02*
Y592333D01*
G01Y591500D02*
X753733Y591917D01*
X754133Y592250D01*
X754667Y592333D01*
X755133Y592250D01*
X755533Y591917D01*
X755733Y591333D01*
Y589000D01*
G01X758767Y587750D02*
X759233Y587417D01*
X759767Y587333D01*
X760233Y587417D01*
X760633Y587833D01*
X760900Y588417D01*
Y592333D01*
G01Y591667D02*
X760633Y592000D01*
X760233Y592250D01*
X759767Y592333D01*
X759233Y592167D01*
X758900Y591833D01*
X758633Y591250D01*
X758500Y590667D01*
X758567Y590167D01*
X758833Y589583D01*
X759233Y589167D01*
X759767Y589000D01*
X760167Y589083D01*
X760633Y589417D01*
X760900Y589750D01*
G01X771100Y594000D02*
Y589000D01*
G01Y589750D02*
X770833Y589333D01*
X770433Y589083D01*
X769967Y589000D01*
X769433Y589167D01*
X769033Y589583D01*
X768767Y590083D01*
X768700Y590667D01*
X768767Y591250D01*
X769033Y591750D01*
X769433Y592167D01*
X769967Y592333D01*
X770433Y592250D01*
X770767Y592083D01*
X771100Y591750D01*
G01X774000Y591250D02*
X776133D01*
X775933Y591833D01*
X775600Y592167D01*
X775133Y592333D01*
X774667Y592250D01*
X774267Y592000D01*
X774000Y591417D01*
X773867Y590917D01*
Y590417D01*
X774000Y589917D01*
X774333Y589417D01*
X774733Y589083D01*
X775200Y589000D01*
X775667Y589167D01*
X776133Y589667D01*
G01X779700Y589000D02*
Y593250D01*
X779833Y593667D01*
X780100Y593917D01*
X780500Y594000D01*
X780900Y593833D01*
X781100Y593417D01*
G01X780300Y592000D02*
X778967D01*
G01X785200Y592333D02*
Y589000D01*
G01Y593667D02*
X785067Y593750D01*
Y593917D01*
X785200Y594000D01*
X785333Y593917D01*
Y593750D01*
X785200Y593667D01*
G01X789167Y589000D02*
Y592333D01*
G01Y591500D02*
X789433Y591917D01*
X789833Y592250D01*
X790367Y592333D01*
X790833Y592250D01*
X791233Y591917D01*
X791433Y591333D01*
Y589000D01*
G01X794400Y591250D02*
X796533D01*
X796333Y591833D01*
X796000Y592167D01*
X795533Y592333D01*
X795067Y592250D01*
X794667Y592000D01*
X794400Y591417D01*
X794267Y590917D01*
Y590417D01*
X794400Y589917D01*
X794733Y589417D01*
X795133Y589083D01*
X795600Y589000D01*
X796067Y589167D01*
X796533Y589667D01*
G01X713000Y579500D02*
X1343000D01*
G01X713000Y604500D02*
X1343000D01*
G01X722533Y765000D02*
X722933Y764417D01*
X723467Y764083D01*
X724067Y764000D01*
X724600Y764083D01*
X725133Y764500D01*
X725467Y765000D01*
X725533Y765500D01*
X725400Y766083D01*
X724933Y766500D01*
X724467Y766667D01*
X723867D01*
G01X724467D02*
X724867Y766917D01*
X725200Y767333D01*
X725333Y767833D01*
X725200Y768333D01*
X724867Y768750D01*
X724267Y769000D01*
X723667Y768917D01*
X723067Y768583D01*
G01X729100Y763833D02*
X728967Y763917D01*
Y764083D01*
X729100Y764167D01*
X729233Y764083D01*
Y763917D01*
X729100Y763833D01*
G01X737967Y764000D02*
Y769000D01*
X739567D01*
X740100Y768750D01*
X740500Y768167D01*
X740633Y767500D01*
X740500Y766833D01*
X740167Y766333D01*
X739567Y766083D01*
X737967D01*
G01X744400Y764000D02*
Y769000D01*
G01X748367Y767333D02*
Y765000D01*
X748633Y764417D01*
X749033Y764083D01*
X749500Y764000D01*
X749967Y764083D01*
X750367Y764417D01*
X750633Y765000D01*
G01Y764000D02*
Y767333D01*
G01X753667Y762750D02*
X754133Y762417D01*
X754667Y762333D01*
X755133Y762417D01*
X755533Y762833D01*
X755800Y763417D01*
Y767333D01*
G01Y766667D02*
X755533Y767000D01*
X755133Y767250D01*
X754667Y767333D01*
X754133Y767167D01*
X753800Y766833D01*
X753533Y766250D01*
X753400Y765667D01*
X753467Y765167D01*
X753733Y764583D01*
X754133Y764167D01*
X754667Y764000D01*
X755067Y764083D01*
X755533Y764417D01*
X755800Y764750D01*
G01X763600Y767333D02*
X764800Y764000D01*
X766000Y767333D01*
G01X769900D02*
Y764000D01*
G01Y768667D02*
X769767Y768750D01*
Y768917D01*
X769900Y769000D01*
X770033Y768917D01*
Y768750D01*
X769900Y768667D01*
G01X776200Y764000D02*
Y767333D01*
G01Y766750D02*
X775933Y767083D01*
X775533Y767250D01*
X775067Y767333D01*
X774600Y767167D01*
X774200Y766833D01*
X773933Y766333D01*
X773800Y765667D01*
X773933Y765000D01*
X774200Y764500D01*
X774600Y764167D01*
X775067Y764000D01*
X775533Y764083D01*
X775933Y764333D01*
X776200Y764667D01*
G01X784000Y763833D02*
X786400Y769000D01*
G01X788633D02*
X790300Y764000D01*
X791967Y769000D01*
G01X795400Y764000D02*
X794867Y764083D01*
X794400Y764417D01*
X794000Y764917D01*
X793733Y765500D01*
X793600Y766167D01*
Y766833D01*
X793733Y767500D01*
X794000Y768083D01*
X794400Y768583D01*
X794867Y768917D01*
X795400Y769000D01*
X795933Y768917D01*
X796400Y768583D01*
X796800Y768083D01*
X797067Y767500D01*
X797200Y766833D01*
Y766167D01*
X797067Y765500D01*
X796800Y764917D01*
X796400Y764417D01*
X795933Y764083D01*
X795400Y764000D01*
G01X799167D02*
Y769000D01*
X800767D01*
X801300Y768750D01*
X801700Y768167D01*
X801833Y767500D01*
X801700Y766833D01*
X801367Y766333D01*
X800767Y766083D01*
X799167D01*
G01X804400Y763833D02*
X806800Y769000D01*
G01X809033D02*
X810700Y764000D01*
X812367Y769000D01*
G01X815000D02*
X816600D01*
G01X815800D02*
Y764000D01*
G01X815000D02*
X816600D01*
G01X819567D02*
Y769000D01*
X821167D01*
X821700Y768750D01*
X822100Y768167D01*
X822233Y767500D01*
X822100Y766833D01*
X821767Y766333D01*
X821167Y766083D01*
X819567D01*
G01X826000Y763833D02*
X825867Y763917D01*
Y764083D01*
X826000Y764167D01*
X826133Y764083D01*
Y763917D01*
X826000Y763833D01*
G01Y766083D02*
X825867Y766167D01*
Y766333D01*
X826000Y766417D01*
X826133Y766333D01*
Y766167D01*
X826000Y766083D01*
G01X713000Y752000D02*
X1344500D01*
G01X724647Y813000D02*
Y818000D01*
X726313D01*
X726847Y817750D01*
X727180Y817417D01*
X727313Y816750D01*
X727180Y816083D01*
X726780Y815667D01*
X726313Y815417D01*
X724647D01*
G01X726313D02*
X727313Y813000D01*
G01X731080D02*
X730680Y813083D01*
X730280Y813417D01*
X730013Y814000D01*
X729880Y814667D01*
X730013Y815333D01*
X730280Y815917D01*
X730680Y816250D01*
X731080Y816333D01*
X731480Y816250D01*
X731880Y815917D01*
X732147Y815333D01*
X732213Y814667D01*
X732147Y814000D01*
X731880Y813417D01*
X731480Y813083D01*
X731080Y813000D01*
G01X735047Y816333D02*
Y814000D01*
X735313Y813417D01*
X735713Y813083D01*
X736180Y813000D01*
X736647Y813083D01*
X737047Y813417D01*
X737313Y814000D01*
G01Y813000D02*
Y816333D01*
G01X741280Y818000D02*
Y813000D01*
G01X740347Y816333D02*
X742213D01*
G01X746380D02*
Y813000D01*
G01Y817667D02*
X746247Y817750D01*
Y817917D01*
X746380Y818000D01*
X746513Y817917D01*
Y817750D01*
X746380Y817667D01*
G01X750347Y813000D02*
Y816333D01*
G01Y815500D02*
X750613Y815917D01*
X751013Y816250D01*
X751547Y816333D01*
X752013Y816250D01*
X752413Y815917D01*
X752613Y815333D01*
Y813000D01*
G01X755647Y811750D02*
X756113Y811417D01*
X756647Y811333D01*
X757113Y811417D01*
X757513Y811833D01*
X757780Y812417D01*
Y816333D01*
G01Y815667D02*
X757513Y816000D01*
X757113Y816250D01*
X756647Y816333D01*
X756113Y816167D01*
X755780Y815833D01*
X755513Y815250D01*
X755380Y814667D01*
X755447Y814167D01*
X755713Y813583D01*
X756113Y813167D01*
X756647Y813000D01*
X757047Y813083D01*
X757513Y813417D01*
X757780Y813750D01*
G01X712980Y850500D02*
X1343000D01*
G01X736803Y-65320D02*
X737203Y-65737D01*
X737670Y-65987D01*
X738270Y-66070D01*
X738870Y-65903D01*
X739337Y-65570D01*
X739670Y-64987D01*
X739737Y-64320D01*
X739603Y-63653D01*
X739270Y-63237D01*
X738803Y-62903D01*
X738337Y-62820D01*
X737870Y-62903D01*
X737270Y-63237D01*
X737470Y-61070D01*
X739270D01*
G01X743370Y-66237D02*
X743237Y-66153D01*
Y-65987D01*
X743370Y-65903D01*
X743503Y-65987D01*
Y-66153D01*
X743370Y-66237D01*
G01X748470Y-66070D02*
Y-61070D01*
X747670Y-62070D01*
G01Y-66070D02*
X749270D01*
G01X757870Y-61070D02*
X759470D01*
G01X758670D02*
Y-66070D01*
G01X757870D02*
X759470D01*
G01X763370D02*
Y-61820D01*
X763503Y-61403D01*
X763770Y-61153D01*
X764170Y-61070D01*
X764570Y-61237D01*
X764770Y-61653D01*
G01X763970Y-63070D02*
X762637D01*
G01X774370Y-63570D02*
X775703D01*
Y-65070D01*
X775303Y-65570D01*
X774837Y-65903D01*
X774170Y-66070D01*
X773503Y-65903D01*
X773037Y-65570D01*
X772637Y-65070D01*
X772370Y-64487D01*
X772237Y-63820D01*
Y-63237D01*
X772370Y-62737D01*
X772637Y-62153D01*
X773037Y-61653D01*
X773437Y-61320D01*
X773970Y-61070D01*
X774437D01*
X774970Y-61237D01*
X775370Y-61570D01*
G01X778070Y-63820D02*
X780203D01*
X780003Y-63237D01*
X779670Y-62903D01*
X779203Y-62737D01*
X778737Y-62820D01*
X778337Y-63070D01*
X778070Y-63653D01*
X777937Y-64153D01*
Y-64653D01*
X778070Y-65153D01*
X778403Y-65653D01*
X778803Y-65987D01*
X779270Y-66070D01*
X779737Y-65903D01*
X780203Y-65403D01*
G01X783237Y-66070D02*
Y-62737D01*
G01Y-63403D02*
X783570Y-63070D01*
X783903Y-62820D01*
X784370Y-62737D01*
X784703Y-62820D01*
X785103Y-63070D01*
G01X788070Y-66070D02*
Y-61070D01*
G01Y-63570D02*
X788403Y-63070D01*
X788803Y-62820D01*
X789203Y-62737D01*
X789803Y-62903D01*
X790203Y-63237D01*
X790470Y-63820D01*
Y-64487D01*
X790337Y-65153D01*
X790070Y-65653D01*
X789603Y-65987D01*
X789203Y-66070D01*
X788803Y-65987D01*
X788403Y-65737D01*
X788070Y-65320D01*
G01X793370Y-63820D02*
X795503D01*
X795303Y-63237D01*
X794970Y-62903D01*
X794503Y-62737D01*
X794037Y-62820D01*
X793637Y-63070D01*
X793370Y-63653D01*
X793237Y-64153D01*
Y-64653D01*
X793370Y-65153D01*
X793703Y-65653D01*
X794103Y-65987D01*
X794570Y-66070D01*
X795037Y-65903D01*
X795503Y-65403D01*
G01X798537Y-66070D02*
Y-62737D01*
G01Y-63403D02*
X798870Y-63070D01*
X799203Y-62820D01*
X799670Y-62737D01*
X800003Y-62820D01*
X800403Y-63070D01*
G01X808537Y-66070D02*
Y-61070D01*
G01Y-63487D02*
X808870Y-63070D01*
X809203Y-62820D01*
X809737Y-62737D01*
X810137Y-62820D01*
X810603Y-63153D01*
X810803Y-63653D01*
Y-66070D01*
G01X815970D02*
Y-62737D01*
G01Y-63320D02*
X815703Y-62987D01*
X815303Y-62820D01*
X814837Y-62737D01*
X814370Y-62903D01*
X813970Y-63237D01*
X813703Y-63737D01*
X813570Y-64403D01*
X813703Y-65070D01*
X813970Y-65570D01*
X814370Y-65903D01*
X814837Y-66070D01*
X815303Y-65987D01*
X815703Y-65737D01*
X815970Y-65403D01*
G01X818870Y-65487D02*
X819203Y-65820D01*
X819670Y-66070D01*
X820070D01*
X820470Y-65903D01*
X820737Y-65653D01*
X820870Y-65320D01*
X820803Y-64820D01*
X820537Y-64570D01*
X819337Y-64070D01*
X819070Y-63487D01*
X819203Y-63070D01*
X819470Y-62820D01*
X819870Y-62737D01*
X820270Y-62820D01*
X820670Y-63070D01*
G01X830070Y-61070D02*
Y-66070D01*
G01X829137Y-62737D02*
X831003D01*
G01X834037Y-66070D02*
Y-61070D01*
G01Y-63487D02*
X834370Y-63070D01*
X834703Y-62820D01*
X835237Y-62737D01*
X835637Y-62820D01*
X836103Y-63153D01*
X836303Y-63653D01*
Y-66070D01*
G01X840270Y-62737D02*
Y-66070D01*
G01Y-61403D02*
X840137Y-61320D01*
Y-61153D01*
X840270Y-61070D01*
X840403Y-61153D01*
Y-61320D01*
X840270Y-61403D01*
G01X844370Y-65487D02*
X844703Y-65820D01*
X845170Y-66070D01*
X845570D01*
X845970Y-65903D01*
X846237Y-65653D01*
X846370Y-65320D01*
X846303Y-64820D01*
X846037Y-64570D01*
X844837Y-64070D01*
X844570Y-63487D01*
X844703Y-63070D01*
X844970Y-62820D01*
X845370Y-62737D01*
X845770Y-62820D01*
X846170Y-63070D01*
G01X854437Y-66070D02*
Y-61070D01*
G01X856570Y-62737D02*
X854437Y-64653D01*
G01X855303Y-63903D02*
X856703Y-66070D01*
G01X860670Y-62737D02*
Y-66070D01*
G01Y-61403D02*
X860537Y-61320D01*
Y-61153D01*
X860670Y-61070D01*
X860803Y-61153D01*
Y-61320D01*
X860670Y-61403D01*
G01X864637Y-66070D02*
Y-62737D01*
G01Y-63570D02*
X864903Y-63153D01*
X865303Y-62820D01*
X865837Y-62737D01*
X866303Y-62820D01*
X866703Y-63153D01*
X866903Y-63737D01*
Y-66070D01*
G01X872070Y-61070D02*
Y-66070D01*
G01Y-65320D02*
X871803Y-65737D01*
X871403Y-65987D01*
X870937Y-66070D01*
X870403Y-65903D01*
X870003Y-65487D01*
X869737Y-64987D01*
X869670Y-64403D01*
X869737Y-63820D01*
X870003Y-63320D01*
X870403Y-62903D01*
X870937Y-62737D01*
X871403Y-62820D01*
X871737Y-62987D01*
X872070Y-63320D01*
G01X881070Y-66070D02*
X880670Y-65987D01*
X880270Y-65653D01*
X880003Y-65070D01*
X879870Y-64403D01*
X880003Y-63737D01*
X880270Y-63153D01*
X880670Y-62820D01*
X881070Y-62737D01*
X881470Y-62820D01*
X881870Y-63153D01*
X882137Y-63737D01*
X882203Y-64403D01*
X882137Y-65070D01*
X881870Y-65653D01*
X881470Y-65987D01*
X881070Y-66070D01*
G01X885770D02*
Y-61820D01*
X885903Y-61403D01*
X886170Y-61153D01*
X886570Y-61070D01*
X886970Y-61237D01*
X887170Y-61653D01*
G01X886370Y-63070D02*
X885037D01*
G01X897570Y-61070D02*
Y-66070D01*
G01Y-65320D02*
X897303Y-65737D01*
X896903Y-65987D01*
X896437Y-66070D01*
X895903Y-65903D01*
X895503Y-65487D01*
X895237Y-64987D01*
X895170Y-64403D01*
X895237Y-63820D01*
X895503Y-63320D01*
X895903Y-62903D01*
X896437Y-62737D01*
X896903Y-62820D01*
X897237Y-62987D01*
X897570Y-63320D01*
G01X900470Y-63820D02*
X902603D01*
X902403Y-63237D01*
X902070Y-62903D01*
X901603Y-62737D01*
X901137Y-62820D01*
X900737Y-63070D01*
X900470Y-63653D01*
X900337Y-64153D01*
Y-64653D01*
X900470Y-65153D01*
X900803Y-65653D01*
X901203Y-65987D01*
X901670Y-66070D01*
X902137Y-65903D01*
X902603Y-65403D01*
G01X905570Y-65487D02*
X905903Y-65820D01*
X906370Y-66070D01*
X906770D01*
X907170Y-65903D01*
X907437Y-65653D01*
X907570Y-65320D01*
X907503Y-64820D01*
X907237Y-64570D01*
X906037Y-64070D01*
X905770Y-63487D01*
X905903Y-63070D01*
X906170Y-62820D01*
X906570Y-62737D01*
X906970Y-62820D01*
X907370Y-63070D01*
G01X911670Y-62737D02*
Y-66070D01*
G01Y-61403D02*
X911537Y-61320D01*
Y-61153D01*
X911670Y-61070D01*
X911803Y-61153D01*
Y-61320D01*
X911670Y-61403D01*
G01X915837Y-67320D02*
X916303Y-67653D01*
X916837Y-67737D01*
X917303Y-67653D01*
X917703Y-67237D01*
X917970Y-66653D01*
Y-62737D01*
G01Y-63403D02*
X917703Y-63070D01*
X917303Y-62820D01*
X916837Y-62737D01*
X916303Y-62903D01*
X915970Y-63237D01*
X915703Y-63820D01*
X915570Y-64403D01*
X915637Y-64903D01*
X915903Y-65487D01*
X916303Y-65903D01*
X916837Y-66070D01*
X917237Y-65987D01*
X917703Y-65653D01*
X917970Y-65320D01*
G01X920737Y-66070D02*
Y-62737D01*
G01Y-63570D02*
X921003Y-63153D01*
X921403Y-62820D01*
X921937Y-62737D01*
X922403Y-62820D01*
X922803Y-63153D01*
X923003Y-63737D01*
Y-66070D01*
G01X926837Y-66987D02*
X927103Y-65903D01*
G01X935970Y-67737D02*
Y-62737D01*
G01Y-63487D02*
X936303Y-63070D01*
X936637Y-62820D01*
X937170Y-62737D01*
X937637Y-62820D01*
X938103Y-63237D01*
X938303Y-63820D01*
X938370Y-64403D01*
X938303Y-64987D01*
X938103Y-65570D01*
X937703Y-65903D01*
X937170Y-66070D01*
X936703Y-65987D01*
X936237Y-65737D01*
X935970Y-65403D01*
G01X942270Y-66070D02*
Y-61070D01*
G01X946370Y-63820D02*
X948503D01*
X948303Y-63237D01*
X947970Y-62903D01*
X947503Y-62737D01*
X947037Y-62820D01*
X946637Y-63070D01*
X946370Y-63653D01*
X946237Y-64153D01*
Y-64653D01*
X946370Y-65153D01*
X946703Y-65653D01*
X947103Y-65987D01*
X947570Y-66070D01*
X948037Y-65903D01*
X948503Y-65403D01*
G01X953670Y-66070D02*
Y-62737D01*
G01Y-63320D02*
X953403Y-62987D01*
X953003Y-62820D01*
X952537Y-62737D01*
X952070Y-62903D01*
X951670Y-63237D01*
X951403Y-63737D01*
X951270Y-64403D01*
X951403Y-65070D01*
X951670Y-65570D01*
X952070Y-65903D01*
X952537Y-66070D01*
X953003Y-65987D01*
X953403Y-65737D01*
X953670Y-65403D01*
G01X956570Y-65487D02*
X956903Y-65820D01*
X957370Y-66070D01*
X957770D01*
X958170Y-65903D01*
X958437Y-65653D01*
X958570Y-65320D01*
X958503Y-64820D01*
X958237Y-64570D01*
X957037Y-64070D01*
X956770Y-63487D01*
X956903Y-63070D01*
X957170Y-62820D01*
X957570Y-62737D01*
X957970Y-62820D01*
X958370Y-63070D01*
G01X961670Y-63820D02*
X963803D01*
X963603Y-63237D01*
X963270Y-62903D01*
X962803Y-62737D01*
X962337Y-62820D01*
X961937Y-63070D01*
X961670Y-63653D01*
X961537Y-64153D01*
Y-64653D01*
X961670Y-65153D01*
X962003Y-65653D01*
X962403Y-65987D01*
X962870Y-66070D01*
X963337Y-65903D01*
X963803Y-65403D01*
G01X972470Y-66070D02*
Y-61820D01*
X972603Y-61403D01*
X972870Y-61153D01*
X973270Y-61070D01*
X973670Y-61237D01*
X973870Y-61653D01*
G01X973070Y-63070D02*
X971737D01*
G01X977970Y-66070D02*
X977570Y-65987D01*
X977170Y-65653D01*
X976903Y-65070D01*
X976770Y-64403D01*
X976903Y-63737D01*
X977170Y-63153D01*
X977570Y-62820D01*
X977970Y-62737D01*
X978370Y-62820D01*
X978770Y-63153D01*
X979037Y-63737D01*
X979103Y-64403D01*
X979037Y-65070D01*
X978770Y-65653D01*
X978370Y-65987D01*
X977970Y-66070D01*
G01X983070D02*
Y-61070D01*
G01X988170Y-66070D02*
Y-61070D01*
G01X993270Y-66070D02*
X992870Y-65987D01*
X992470Y-65653D01*
X992203Y-65070D01*
X992070Y-64403D01*
X992203Y-63737D01*
X992470Y-63153D01*
X992870Y-62820D01*
X993270Y-62737D01*
X993670Y-62820D01*
X994070Y-63153D01*
X994337Y-63737D01*
X994403Y-64403D01*
X994337Y-65070D01*
X994070Y-65653D01*
X993670Y-65987D01*
X993270Y-66070D01*
G01X996703Y-62737D02*
X997503Y-66070D01*
X998370Y-62737D01*
X999237Y-66070D01*
X1000037Y-62737D01*
G01X1003470Y-66237D02*
X1003337Y-66153D01*
Y-65987D01*
X1003470Y-65903D01*
X1003603Y-65987D01*
Y-66153D01*
X1003470Y-66237D01*
G01X1012870Y-61070D02*
X1014470D01*
G01X1013670D02*
Y-66070D01*
G01X1012870D02*
X1014470D01*
G01X1018370D02*
Y-61820D01*
X1018503Y-61403D01*
X1018770Y-61153D01*
X1019170Y-61070D01*
X1019570Y-61237D01*
X1019770Y-61653D01*
G01X1018970Y-63070D02*
X1017637D01*
G01X1027837Y-66070D02*
Y-62737D01*
G01Y-63570D02*
X1028103Y-63153D01*
X1028503Y-62820D01*
X1029037Y-62737D01*
X1029503Y-62820D01*
X1029903Y-63153D01*
X1030103Y-63737D01*
Y-66070D01*
G01X1034070D02*
X1033670Y-65987D01*
X1033270Y-65653D01*
X1033003Y-65070D01*
X1032870Y-64403D01*
X1033003Y-63737D01*
X1033270Y-63153D01*
X1033670Y-62820D01*
X1034070Y-62737D01*
X1034470Y-62820D01*
X1034870Y-63153D01*
X1035137Y-63737D01*
X1035203Y-64403D01*
X1035137Y-65070D01*
X1034870Y-65653D01*
X1034470Y-65987D01*
X1034070Y-66070D01*
G01X1039170Y-61070D02*
Y-66070D01*
G01X1038237Y-62737D02*
X1040103D01*
G01X1044137Y-66987D02*
X1044403Y-65903D01*
G01X1053270Y-67737D02*
Y-62737D01*
G01Y-63487D02*
X1053603Y-63070D01*
X1053937Y-62820D01*
X1054470Y-62737D01*
X1054937Y-62820D01*
X1055403Y-63237D01*
X1055603Y-63820D01*
X1055670Y-64403D01*
X1055603Y-64987D01*
X1055403Y-65570D01*
X1055003Y-65903D01*
X1054470Y-66070D01*
X1054003Y-65987D01*
X1053537Y-65737D01*
X1053270Y-65403D01*
G01X1059570Y-66070D02*
Y-61070D01*
G01X1063670Y-63820D02*
X1065803D01*
X1065603Y-63237D01*
X1065270Y-62903D01*
X1064803Y-62737D01*
X1064337Y-62820D01*
X1063937Y-63070D01*
X1063670Y-63653D01*
X1063537Y-64153D01*
Y-64653D01*
X1063670Y-65153D01*
X1064003Y-65653D01*
X1064403Y-65987D01*
X1064870Y-66070D01*
X1065337Y-65903D01*
X1065803Y-65403D01*
G01X1070970Y-66070D02*
Y-62737D01*
G01Y-63320D02*
X1070703Y-62987D01*
X1070303Y-62820D01*
X1069837Y-62737D01*
X1069370Y-62903D01*
X1068970Y-63237D01*
X1068703Y-63737D01*
X1068570Y-64403D01*
X1068703Y-65070D01*
X1068970Y-65570D01*
X1069370Y-65903D01*
X1069837Y-66070D01*
X1070303Y-65987D01*
X1070703Y-65737D01*
X1070970Y-65403D01*
G01X1073870Y-65487D02*
X1074203Y-65820D01*
X1074670Y-66070D01*
X1075070D01*
X1075470Y-65903D01*
X1075737Y-65653D01*
X1075870Y-65320D01*
X1075803Y-64820D01*
X1075537Y-64570D01*
X1074337Y-64070D01*
X1074070Y-63487D01*
X1074203Y-63070D01*
X1074470Y-62820D01*
X1074870Y-62737D01*
X1075270Y-62820D01*
X1075670Y-63070D01*
G01X1078970Y-63820D02*
X1081103D01*
X1080903Y-63237D01*
X1080570Y-62903D01*
X1080103Y-62737D01*
X1079637Y-62820D01*
X1079237Y-63070D01*
X1078970Y-63653D01*
X1078837Y-64153D01*
Y-64653D01*
X1078970Y-65153D01*
X1079303Y-65653D01*
X1079703Y-65987D01*
X1080170Y-66070D01*
X1080637Y-65903D01*
X1081103Y-65403D01*
G01X1090170Y-62737D02*
Y-66070D01*
G01Y-61403D02*
X1090037Y-61320D01*
Y-61153D01*
X1090170Y-61070D01*
X1090303Y-61153D01*
Y-61320D01*
X1090170Y-61403D01*
G01X1096470Y-67737D02*
Y-62737D01*
G01Y-63487D02*
X1096137Y-63070D01*
X1095737Y-62820D01*
X1095270Y-62737D01*
X1094870Y-62820D01*
X1094403Y-63237D01*
X1094137Y-63820D01*
X1094070Y-64403D01*
X1094137Y-64987D01*
X1094403Y-65570D01*
X1094870Y-65987D01*
X1095270Y-66070D01*
X1095737Y-65987D01*
X1096137Y-65737D01*
X1096470Y-65320D01*
G01X1099237Y-66070D02*
Y-62737D01*
G01Y-63570D02*
X1099503Y-63153D01*
X1099903Y-62820D01*
X1100437Y-62737D01*
X1100903Y-62820D01*
X1101303Y-63153D01*
X1101503Y-63737D01*
Y-66070D01*
G01X1105470D02*
X1105070Y-65987D01*
X1104670Y-65653D01*
X1104403Y-65070D01*
X1104270Y-64403D01*
X1104403Y-63737D01*
X1104670Y-63153D01*
X1105070Y-62820D01*
X1105470Y-62737D01*
X1105870Y-62820D01*
X1106270Y-63153D01*
X1106537Y-63737D01*
X1106603Y-64403D01*
X1106537Y-65070D01*
X1106270Y-65653D01*
X1105870Y-65987D01*
X1105470Y-66070D01*
G01X1109637D02*
Y-62737D01*
G01Y-63403D02*
X1109970Y-63070D01*
X1110303Y-62820D01*
X1110770Y-62737D01*
X1111103Y-62820D01*
X1111503Y-63070D01*
G01X1114670Y-63820D02*
X1116803D01*
X1116603Y-63237D01*
X1116270Y-62903D01*
X1115803Y-62737D01*
X1115337Y-62820D01*
X1114937Y-63070D01*
X1114670Y-63653D01*
X1114537Y-64153D01*
Y-64653D01*
X1114670Y-65153D01*
X1115003Y-65653D01*
X1115403Y-65987D01*
X1115870Y-66070D01*
X1116337Y-65903D01*
X1116803Y-65403D01*
G01X1125870Y-61070D02*
Y-66070D01*
G01X1124937Y-62737D02*
X1126803D01*
G01X1129837Y-66070D02*
Y-61070D01*
G01Y-63487D02*
X1130170Y-63070D01*
X1130503Y-62820D01*
X1131037Y-62737D01*
X1131437Y-62820D01*
X1131903Y-63153D01*
X1132103Y-63653D01*
Y-66070D01*
G01X1136070Y-62737D02*
Y-66070D01*
G01Y-61403D02*
X1135937Y-61320D01*
Y-61153D01*
X1136070Y-61070D01*
X1136203Y-61153D01*
Y-61320D01*
X1136070Y-61403D01*
G01X1140170Y-65487D02*
X1140503Y-65820D01*
X1140970Y-66070D01*
X1141370D01*
X1141770Y-65903D01*
X1142037Y-65653D01*
X1142170Y-65320D01*
X1142103Y-64820D01*
X1141837Y-64570D01*
X1140637Y-64070D01*
X1140370Y-63487D01*
X1140503Y-63070D01*
X1140770Y-62820D01*
X1141170Y-62737D01*
X1141570Y-62820D01*
X1141970Y-63070D01*
G01X1150437Y-66070D02*
Y-62737D01*
G01Y-63403D02*
X1150770Y-63070D01*
X1151103Y-62820D01*
X1151570Y-62737D01*
X1151903Y-62820D01*
X1152303Y-63070D01*
G01X1155470Y-63820D02*
X1157603D01*
X1157403Y-63237D01*
X1157070Y-62903D01*
X1156603Y-62737D01*
X1156137Y-62820D01*
X1155737Y-63070D01*
X1155470Y-63653D01*
X1155337Y-64153D01*
Y-64653D01*
X1155470Y-65153D01*
X1155803Y-65653D01*
X1156203Y-65987D01*
X1156670Y-66070D01*
X1157137Y-65903D01*
X1157603Y-65403D01*
G01X1162770Y-67737D02*
Y-62737D01*
G01Y-63487D02*
X1162437Y-63070D01*
X1162037Y-62820D01*
X1161570Y-62737D01*
X1161170Y-62820D01*
X1160703Y-63237D01*
X1160437Y-63820D01*
X1160370Y-64403D01*
X1160437Y-64987D01*
X1160703Y-65570D01*
X1161170Y-65987D01*
X1161570Y-66070D01*
X1162037Y-65987D01*
X1162437Y-65737D01*
X1162770Y-65320D01*
G01X1165537Y-62737D02*
Y-65070D01*
X1165803Y-65653D01*
X1166203Y-65987D01*
X1166670Y-66070D01*
X1167137Y-65987D01*
X1167537Y-65653D01*
X1167803Y-65070D01*
G01Y-66070D02*
Y-62737D01*
G01X1170770Y-63820D02*
X1172903D01*
X1172703Y-63237D01*
X1172370Y-62903D01*
X1171903Y-62737D01*
X1171437Y-62820D01*
X1171037Y-63070D01*
X1170770Y-63653D01*
X1170637Y-64153D01*
Y-64653D01*
X1170770Y-65153D01*
X1171103Y-65653D01*
X1171503Y-65987D01*
X1171970Y-66070D01*
X1172437Y-65903D01*
X1172903Y-65403D01*
G01X1175870Y-65487D02*
X1176203Y-65820D01*
X1176670Y-66070D01*
X1177070D01*
X1177470Y-65903D01*
X1177737Y-65653D01*
X1177870Y-65320D01*
X1177803Y-64820D01*
X1177537Y-64570D01*
X1176337Y-64070D01*
X1176070Y-63487D01*
X1176203Y-63070D01*
X1176470Y-62820D01*
X1176870Y-62737D01*
X1177270Y-62820D01*
X1177670Y-63070D01*
G01X1181970Y-61070D02*
Y-66070D01*
G01X1181037Y-62737D02*
X1182903D01*
G01X1187070Y-66237D02*
X1186937Y-66153D01*
Y-65987D01*
X1187070Y-65903D01*
X1187203Y-65987D01*
Y-66153D01*
X1187070Y-66237D01*
G01X777033Y123000D02*
Y128000D01*
X778367D01*
X778900Y127750D01*
X779300Y127417D01*
X779633Y126917D01*
X779900Y126333D01*
X779967Y125500D01*
X779900Y124667D01*
X779633Y124083D01*
X779300Y123583D01*
X778900Y123250D01*
X778367Y123000D01*
X777033D01*
G01X782667D02*
Y126333D01*
G01Y125667D02*
X783000Y126000D01*
X783333Y126250D01*
X783800Y126333D01*
X784133Y126250D01*
X784533Y126000D01*
G01X788700Y126333D02*
Y123000D01*
G01Y127667D02*
X788567Y127750D01*
Y127917D01*
X788700Y128000D01*
X788833Y127917D01*
Y127750D01*
X788700Y127667D01*
G01X793800Y123000D02*
Y128000D01*
G01X798900Y123000D02*
Y128000D01*
G01X807833Y123000D02*
Y128000D01*
X810367D01*
G01X809433Y125583D02*
X807833D01*
G01X813267Y123000D02*
Y126333D01*
G01Y125667D02*
X813600Y126000D01*
X813933Y126250D01*
X814400Y126333D01*
X814733Y126250D01*
X815133Y126000D01*
G01X819300Y123000D02*
X818900Y123083D01*
X818500Y123417D01*
X818233Y124000D01*
X818100Y124667D01*
X818233Y125333D01*
X818500Y125917D01*
X818900Y126250D01*
X819300Y126333D01*
X819700Y126250D01*
X820100Y125917D01*
X820367Y125333D01*
X820433Y124667D01*
X820367Y124000D01*
X820100Y123417D01*
X819700Y123083D01*
X819300Y123000D01*
G01X822400D02*
Y126333D01*
G01Y125417D02*
X822600Y125833D01*
X822933Y126167D01*
X823400Y126333D01*
X823867Y126167D01*
X824200Y125833D01*
X824400Y125417D01*
Y123000D01*
G01Y125417D02*
X824600Y125833D01*
X824933Y126167D01*
X825400Y126333D01*
X825867Y126167D01*
X826200Y125833D01*
X826400Y125333D01*
Y123000D01*
G01X833267Y128000D02*
Y123000D01*
X835933D01*
G01X839700D02*
Y128000D01*
X838900Y127000D01*
G01Y123000D02*
X840500D01*
G01X849567Y121333D02*
X848900Y122167D01*
X848567Y123000D01*
Y126333D01*
X848900Y127167D01*
X849567Y128000D01*
G01X855000D02*
Y123000D01*
G01X853467Y128000D02*
X856533D01*
G01X860100Y123000D02*
X859567Y123083D01*
X859100Y123417D01*
X858700Y123917D01*
X858433Y124500D01*
X858300Y125167D01*
Y125833D01*
X858433Y126500D01*
X858700Y127083D01*
X859100Y127583D01*
X859567Y127917D01*
X860100Y128000D01*
X860633Y127917D01*
X861100Y127583D01*
X861500Y127083D01*
X861767Y126500D01*
X861900Y125833D01*
Y125167D01*
X861767Y124500D01*
X861500Y123917D01*
X861100Y123417D01*
X860633Y123083D01*
X860100Y123000D01*
G01X863867D02*
Y128000D01*
X865467D01*
X866000Y127750D01*
X866400Y127167D01*
X866533Y126500D01*
X866400Y125833D01*
X866067Y125333D01*
X865467Y125083D01*
X863867D01*
G01X870633Y121333D02*
X871300Y122167D01*
X871633Y123000D01*
Y126333D01*
X871300Y127167D01*
X870633Y128000D01*
G01X880500D02*
Y123000D01*
G01X879567Y126333D02*
X881433D01*
G01X885600Y123000D02*
X885200Y123083D01*
X884800Y123417D01*
X884533Y124000D01*
X884400Y124667D01*
X884533Y125333D01*
X884800Y125917D01*
X885200Y126250D01*
X885600Y126333D01*
X886000Y126250D01*
X886400Y125917D01*
X886667Y125333D01*
X886733Y124667D01*
X886667Y124000D01*
X886400Y123417D01*
X886000Y123083D01*
X885600Y123000D01*
G01X894467Y128000D02*
Y123000D01*
X897133D01*
G01X899900Y126333D02*
X901900Y123000D01*
G01Y126333D02*
X899900Y123000D01*
G01X777417Y104700D02*
Y99700D01*
X780083D01*
G01X782850Y103033D02*
X784850Y99700D01*
G01Y103033D02*
X782850Y99700D01*
G01X788950Y99533D02*
X788817Y99617D01*
Y99783D01*
X788950Y99867D01*
X789083Y99783D01*
Y99617D01*
X788950Y99533D01*
G01Y101783D02*
X788817Y101867D01*
Y102033D01*
X788950Y102117D01*
X789083Y102033D01*
Y101867D01*
X788950Y101783D01*
G01X797150Y99700D02*
Y103033D01*
G01Y102117D02*
X797350Y102533D01*
X797683Y102867D01*
X798150Y103033D01*
X798617Y102867D01*
X798950Y102533D01*
X799150Y102117D01*
Y99700D01*
G01Y102117D02*
X799350Y102533D01*
X799683Y102867D01*
X800150Y103033D01*
X800617Y102867D01*
X800950Y102533D01*
X801150Y102033D01*
Y99700D01*
G01X803117Y103033D02*
Y100700D01*
X803383Y100117D01*
X803783Y99783D01*
X804250Y99700D01*
X804717Y99783D01*
X805117Y100117D01*
X805383Y100700D01*
G01Y99700D02*
Y103033D01*
G01X808350Y100283D02*
X808683Y99950D01*
X809150Y99700D01*
X809550D01*
X809950Y99867D01*
X810217Y100117D01*
X810350Y100450D01*
X810283Y100950D01*
X810017Y101200D01*
X808817Y101700D01*
X808550Y102283D01*
X808683Y102700D01*
X808950Y102950D01*
X809350Y103033D01*
X809750Y102950D01*
X810150Y102700D01*
G01X814450Y104700D02*
Y99700D01*
G01X813517Y103033D02*
X815383D01*
G01X823450Y99700D02*
Y104700D01*
G01Y102200D02*
X823783Y102700D01*
X824183Y102950D01*
X824583Y103033D01*
X825183Y102867D01*
X825583Y102533D01*
X825850Y101950D01*
Y101283D01*
X825717Y100617D01*
X825450Y100117D01*
X824983Y99783D01*
X824583Y99700D01*
X824183Y99783D01*
X823783Y100033D01*
X823450Y100450D01*
G01X828750Y101950D02*
X830883D01*
X830683Y102533D01*
X830350Y102867D01*
X829883Y103033D01*
X829417Y102950D01*
X829017Y102700D01*
X828750Y102117D01*
X828617Y101617D01*
Y101117D01*
X828750Y100617D01*
X829083Y100117D01*
X829483Y99783D01*
X829950Y99700D01*
X830417Y99867D01*
X830883Y100367D01*
G01X838750Y99700D02*
Y104700D01*
G01Y102200D02*
X839083Y102700D01*
X839483Y102950D01*
X839883Y103033D01*
X840483Y102867D01*
X840883Y102533D01*
X841150Y101950D01*
Y101283D01*
X841017Y100617D01*
X840750Y100117D01*
X840283Y99783D01*
X839883Y99700D01*
X839483Y99783D01*
X839083Y100033D01*
X838750Y100450D01*
G01X844117Y99700D02*
Y103033D01*
G01Y102367D02*
X844450Y102700D01*
X844783Y102950D01*
X845250Y103033D01*
X845583Y102950D01*
X845983Y102700D01*
G01X850150Y99700D02*
X849750Y99783D01*
X849350Y100117D01*
X849083Y100700D01*
X848950Y101367D01*
X849083Y102033D01*
X849350Y102617D01*
X849750Y102950D01*
X850150Y103033D01*
X850550Y102950D01*
X850950Y102617D01*
X851217Y102033D01*
X851283Y101367D01*
X851217Y100700D01*
X850950Y100117D01*
X850550Y99783D01*
X850150Y99700D01*
G01X854117D02*
Y104700D01*
G01X856250Y103033D02*
X854117Y101117D01*
G01X854983Y101867D02*
X856383Y99700D01*
G01X859350Y101950D02*
X861483D01*
X861283Y102533D01*
X860950Y102867D01*
X860483Y103033D01*
X860017Y102950D01*
X859617Y102700D01*
X859350Y102117D01*
X859217Y101617D01*
Y101117D01*
X859350Y100617D01*
X859683Y100117D01*
X860083Y99783D01*
X860550Y99700D01*
X861017Y99867D01*
X861483Y100367D01*
G01X864317Y99700D02*
Y103033D01*
G01Y102200D02*
X864583Y102617D01*
X864983Y102950D01*
X865517Y103033D01*
X865983Y102950D01*
X866383Y102617D01*
X866583Y102033D01*
Y99700D01*
G01X875650D02*
Y104700D01*
G01X881950Y99700D02*
Y103033D01*
G01Y102450D02*
X881683Y102783D01*
X881283Y102950D01*
X880817Y103033D01*
X880350Y102867D01*
X879950Y102533D01*
X879683Y102033D01*
X879550Y101367D01*
X879683Y100700D01*
X879950Y100200D01*
X880350Y99867D01*
X880817Y99700D01*
X881283Y99783D01*
X881683Y100033D01*
X881950Y100367D01*
G01X884450Y98200D02*
X884850Y98033D01*
X885383Y98200D01*
X885717Y98533D01*
X885983Y98950D01*
X886383Y100283D01*
X887250Y103033D01*
G01X885117D02*
X886383Y100283D01*
G01X889950Y101950D02*
X892083D01*
X891883Y102533D01*
X891550Y102867D01*
X891083Y103033D01*
X890617Y102950D01*
X890217Y102700D01*
X889950Y102117D01*
X889817Y101617D01*
Y101117D01*
X889950Y100617D01*
X890283Y100117D01*
X890683Y99783D01*
X891150Y99700D01*
X891617Y99867D01*
X892083Y100367D01*
G01X895117Y99700D02*
Y103033D01*
G01Y102367D02*
X895450Y102700D01*
X895783Y102950D01*
X896250Y103033D01*
X896583Y102950D01*
X896983Y102700D01*
G01X776817Y116310D02*
Y111310D01*
X779483D01*
G01X782117D02*
Y114643D01*
G01Y113810D02*
X782383Y114227D01*
X782783Y114560D01*
X783317Y114643D01*
X783783Y114560D01*
X784183Y114227D01*
X784383Y113643D01*
Y111310D01*
G01X788350Y111143D02*
X788217Y111227D01*
Y111393D01*
X788350Y111477D01*
X788483Y111393D01*
Y111227D01*
X788350Y111143D01*
G01Y113393D02*
X788217Y113477D01*
Y113643D01*
X788350Y113727D01*
X788483Y113643D01*
Y113477D01*
X788350Y113393D01*
G01X799617Y114227D02*
X799150Y114560D01*
X798750Y114643D01*
X798217Y114477D01*
X797817Y114143D01*
X797550Y113560D01*
X797483Y112977D01*
X797550Y112393D01*
X797817Y111893D01*
X798217Y111477D01*
X798750Y111310D01*
X799217Y111477D01*
X799617Y111810D01*
G01X804850Y111310D02*
Y114643D01*
G01Y114060D02*
X804583Y114393D01*
X804183Y114560D01*
X803717Y114643D01*
X803250Y114477D01*
X802850Y114143D01*
X802583Y113643D01*
X802450Y112977D01*
X802583Y112310D01*
X802850Y111810D01*
X803250Y111477D01*
X803717Y111310D01*
X804183Y111393D01*
X804583Y111643D01*
X804850Y111977D01*
G01X807617Y111310D02*
Y114643D01*
G01Y113810D02*
X807883Y114227D01*
X808283Y114560D01*
X808817Y114643D01*
X809283Y114560D01*
X809683Y114227D01*
X809883Y113643D01*
Y111310D01*
G01X813850Y114643D02*
X814517Y115685D01*
Y116310D01*
X814017D01*
Y115685D01*
X814517D01*
G01X818950Y116310D02*
Y111310D01*
G01X818017Y114643D02*
X819883D01*
G01X827950Y111310D02*
Y116310D01*
G01Y113810D02*
X828283Y114310D01*
X828683Y114560D01*
X829083Y114643D01*
X829683Y114477D01*
X830083Y114143D01*
X830350Y113560D01*
Y112893D01*
X830217Y112227D01*
X829950Y111727D01*
X829483Y111393D01*
X829083Y111310D01*
X828683Y111393D01*
X828283Y111643D01*
X827950Y112060D01*
G01X833250Y113560D02*
X835383D01*
X835183Y114143D01*
X834850Y114477D01*
X834383Y114643D01*
X833917Y114560D01*
X833517Y114310D01*
X833250Y113727D01*
X833117Y113227D01*
Y112727D01*
X833250Y112227D01*
X833583Y111727D01*
X833983Y111393D01*
X834450Y111310D01*
X834917Y111477D01*
X835383Y111977D01*
G01X843250Y111310D02*
Y116310D01*
G01Y113810D02*
X843583Y114310D01*
X843983Y114560D01*
X844383Y114643D01*
X844983Y114477D01*
X845383Y114143D01*
X845650Y113560D01*
Y112893D01*
X845517Y112227D01*
X845250Y111727D01*
X844783Y111393D01*
X844383Y111310D01*
X843983Y111393D01*
X843583Y111643D01*
X843250Y112060D01*
G01X848617Y111310D02*
Y114643D01*
G01Y113977D02*
X848950Y114310D01*
X849283Y114560D01*
X849750Y114643D01*
X850083Y114560D01*
X850483Y114310D01*
G01X854650Y111310D02*
X854250Y111393D01*
X853850Y111727D01*
X853583Y112310D01*
X853450Y112977D01*
X853583Y113643D01*
X853850Y114227D01*
X854250Y114560D01*
X854650Y114643D01*
X855050Y114560D01*
X855450Y114227D01*
X855717Y113643D01*
X855783Y112977D01*
X855717Y112310D01*
X855450Y111727D01*
X855050Y111393D01*
X854650Y111310D01*
G01X858617D02*
Y116310D01*
G01X860750Y114643D02*
X858617Y112727D01*
G01X859483Y113477D02*
X860883Y111310D01*
G01X863850Y113560D02*
X865983D01*
X865783Y114143D01*
X865450Y114477D01*
X864983Y114643D01*
X864517Y114560D01*
X864117Y114310D01*
X863850Y113727D01*
X863717Y113227D01*
Y112727D01*
X863850Y112227D01*
X864183Y111727D01*
X864583Y111393D01*
X865050Y111310D01*
X865517Y111477D01*
X865983Y111977D01*
G01X868817Y111310D02*
Y114643D01*
G01Y113810D02*
X869083Y114227D01*
X869483Y114560D01*
X870017Y114643D01*
X870483Y114560D01*
X870883Y114227D01*
X871083Y113643D01*
Y111310D01*
G01X880150D02*
Y116310D01*
G01X886450Y111310D02*
Y114643D01*
G01Y114060D02*
X886183Y114393D01*
X885783Y114560D01*
X885317Y114643D01*
X884850Y114477D01*
X884450Y114143D01*
X884183Y113643D01*
X884050Y112977D01*
X884183Y112310D01*
X884450Y111810D01*
X884850Y111477D01*
X885317Y111310D01*
X885783Y111393D01*
X886183Y111643D01*
X886450Y111977D01*
G01X888950Y109810D02*
X889350Y109643D01*
X889883Y109810D01*
X890217Y110143D01*
X890483Y110560D01*
X890883Y111893D01*
X891750Y114643D01*
G01X889617D02*
X890883Y111893D01*
G01X894450Y113560D02*
X896583D01*
X896383Y114143D01*
X896050Y114477D01*
X895583Y114643D01*
X895117Y114560D01*
X894717Y114310D01*
X894450Y113727D01*
X894317Y113227D01*
Y112727D01*
X894450Y112227D01*
X894783Y111727D01*
X895183Y111393D01*
X895650Y111310D01*
X896117Y111477D01*
X896583Y111977D01*
G01X899617Y111310D02*
Y114643D01*
G01Y113977D02*
X899950Y114310D01*
X900283Y114560D01*
X900750Y114643D01*
X901083Y114560D01*
X901483Y114310D01*
G01X802033Y-15500D02*
Y-10500D01*
X803367D01*
X803900Y-10750D01*
X804300Y-11083D01*
X804633Y-11583D01*
X804900Y-12167D01*
X804967Y-13000D01*
X804900Y-13833D01*
X804633Y-14417D01*
X804300Y-14917D01*
X803900Y-15250D01*
X803367Y-15500D01*
X802033D01*
G01X808600D02*
Y-10500D01*
X807800Y-11500D01*
G01Y-15500D02*
X809400D01*
G01X812433Y-13417D02*
X812900Y-12833D01*
X813300Y-12500D01*
X813833Y-12333D01*
X814300Y-12500D01*
X814633Y-12833D01*
X814900Y-13333D01*
X814967Y-13917D01*
X814900Y-14417D01*
X814633Y-14917D01*
X814233Y-15333D01*
X813767Y-15500D01*
X813233Y-15333D01*
X812767Y-14833D01*
X812500Y-14083D01*
X812433Y-13250D01*
X812567Y-12167D01*
X812767Y-11583D01*
X813100Y-11000D01*
X813567Y-10583D01*
X814033Y-10500D01*
X814500Y-10667D01*
X814833Y-11083D01*
G01X827533Y150500D02*
Y155500D01*
X828867D01*
X829400Y155250D01*
X829800Y154917D01*
X830133Y154417D01*
X830400Y153833D01*
X830467Y153000D01*
X830400Y152167D01*
X830133Y151583D01*
X829800Y151083D01*
X829400Y150750D01*
X828867Y150500D01*
X827533D01*
G01X834100D02*
Y155500D01*
X833300Y154500D01*
G01Y150500D02*
X834900D01*
G01X825533Y314500D02*
Y319500D01*
X826867D01*
X827400Y319250D01*
X827800Y318917D01*
X828133Y318417D01*
X828400Y317833D01*
X828467Y317000D01*
X828400Y316167D01*
X828133Y315583D01*
X827800Y315083D01*
X827400Y314750D01*
X826867Y314500D01*
X825533D01*
G01X830833Y318667D02*
X831233Y319167D01*
X831700Y319417D01*
X832233Y319500D01*
X832900Y319333D01*
X833367Y318917D01*
X833500Y318417D01*
X833433Y317917D01*
X833167Y317500D01*
X831833Y316667D01*
X831233Y316083D01*
X830833Y315250D01*
X830700Y314500D01*
X833500D01*
G01X820790Y376450D02*
Y379783D01*
G01Y379200D02*
X820523Y379533D01*
X820123Y379700D01*
X819657Y379783D01*
X819190Y379617D01*
X818790Y379283D01*
X818523Y378783D01*
X818390Y378117D01*
X818523Y377450D01*
X818790Y376950D01*
X819190Y376617D01*
X819657Y376450D01*
X820123Y376533D01*
X820523Y376783D01*
X820790Y377117D01*
G01X823557Y376450D02*
Y379783D01*
G01Y378950D02*
X823823Y379367D01*
X824223Y379700D01*
X824757Y379783D01*
X825223Y379700D01*
X825623Y379367D01*
X825823Y378783D01*
Y376450D01*
G01X830990Y381450D02*
Y376450D01*
G01Y377200D02*
X830723Y376783D01*
X830323Y376533D01*
X829857Y376450D01*
X829323Y376617D01*
X828923Y377033D01*
X828657Y377533D01*
X828590Y378117D01*
X828657Y378700D01*
X828923Y379200D01*
X829323Y379617D01*
X829857Y379783D01*
X830323Y379700D01*
X830657Y379533D01*
X830990Y379200D01*
G01X841057Y379367D02*
X840590Y379700D01*
X840190Y379783D01*
X839657Y379617D01*
X839257Y379283D01*
X838990Y378700D01*
X838923Y378117D01*
X838990Y377533D01*
X839257Y377033D01*
X839657Y376617D01*
X840190Y376450D01*
X840657Y376617D01*
X841057Y376950D01*
G01X845090Y376450D02*
X844690Y376533D01*
X844290Y376867D01*
X844023Y377450D01*
X843890Y378117D01*
X844023Y378783D01*
X844290Y379367D01*
X844690Y379700D01*
X845090Y379783D01*
X845490Y379700D01*
X845890Y379367D01*
X846157Y378783D01*
X846223Y378117D01*
X846157Y377450D01*
X845890Y376867D01*
X845490Y376533D01*
X845090Y376450D01*
G01X848990Y379783D02*
X850190Y376450D01*
X851390Y379783D01*
G01X854290Y378700D02*
X856423D01*
X856223Y379283D01*
X855890Y379617D01*
X855423Y379783D01*
X854957Y379700D01*
X854557Y379450D01*
X854290Y378867D01*
X854157Y378367D01*
Y377867D01*
X854290Y377367D01*
X854623Y376867D01*
X855023Y376533D01*
X855490Y376450D01*
X855957Y376617D01*
X856423Y377117D01*
G01X859457Y376450D02*
Y379783D01*
G01Y379117D02*
X859790Y379450D01*
X860123Y379700D01*
X860590Y379783D01*
X860923Y379700D01*
X861323Y379450D01*
G01X864490Y378700D02*
X866623D01*
X866423Y379283D01*
X866090Y379617D01*
X865623Y379783D01*
X865157Y379700D01*
X864757Y379450D01*
X864490Y378867D01*
X864357Y378367D01*
Y377867D01*
X864490Y377367D01*
X864823Y376867D01*
X865223Y376533D01*
X865690Y376450D01*
X866157Y376617D01*
X866623Y377117D01*
G01X871790Y381450D02*
Y376450D01*
G01Y377200D02*
X871523Y376783D01*
X871123Y376533D01*
X870657Y376450D01*
X870123Y376617D01*
X869723Y377033D01*
X869457Y377533D01*
X869390Y378117D01*
X869457Y378700D01*
X869723Y379200D01*
X870123Y379617D01*
X870657Y379783D01*
X871123Y379700D01*
X871457Y379533D01*
X871790Y379200D01*
G01X879123Y379783D02*
X879923Y376450D01*
X880790Y379783D01*
X881657Y376450D01*
X882457Y379783D01*
G01X885890D02*
Y376450D01*
G01Y381117D02*
X885757Y381200D01*
Y381367D01*
X885890Y381450D01*
X886023Y381367D01*
Y381200D01*
X885890Y381117D01*
G01X890990Y381450D02*
Y376450D01*
G01X890057Y379783D02*
X891923D01*
G01X894957Y376450D02*
Y381450D01*
G01Y379033D02*
X895290Y379450D01*
X895623Y379700D01*
X896157Y379783D01*
X896557Y379700D01*
X897023Y379367D01*
X897223Y378867D01*
Y376450D01*
G01X907357Y379367D02*
X906890Y379700D01*
X906490Y379783D01*
X905957Y379617D01*
X905557Y379283D01*
X905290Y378700D01*
X905223Y378117D01*
X905290Y377533D01*
X905557Y377033D01*
X905957Y376617D01*
X906490Y376450D01*
X906957Y376617D01*
X907357Y376950D01*
G01X911390Y376450D02*
X910990Y376533D01*
X910590Y376867D01*
X910323Y377450D01*
X910190Y378117D01*
X910323Y378783D01*
X910590Y379367D01*
X910990Y379700D01*
X911390Y379783D01*
X911790Y379700D01*
X912190Y379367D01*
X912457Y378783D01*
X912523Y378117D01*
X912457Y377450D01*
X912190Y376867D01*
X911790Y376533D01*
X911390Y376450D01*
G01X915290Y374783D02*
Y379783D01*
G01Y379033D02*
X915623Y379450D01*
X915957Y379700D01*
X916490Y379783D01*
X916957Y379700D01*
X917423Y379283D01*
X917623Y378700D01*
X917690Y378117D01*
X917623Y377533D01*
X917423Y376950D01*
X917023Y376617D01*
X916490Y376450D01*
X916023Y376533D01*
X915557Y376783D01*
X915290Y377117D01*
G01X920390Y374783D02*
Y379783D01*
G01Y379033D02*
X920723Y379450D01*
X921057Y379700D01*
X921590Y379783D01*
X922057Y379700D01*
X922523Y379283D01*
X922723Y378700D01*
X922790Y378117D01*
X922723Y377533D01*
X922523Y376950D01*
X922123Y376617D01*
X921590Y376450D01*
X921123Y376533D01*
X920657Y376783D01*
X920390Y377117D01*
G01X925690Y378700D02*
X927823D01*
X927623Y379283D01*
X927290Y379617D01*
X926823Y379783D01*
X926357Y379700D01*
X925957Y379450D01*
X925690Y378867D01*
X925557Y378367D01*
Y377867D01*
X925690Y377367D01*
X926023Y376867D01*
X926423Y376533D01*
X926890Y376450D01*
X927357Y376617D01*
X927823Y377117D01*
G01X930857Y376450D02*
Y379783D01*
G01Y379117D02*
X931190Y379450D01*
X931523Y379700D01*
X931990Y379783D01*
X932323Y379700D01*
X932723Y379450D01*
G01X819190Y389810D02*
Y394060D01*
X819323Y394477D01*
X819590Y394727D01*
X819990Y394810D01*
X820390Y394643D01*
X820590Y394227D01*
G01X819790Y392810D02*
X818457D01*
G01X824690Y389810D02*
X824290Y389893D01*
X823890Y390227D01*
X823623Y390810D01*
X823490Y391477D01*
X823623Y392143D01*
X823890Y392727D01*
X824290Y393060D01*
X824690Y393143D01*
X825090Y393060D01*
X825490Y392727D01*
X825757Y392143D01*
X825823Y391477D01*
X825757Y390810D01*
X825490Y390227D01*
X825090Y389893D01*
X824690Y389810D01*
G01X829790D02*
Y394810D01*
G01X834890Y389810D02*
Y394810D01*
G01X839990Y389810D02*
X839590Y389893D01*
X839190Y390227D01*
X838923Y390810D01*
X838790Y391477D01*
X838923Y392143D01*
X839190Y392727D01*
X839590Y393060D01*
X839990Y393143D01*
X840390Y393060D01*
X840790Y392727D01*
X841057Y392143D01*
X841123Y391477D01*
X841057Y390810D01*
X840790Y390227D01*
X840390Y389893D01*
X839990Y389810D01*
G01X843423Y393143D02*
X844223Y389810D01*
X845090Y393143D01*
X845957Y389810D01*
X846757Y393143D01*
G01X855690Y392310D02*
X857023D01*
Y390810D01*
X856623Y390310D01*
X856157Y389977D01*
X855490Y389810D01*
X854823Y389977D01*
X854357Y390310D01*
X853957Y390810D01*
X853690Y391393D01*
X853557Y392060D01*
Y392643D01*
X853690Y393143D01*
X853957Y393727D01*
X854357Y394227D01*
X854757Y394560D01*
X855290Y394810D01*
X855757D01*
X856290Y394643D01*
X856690Y394310D01*
G01X859390Y392060D02*
X861523D01*
X861323Y392643D01*
X860990Y392977D01*
X860523Y393143D01*
X860057Y393060D01*
X859657Y392810D01*
X859390Y392227D01*
X859257Y391727D01*
Y391227D01*
X859390Y390727D01*
X859723Y390227D01*
X860123Y389893D01*
X860590Y389810D01*
X861057Y389977D01*
X861523Y390477D01*
G01X864557Y389810D02*
Y393143D01*
G01Y392477D02*
X864890Y392810D01*
X865223Y393060D01*
X865690Y393143D01*
X866023Y393060D01*
X866423Y392810D01*
G01X869390Y389810D02*
Y394810D01*
G01Y392310D02*
X869723Y392810D01*
X870123Y393060D01*
X870523Y393143D01*
X871123Y392977D01*
X871523Y392643D01*
X871790Y392060D01*
Y391393D01*
X871657Y390727D01*
X871390Y390227D01*
X870923Y389893D01*
X870523Y389810D01*
X870123Y389893D01*
X869723Y390143D01*
X869390Y390560D01*
G01X874690Y392060D02*
X876823D01*
X876623Y392643D01*
X876290Y392977D01*
X875823Y393143D01*
X875357Y393060D01*
X874957Y392810D01*
X874690Y392227D01*
X874557Y391727D01*
Y391227D01*
X874690Y390727D01*
X875023Y390227D01*
X875423Y389893D01*
X875890Y389810D01*
X876357Y389977D01*
X876823Y390477D01*
G01X879857Y389810D02*
Y393143D01*
G01Y392477D02*
X880190Y392810D01*
X880523Y393060D01*
X880990Y393143D01*
X881323Y393060D01*
X881723Y392810D01*
G01X892190Y389810D02*
Y393143D01*
G01Y392560D02*
X891923Y392893D01*
X891523Y393060D01*
X891057Y393143D01*
X890590Y392977D01*
X890190Y392643D01*
X889923Y392143D01*
X889790Y391477D01*
X889923Y390810D01*
X890190Y390310D01*
X890590Y389977D01*
X891057Y389810D01*
X891523Y389893D01*
X891923Y390143D01*
X892190Y390477D01*
G01X894957Y389810D02*
Y393143D01*
G01Y392310D02*
X895223Y392727D01*
X895623Y393060D01*
X896157Y393143D01*
X896623Y393060D01*
X897023Y392727D01*
X897223Y392143D01*
Y389810D01*
G01X902390Y394810D02*
Y389810D01*
G01Y390560D02*
X902123Y390143D01*
X901723Y389893D01*
X901257Y389810D01*
X900723Y389977D01*
X900323Y390393D01*
X900057Y390893D01*
X899990Y391477D01*
X900057Y392060D01*
X900323Y392560D01*
X900723Y392977D01*
X901257Y393143D01*
X901723Y393060D01*
X902057Y392893D01*
X902390Y392560D01*
G01X910190Y388143D02*
Y393143D01*
G01Y392393D02*
X910523Y392810D01*
X910857Y393060D01*
X911390Y393143D01*
X911857Y393060D01*
X912323Y392643D01*
X912523Y392060D01*
X912590Y391477D01*
X912523Y390893D01*
X912323Y390310D01*
X911923Y389977D01*
X911390Y389810D01*
X910923Y389893D01*
X910457Y390143D01*
X910190Y390477D01*
G01X916490Y389810D02*
Y394810D01*
G01X920457Y393143D02*
Y390810D01*
X920723Y390227D01*
X921123Y389893D01*
X921590Y389810D01*
X922057Y389893D01*
X922457Y390227D01*
X922723Y390810D01*
G01Y389810D02*
Y393143D01*
G01X925757Y388560D02*
X926223Y388227D01*
X926757Y388143D01*
X927223Y388227D01*
X927623Y388643D01*
X927890Y389227D01*
Y393143D01*
G01Y392477D02*
X927623Y392810D01*
X927223Y393060D01*
X926757Y393143D01*
X926223Y392977D01*
X925890Y392643D01*
X925623Y392060D01*
X925490Y391477D01*
X925557Y390977D01*
X925823Y390393D01*
X926223Y389977D01*
X926757Y389810D01*
X927157Y389893D01*
X927623Y390227D01*
X927890Y390560D01*
G01X935223Y393143D02*
X936023Y389810D01*
X936890Y393143D01*
X937757Y389810D01*
X938557Y393143D01*
G01X941990D02*
Y389810D01*
G01Y394477D02*
X941857Y394560D01*
Y394727D01*
X941990Y394810D01*
X942123Y394727D01*
Y394560D01*
X941990Y394477D01*
G01X947090Y394810D02*
Y389810D01*
G01X946157Y393143D02*
X948023D01*
G01X951057Y389810D02*
Y394810D01*
G01Y392393D02*
X951390Y392810D01*
X951723Y393060D01*
X952257Y393143D01*
X952657Y393060D01*
X953123Y392727D01*
X953323Y392227D01*
Y389810D01*
G01X961457D02*
Y393143D01*
G01Y392477D02*
X961790Y392810D01*
X962123Y393060D01*
X962590Y393143D01*
X962923Y393060D01*
X963323Y392810D01*
G01X966490Y392060D02*
X968623D01*
X968423Y392643D01*
X968090Y392977D01*
X967623Y393143D01*
X967157Y393060D01*
X966757Y392810D01*
X966490Y392227D01*
X966357Y391727D01*
Y391227D01*
X966490Y390727D01*
X966823Y390227D01*
X967223Y389893D01*
X967690Y389810D01*
X968157Y389977D01*
X968623Y390477D01*
G01X971590Y390393D02*
X971923Y390060D01*
X972390Y389810D01*
X972790D01*
X973190Y389977D01*
X973457Y390227D01*
X973590Y390560D01*
X973523Y391060D01*
X973257Y391310D01*
X972057Y391810D01*
X971790Y392393D01*
X971923Y392810D01*
X972190Y393060D01*
X972590Y393143D01*
X972990Y393060D01*
X973390Y392810D01*
G01X977690Y393143D02*
Y389810D01*
G01Y394477D02*
X977557Y394560D01*
Y394727D01*
X977690Y394810D01*
X977823Y394727D01*
Y394560D01*
X977690Y394477D01*
G01X981657Y389810D02*
Y393143D01*
G01Y392310D02*
X981923Y392727D01*
X982323Y393060D01*
X982857Y393143D01*
X983323Y393060D01*
X983723Y392727D01*
X983923Y392143D01*
Y389810D01*
G01X812000Y604500D02*
Y366000D01*
G01X822700Y455500D02*
Y458833D01*
G01Y458250D02*
X822433Y458583D01*
X822033Y458750D01*
X821567Y458833D01*
X821100Y458667D01*
X820700Y458333D01*
X820433Y457833D01*
X820300Y457167D01*
X820433Y456500D01*
X820700Y456000D01*
X821100Y455667D01*
X821567Y455500D01*
X822033Y455583D01*
X822433Y455833D01*
X822700Y456167D01*
G01X825467Y455500D02*
Y458833D01*
G01Y458000D02*
X825733Y458417D01*
X826133Y458750D01*
X826667Y458833D01*
X827133Y458750D01*
X827533Y458417D01*
X827733Y457833D01*
Y455500D01*
G01X832900Y460500D02*
Y455500D01*
G01Y456250D02*
X832633Y455833D01*
X832233Y455583D01*
X831767Y455500D01*
X831233Y455667D01*
X830833Y456083D01*
X830567Y456583D01*
X830500Y457167D01*
X830567Y457750D01*
X830833Y458250D01*
X831233Y458667D01*
X831767Y458833D01*
X832233Y458750D01*
X832567Y458583D01*
X832900Y458250D01*
G01X840700Y455500D02*
Y460500D01*
G01Y458000D02*
X841033Y458500D01*
X841433Y458750D01*
X841833Y458833D01*
X842433Y458667D01*
X842833Y458333D01*
X843100Y457750D01*
Y457083D01*
X842967Y456417D01*
X842700Y455917D01*
X842233Y455583D01*
X841833Y455500D01*
X841433Y455583D01*
X841033Y455833D01*
X840700Y456250D01*
G01X847000Y455500D02*
X846600Y455583D01*
X846200Y455917D01*
X845933Y456500D01*
X845800Y457167D01*
X845933Y457833D01*
X846200Y458417D01*
X846600Y458750D01*
X847000Y458833D01*
X847400Y458750D01*
X847800Y458417D01*
X848067Y457833D01*
X848133Y457167D01*
X848067Y456500D01*
X847800Y455917D01*
X847400Y455583D01*
X847000Y455500D01*
G01X852100Y460500D02*
Y455500D01*
G01X851167Y458833D02*
X853033D01*
G01X857200Y460500D02*
Y455500D01*
G01X856267Y458833D02*
X858133D01*
G01X862300Y455500D02*
X861900Y455583D01*
X861500Y455917D01*
X861233Y456500D01*
X861100Y457167D01*
X861233Y457833D01*
X861500Y458417D01*
X861900Y458750D01*
X862300Y458833D01*
X862700Y458750D01*
X863100Y458417D01*
X863367Y457833D01*
X863433Y457167D01*
X863367Y456500D01*
X863100Y455917D01*
X862700Y455583D01*
X862300Y455500D01*
G01X865400D02*
Y458833D01*
G01Y457917D02*
X865600Y458333D01*
X865933Y458667D01*
X866400Y458833D01*
X866867Y458667D01*
X867200Y458333D01*
X867400Y457917D01*
Y455500D01*
G01Y457917D02*
X867600Y458333D01*
X867933Y458667D01*
X868400Y458833D01*
X868867Y458667D01*
X869200Y458333D01*
X869400Y457833D01*
Y455500D01*
G01X876600Y456083D02*
X876933Y455750D01*
X877400Y455500D01*
X877800D01*
X878200Y455667D01*
X878467Y455917D01*
X878600Y456250D01*
X878533Y456750D01*
X878267Y457000D01*
X877067Y457500D01*
X876800Y458083D01*
X876933Y458500D01*
X877200Y458750D01*
X877600Y458833D01*
X878000Y458750D01*
X878400Y458500D01*
G01X882700Y458833D02*
Y455500D01*
G01Y460167D02*
X882567Y460250D01*
Y460417D01*
X882700Y460500D01*
X882833Y460417D01*
Y460250D01*
X882700Y460167D01*
G01X889000Y460500D02*
Y455500D01*
G01Y456250D02*
X888733Y455833D01*
X888333Y455583D01*
X887867Y455500D01*
X887333Y455667D01*
X886933Y456083D01*
X886667Y456583D01*
X886600Y457167D01*
X886667Y457750D01*
X886933Y458250D01*
X887333Y458667D01*
X887867Y458833D01*
X888333Y458750D01*
X888667Y458583D01*
X889000Y458250D01*
G01X891900Y457750D02*
X894033D01*
X893833Y458333D01*
X893500Y458667D01*
X893033Y458833D01*
X892567Y458750D01*
X892167Y458500D01*
X891900Y457917D01*
X891767Y457417D01*
Y456917D01*
X891900Y456417D01*
X892233Y455917D01*
X892633Y455583D01*
X893100Y455500D01*
X893567Y455667D01*
X894033Y456167D01*
G01X821100Y440500D02*
Y444750D01*
X821233Y445167D01*
X821500Y445417D01*
X821900Y445500D01*
X822300Y445333D01*
X822500Y444917D01*
G01X821700Y443500D02*
X820367D01*
G01X826600Y440500D02*
X826200Y440583D01*
X825800Y440917D01*
X825533Y441500D01*
X825400Y442167D01*
X825533Y442833D01*
X825800Y443417D01*
X826200Y443750D01*
X826600Y443833D01*
X827000Y443750D01*
X827400Y443417D01*
X827667Y442833D01*
X827733Y442167D01*
X827667Y441500D01*
X827400Y440917D01*
X827000Y440583D01*
X826600Y440500D01*
G01X831700D02*
Y445500D01*
G01X836800Y440500D02*
Y445500D01*
G01X841900Y440500D02*
X841500Y440583D01*
X841100Y440917D01*
X840833Y441500D01*
X840700Y442167D01*
X840833Y442833D01*
X841100Y443417D01*
X841500Y443750D01*
X841900Y443833D01*
X842300Y443750D01*
X842700Y443417D01*
X842967Y442833D01*
X843033Y442167D01*
X842967Y441500D01*
X842700Y440917D01*
X842300Y440583D01*
X841900Y440500D01*
G01X845333Y443833D02*
X846133Y440500D01*
X847000Y443833D01*
X847867Y440500D01*
X848667Y443833D01*
G01X857600Y443000D02*
X858933D01*
Y441500D01*
X858533Y441000D01*
X858067Y440667D01*
X857400Y440500D01*
X856733Y440667D01*
X856267Y441000D01*
X855867Y441500D01*
X855600Y442083D01*
X855467Y442750D01*
Y443333D01*
X855600Y443833D01*
X855867Y444417D01*
X856267Y444917D01*
X856667Y445250D01*
X857200Y445500D01*
X857667D01*
X858200Y445333D01*
X858600Y445000D01*
G01X861300Y442750D02*
X863433D01*
X863233Y443333D01*
X862900Y443667D01*
X862433Y443833D01*
X861967Y443750D01*
X861567Y443500D01*
X861300Y442917D01*
X861167Y442417D01*
Y441917D01*
X861300Y441417D01*
X861633Y440917D01*
X862033Y440583D01*
X862500Y440500D01*
X862967Y440667D01*
X863433Y441167D01*
G01X866467Y440500D02*
Y443833D01*
G01Y443167D02*
X866800Y443500D01*
X867133Y443750D01*
X867600Y443833D01*
X867933Y443750D01*
X868333Y443500D01*
G01X871300Y440500D02*
Y445500D01*
G01Y443000D02*
X871633Y443500D01*
X872033Y443750D01*
X872433Y443833D01*
X873033Y443667D01*
X873433Y443333D01*
X873700Y442750D01*
Y442083D01*
X873567Y441417D01*
X873300Y440917D01*
X872833Y440583D01*
X872433Y440500D01*
X872033Y440583D01*
X871633Y440833D01*
X871300Y441250D01*
G01X876600Y442750D02*
X878733D01*
X878533Y443333D01*
X878200Y443667D01*
X877733Y443833D01*
X877267Y443750D01*
X876867Y443500D01*
X876600Y442917D01*
X876467Y442417D01*
Y441917D01*
X876600Y441417D01*
X876933Y440917D01*
X877333Y440583D01*
X877800Y440500D01*
X878267Y440667D01*
X878733Y441167D01*
G01X881767Y440500D02*
Y443833D01*
G01Y443167D02*
X882100Y443500D01*
X882433Y443750D01*
X882900Y443833D01*
X883233Y443750D01*
X883633Y443500D01*
G01X821100Y419500D02*
Y423750D01*
X821233Y424167D01*
X821500Y424417D01*
X821900Y424500D01*
X822300Y424333D01*
X822500Y423917D01*
G01X821700Y422500D02*
X820367D01*
G01X826600Y419500D02*
X826200Y419583D01*
X825800Y419917D01*
X825533Y420500D01*
X825400Y421167D01*
X825533Y421833D01*
X825800Y422417D01*
X826200Y422750D01*
X826600Y422833D01*
X827000Y422750D01*
X827400Y422417D01*
X827667Y421833D01*
X827733Y421167D01*
X827667Y420500D01*
X827400Y419917D01*
X827000Y419583D01*
X826600Y419500D01*
G01X831700D02*
Y424500D01*
G01X836800Y419500D02*
Y424500D01*
G01X841900Y419500D02*
X841500Y419583D01*
X841100Y419917D01*
X840833Y420500D01*
X840700Y421167D01*
X840833Y421833D01*
X841100Y422417D01*
X841500Y422750D01*
X841900Y422833D01*
X842300Y422750D01*
X842700Y422417D01*
X842967Y421833D01*
X843033Y421167D01*
X842967Y420500D01*
X842700Y419917D01*
X842300Y419583D01*
X841900Y419500D01*
G01X845333Y422833D02*
X846133Y419500D01*
X847000Y422833D01*
X847867Y419500D01*
X848667Y422833D01*
G01X857600Y422000D02*
X858933D01*
Y420500D01*
X858533Y420000D01*
X858067Y419667D01*
X857400Y419500D01*
X856733Y419667D01*
X856267Y420000D01*
X855867Y420500D01*
X855600Y421083D01*
X855467Y421750D01*
Y422333D01*
X855600Y422833D01*
X855867Y423417D01*
X856267Y423917D01*
X856667Y424250D01*
X857200Y424500D01*
X857667D01*
X858200Y424333D01*
X858600Y424000D01*
G01X861300Y421750D02*
X863433D01*
X863233Y422333D01*
X862900Y422667D01*
X862433Y422833D01*
X861967Y422750D01*
X861567Y422500D01*
X861300Y421917D01*
X861167Y421417D01*
Y420917D01*
X861300Y420417D01*
X861633Y419917D01*
X862033Y419583D01*
X862500Y419500D01*
X862967Y419667D01*
X863433Y420167D01*
G01X866467Y419500D02*
Y422833D01*
G01Y422167D02*
X866800Y422500D01*
X867133Y422750D01*
X867600Y422833D01*
X867933Y422750D01*
X868333Y422500D01*
G01X871300Y419500D02*
Y424500D01*
G01Y422000D02*
X871633Y422500D01*
X872033Y422750D01*
X872433Y422833D01*
X873033Y422667D01*
X873433Y422333D01*
X873700Y421750D01*
Y421083D01*
X873567Y420417D01*
X873300Y419917D01*
X872833Y419583D01*
X872433Y419500D01*
X872033Y419583D01*
X871633Y419833D01*
X871300Y420250D01*
G01X876600Y421750D02*
X878733D01*
X878533Y422333D01*
X878200Y422667D01*
X877733Y422833D01*
X877267Y422750D01*
X876867Y422500D01*
X876600Y421917D01*
X876467Y421417D01*
Y420917D01*
X876600Y420417D01*
X876933Y419917D01*
X877333Y419583D01*
X877800Y419500D01*
X878267Y419667D01*
X878733Y420167D01*
G01X881767Y419500D02*
Y422833D01*
G01Y422167D02*
X882100Y422500D01*
X882433Y422750D01*
X882900Y422833D01*
X883233Y422750D01*
X883633Y422500D01*
G01X894100Y419500D02*
Y422833D01*
G01Y422250D02*
X893833Y422583D01*
X893433Y422750D01*
X892967Y422833D01*
X892500Y422667D01*
X892100Y422333D01*
X891833Y421833D01*
X891700Y421167D01*
X891833Y420500D01*
X892100Y420000D01*
X892500Y419667D01*
X892967Y419500D01*
X893433Y419583D01*
X893833Y419833D01*
X894100Y420167D01*
G01X896867Y419500D02*
Y422833D01*
G01Y422000D02*
X897133Y422417D01*
X897533Y422750D01*
X898067Y422833D01*
X898533Y422750D01*
X898933Y422417D01*
X899133Y421833D01*
Y419500D01*
G01X904300Y424500D02*
Y419500D01*
G01Y420250D02*
X904033Y419833D01*
X903633Y419583D01*
X903167Y419500D01*
X902633Y419667D01*
X902233Y420083D01*
X901967Y420583D01*
X901900Y421167D01*
X901967Y421750D01*
X902233Y422250D01*
X902633Y422667D01*
X903167Y422833D01*
X903633Y422750D01*
X903967Y422583D01*
X904300Y422250D01*
G01X912100Y417833D02*
Y422833D01*
G01Y422083D02*
X912433Y422500D01*
X912767Y422750D01*
X913300Y422833D01*
X913767Y422750D01*
X914233Y422333D01*
X914433Y421750D01*
X914500Y421167D01*
X914433Y420583D01*
X914233Y420000D01*
X913833Y419667D01*
X913300Y419500D01*
X912833Y419583D01*
X912367Y419833D01*
X912100Y420167D01*
G01X918400Y419500D02*
Y424500D01*
G01X922367Y422833D02*
Y420500D01*
X922633Y419917D01*
X923033Y419583D01*
X923500Y419500D01*
X923967Y419583D01*
X924367Y419917D01*
X924633Y420500D01*
G01Y419500D02*
Y422833D01*
G01X927667Y418250D02*
X928133Y417917D01*
X928667Y417833D01*
X929133Y417917D01*
X929533Y418333D01*
X929800Y418917D01*
Y422833D01*
G01Y422167D02*
X929533Y422500D01*
X929133Y422750D01*
X928667Y422833D01*
X928133Y422667D01*
X927800Y422333D01*
X927533Y421750D01*
X927400Y421167D01*
X927467Y420667D01*
X927733Y420083D01*
X928133Y419667D01*
X928667Y419500D01*
X929067Y419583D01*
X929533Y419917D01*
X929800Y420250D01*
G01X937133Y422833D02*
X937933Y419500D01*
X938800Y422833D01*
X939667Y419500D01*
X940467Y422833D01*
G01X943900D02*
Y419500D01*
G01Y424167D02*
X943767Y424250D01*
Y424417D01*
X943900Y424500D01*
X944033Y424417D01*
Y424250D01*
X943900Y424167D01*
G01X949000Y424500D02*
Y419500D01*
G01X948067Y422833D02*
X949933D01*
G01X952967Y419500D02*
Y424500D01*
G01Y422083D02*
X953300Y422500D01*
X953633Y422750D01*
X954167Y422833D01*
X954567Y422750D01*
X955033Y422417D01*
X955233Y421917D01*
Y419500D01*
G01X963367D02*
Y422833D01*
G01Y422167D02*
X963700Y422500D01*
X964033Y422750D01*
X964500Y422833D01*
X964833Y422750D01*
X965233Y422500D01*
G01X968400Y421750D02*
X970533D01*
X970333Y422333D01*
X970000Y422667D01*
X969533Y422833D01*
X969067Y422750D01*
X968667Y422500D01*
X968400Y421917D01*
X968267Y421417D01*
Y420917D01*
X968400Y420417D01*
X968733Y419917D01*
X969133Y419583D01*
X969600Y419500D01*
X970067Y419667D01*
X970533Y420167D01*
G01X973500Y420083D02*
X973833Y419750D01*
X974300Y419500D01*
X974700D01*
X975100Y419667D01*
X975367Y419917D01*
X975500Y420250D01*
X975433Y420750D01*
X975167Y421000D01*
X973967Y421500D01*
X973700Y422083D01*
X973833Y422500D01*
X974100Y422750D01*
X974500Y422833D01*
X974900Y422750D01*
X975300Y422500D01*
G01X979600Y422833D02*
Y419500D01*
G01Y424167D02*
X979467Y424250D01*
Y424417D01*
X979600Y424500D01*
X979733Y424417D01*
Y424250D01*
X979600Y424167D01*
G01X983567Y419500D02*
Y422833D01*
G01Y422000D02*
X983833Y422417D01*
X984233Y422750D01*
X984767Y422833D01*
X985233Y422750D01*
X985633Y422417D01*
X985833Y421833D01*
Y419500D01*
G01X819833Y470833D02*
X820633Y467500D01*
X821500Y470833D01*
X822367Y467500D01*
X823167Y470833D01*
G01X826600D02*
Y467500D01*
G01Y472167D02*
X826467Y472250D01*
Y472417D01*
X826600Y472500D01*
X826733Y472417D01*
Y472250D01*
X826600Y472167D01*
G01X831700Y472500D02*
Y467500D01*
G01X830767Y470833D02*
X832633D01*
G01X835667Y467500D02*
Y472500D01*
G01Y470083D02*
X836000Y470500D01*
X836333Y470750D01*
X836867Y470833D01*
X837267Y470750D01*
X837733Y470417D01*
X837933Y469917D01*
Y467500D01*
G01X841900D02*
X841500Y467583D01*
X841100Y467917D01*
X840833Y468500D01*
X840700Y469167D01*
X840833Y469833D01*
X841100Y470417D01*
X841500Y470750D01*
X841900Y470833D01*
X842300Y470750D01*
X842700Y470417D01*
X842967Y469833D01*
X843033Y469167D01*
X842967Y468500D01*
X842700Y467917D01*
X842300Y467583D01*
X841900Y467500D01*
G01X845867Y470833D02*
Y468500D01*
X846133Y467917D01*
X846533Y467583D01*
X847000Y467500D01*
X847467Y467583D01*
X847867Y467917D01*
X848133Y468500D01*
G01Y467500D02*
Y470833D01*
G01X852100Y472500D02*
Y467500D01*
G01X851167Y470833D02*
X853033D01*
G01X861300Y468083D02*
X861633Y467750D01*
X862100Y467500D01*
X862500D01*
X862900Y467667D01*
X863167Y467917D01*
X863300Y468250D01*
X863233Y468750D01*
X862967Y469000D01*
X861767Y469500D01*
X861500Y470083D01*
X861633Y470500D01*
X861900Y470750D01*
X862300Y470833D01*
X862700Y470750D01*
X863100Y470500D01*
G01X867400Y467500D02*
X867000Y467583D01*
X866600Y467917D01*
X866333Y468500D01*
X866200Y469167D01*
X866333Y469833D01*
X866600Y470417D01*
X867000Y470750D01*
X867400Y470833D01*
X867800Y470750D01*
X868200Y470417D01*
X868467Y469833D01*
X868533Y469167D01*
X868467Y468500D01*
X868200Y467917D01*
X867800Y467583D01*
X867400Y467500D01*
G01X872500D02*
Y472500D01*
G01X878800D02*
Y467500D01*
G01Y468250D02*
X878533Y467833D01*
X878133Y467583D01*
X877667Y467500D01*
X877133Y467667D01*
X876733Y468083D01*
X876467Y468583D01*
X876400Y469167D01*
X876467Y469750D01*
X876733Y470250D01*
X877133Y470667D01*
X877667Y470833D01*
X878133Y470750D01*
X878467Y470583D01*
X878800Y470250D01*
G01X881700Y469750D02*
X883833D01*
X883633Y470333D01*
X883300Y470667D01*
X882833Y470833D01*
X882367Y470750D01*
X881967Y470500D01*
X881700Y469917D01*
X881567Y469417D01*
Y468917D01*
X881700Y468417D01*
X882033Y467917D01*
X882433Y467583D01*
X882900Y467500D01*
X883367Y467667D01*
X883833Y468167D01*
G01X886867Y467500D02*
Y470833D01*
G01Y470167D02*
X887200Y470500D01*
X887533Y470750D01*
X888000Y470833D01*
X888333Y470750D01*
X888733Y470500D01*
G01X896000Y467500D02*
Y470833D01*
G01Y469917D02*
X896200Y470333D01*
X896533Y470667D01*
X897000Y470833D01*
X897467Y470667D01*
X897800Y470333D01*
X898000Y469917D01*
Y467500D01*
G01Y469917D02*
X898200Y470333D01*
X898533Y470667D01*
X899000Y470833D01*
X899467Y470667D01*
X899800Y470333D01*
X900000Y469833D01*
Y467500D01*
G01X904300D02*
Y470833D01*
G01Y470250D02*
X904033Y470583D01*
X903633Y470750D01*
X903167Y470833D01*
X902700Y470667D01*
X902300Y470333D01*
X902033Y469833D01*
X901900Y469167D01*
X902033Y468500D01*
X902300Y468000D01*
X902700Y467667D01*
X903167Y467500D01*
X903633Y467583D01*
X904033Y467833D01*
X904300Y468167D01*
G01X907200Y468083D02*
X907533Y467750D01*
X908000Y467500D01*
X908400D01*
X908800Y467667D01*
X909067Y467917D01*
X909200Y468250D01*
X909133Y468750D01*
X908867Y469000D01*
X907667Y469500D01*
X907400Y470083D01*
X907533Y470500D01*
X907800Y470750D01*
X908200Y470833D01*
X908600Y470750D01*
X909000Y470500D01*
G01X912167Y467500D02*
Y472500D01*
G01X914300Y470833D02*
X912167Y468917D01*
G01X913033Y469667D02*
X914433Y467500D01*
G01X922300Y465833D02*
Y470833D01*
G01Y470083D02*
X922633Y470500D01*
X922967Y470750D01*
X923500Y470833D01*
X923967Y470750D01*
X924433Y470333D01*
X924633Y469750D01*
X924700Y469167D01*
X924633Y468583D01*
X924433Y468000D01*
X924033Y467667D01*
X923500Y467500D01*
X923033Y467583D01*
X922567Y467833D01*
X922300Y468167D01*
G01X929800Y467500D02*
Y470833D01*
G01Y470250D02*
X929533Y470583D01*
X929133Y470750D01*
X928667Y470833D01*
X928200Y470667D01*
X927800Y470333D01*
X927533Y469833D01*
X927400Y469167D01*
X927533Y468500D01*
X927800Y468000D01*
X928200Y467667D01*
X928667Y467500D01*
X929133Y467583D01*
X929533Y467833D01*
X929800Y468167D01*
G01X934900Y472500D02*
Y467500D01*
G01Y468250D02*
X934633Y467833D01*
X934233Y467583D01*
X933767Y467500D01*
X933233Y467667D01*
X932833Y468083D01*
X932567Y468583D01*
X932500Y469167D01*
X932567Y469750D01*
X932833Y470250D01*
X933233Y470667D01*
X933767Y470833D01*
X934233Y470750D01*
X934567Y470583D01*
X934900Y470250D01*
G01X943900Y467500D02*
X943500Y467583D01*
X943100Y467917D01*
X942833Y468500D01*
X942700Y469167D01*
X942833Y469833D01*
X943100Y470417D01*
X943500Y470750D01*
X943900Y470833D01*
X944300Y470750D01*
X944700Y470417D01*
X944967Y469833D01*
X945033Y469167D01*
X944967Y468500D01*
X944700Y467917D01*
X944300Y467583D01*
X943900Y467500D01*
G01X947867D02*
Y470833D01*
G01Y470000D02*
X948133Y470417D01*
X948533Y470750D01*
X949067Y470833D01*
X949533Y470750D01*
X949933Y470417D01*
X950133Y469833D01*
Y467500D01*
G01X959200Y472500D02*
Y467500D01*
G01X958267Y470833D02*
X960133D01*
G01X964300Y467500D02*
X963900Y467583D01*
X963500Y467917D01*
X963233Y468500D01*
X963100Y469167D01*
X963233Y469833D01*
X963500Y470417D01*
X963900Y470750D01*
X964300Y470833D01*
X964700Y470750D01*
X965100Y470417D01*
X965367Y469833D01*
X965433Y469167D01*
X965367Y468500D01*
X965100Y467917D01*
X964700Y467583D01*
X964300Y467500D01*
G01X968200Y465833D02*
Y470833D01*
G01Y470083D02*
X968533Y470500D01*
X968867Y470750D01*
X969400Y470833D01*
X969867Y470750D01*
X970333Y470333D01*
X970533Y469750D01*
X970600Y469167D01*
X970533Y468583D01*
X970333Y468000D01*
X969933Y467667D01*
X969400Y467500D01*
X968933Y467583D01*
X968467Y467833D01*
X968200Y468167D01*
G01X829500Y542583D02*
X829833Y542250D01*
X830300Y542000D01*
X830700D01*
X831100Y542167D01*
X831367Y542417D01*
X831500Y542750D01*
X831433Y543250D01*
X831167Y543500D01*
X829967Y544000D01*
X829700Y544583D01*
X829833Y545000D01*
X830100Y545250D01*
X830500Y545333D01*
X830900Y545250D01*
X831300Y545000D01*
G01X835600Y542000D02*
X835200Y542083D01*
X834800Y542417D01*
X834533Y543000D01*
X834400Y543667D01*
X834533Y544333D01*
X834800Y544917D01*
X835200Y545250D01*
X835600Y545333D01*
X836000Y545250D01*
X836400Y544917D01*
X836667Y544333D01*
X836733Y543667D01*
X836667Y543000D01*
X836400Y542417D01*
X836000Y542083D01*
X835600Y542000D01*
G01X840700D02*
Y547000D01*
G01X847000D02*
Y542000D01*
G01Y542750D02*
X846733Y542333D01*
X846333Y542083D01*
X845867Y542000D01*
X845333Y542167D01*
X844933Y542583D01*
X844667Y543083D01*
X844600Y543667D01*
X844667Y544250D01*
X844933Y544750D01*
X845333Y545167D01*
X845867Y545333D01*
X846333Y545250D01*
X846667Y545083D01*
X847000Y544750D01*
G01X849900Y544250D02*
X852033D01*
X851833Y544833D01*
X851500Y545167D01*
X851033Y545333D01*
X850567Y545250D01*
X850167Y545000D01*
X849900Y544417D01*
X849767Y543917D01*
Y543417D01*
X849900Y542917D01*
X850233Y542417D01*
X850633Y542083D01*
X851100Y542000D01*
X851567Y542167D01*
X852033Y542667D01*
G01X855067Y542000D02*
Y545333D01*
G01Y544667D02*
X855400Y545000D01*
X855733Y545250D01*
X856200Y545333D01*
X856533Y545250D01*
X856933Y545000D01*
G01X864200Y542000D02*
Y545333D01*
G01Y544417D02*
X864400Y544833D01*
X864733Y545167D01*
X865200Y545333D01*
X865667Y545167D01*
X866000Y544833D01*
X866200Y544417D01*
Y542000D01*
G01Y544417D02*
X866400Y544833D01*
X866733Y545167D01*
X867200Y545333D01*
X867667Y545167D01*
X868000Y544833D01*
X868200Y544333D01*
Y542000D01*
G01X872500D02*
Y545333D01*
G01Y544750D02*
X872233Y545083D01*
X871833Y545250D01*
X871367Y545333D01*
X870900Y545167D01*
X870500Y544833D01*
X870233Y544333D01*
X870100Y543667D01*
X870233Y543000D01*
X870500Y542500D01*
X870900Y542167D01*
X871367Y542000D01*
X871833Y542083D01*
X872233Y542333D01*
X872500Y542667D01*
G01X875400Y542583D02*
X875733Y542250D01*
X876200Y542000D01*
X876600D01*
X877000Y542167D01*
X877267Y542417D01*
X877400Y542750D01*
X877333Y543250D01*
X877067Y543500D01*
X875867Y544000D01*
X875600Y544583D01*
X875733Y545000D01*
X876000Y545250D01*
X876400Y545333D01*
X876800Y545250D01*
X877200Y545000D01*
G01X880367Y542000D02*
Y547000D01*
G01X882500Y545333D02*
X880367Y543417D01*
G01X881233Y544167D02*
X882633Y542000D01*
G01X890500Y540333D02*
Y545333D01*
G01Y544583D02*
X890833Y545000D01*
X891167Y545250D01*
X891700Y545333D01*
X892167Y545250D01*
X892633Y544833D01*
X892833Y544250D01*
X892900Y543667D01*
X892833Y543083D01*
X892633Y542500D01*
X892233Y542167D01*
X891700Y542000D01*
X891233Y542083D01*
X890767Y542333D01*
X890500Y542667D01*
G01X898000Y542000D02*
Y545333D01*
G01Y544750D02*
X897733Y545083D01*
X897333Y545250D01*
X896867Y545333D01*
X896400Y545167D01*
X896000Y544833D01*
X895733Y544333D01*
X895600Y543667D01*
X895733Y543000D01*
X896000Y542500D01*
X896400Y542167D01*
X896867Y542000D01*
X897333Y542083D01*
X897733Y542333D01*
X898000Y542667D01*
G01X903100Y547000D02*
Y542000D01*
G01Y542750D02*
X902833Y542333D01*
X902433Y542083D01*
X901967Y542000D01*
X901433Y542167D01*
X901033Y542583D01*
X900767Y543083D01*
X900700Y543667D01*
X900767Y544250D01*
X901033Y544750D01*
X901433Y545167D01*
X901967Y545333D01*
X902433Y545250D01*
X902767Y545083D01*
X903100Y544750D01*
G01X829833Y563333D02*
X830633Y560000D01*
X831500Y563333D01*
X832367Y560000D01*
X833167Y563333D01*
G01X835467Y560000D02*
Y565000D01*
G01Y562583D02*
X835800Y563000D01*
X836133Y563250D01*
X836667Y563333D01*
X837067Y563250D01*
X837533Y562917D01*
X837733Y562417D01*
Y560000D01*
G01X841700Y563333D02*
Y560000D01*
G01Y564667D02*
X841567Y564750D01*
Y564917D01*
X841700Y565000D01*
X841833Y564917D01*
Y564750D01*
X841700Y564667D01*
G01X847867Y562917D02*
X847400Y563250D01*
X847000Y563333D01*
X846467Y563167D01*
X846067Y562833D01*
X845800Y562250D01*
X845733Y561667D01*
X845800Y561083D01*
X846067Y560583D01*
X846467Y560167D01*
X847000Y560000D01*
X847467Y560167D01*
X847867Y560500D01*
G01X850767Y560000D02*
Y565000D01*
G01Y562583D02*
X851100Y563000D01*
X851433Y563250D01*
X851967Y563333D01*
X852367Y563250D01*
X852833Y562917D01*
X853033Y562417D01*
Y560000D01*
G01X861100Y560583D02*
X861433Y560250D01*
X861900Y560000D01*
X862300D01*
X862700Y560167D01*
X862967Y560417D01*
X863100Y560750D01*
X863033Y561250D01*
X862767Y561500D01*
X861567Y562000D01*
X861300Y562583D01*
X861433Y563000D01*
X861700Y563250D01*
X862100Y563333D01*
X862500Y563250D01*
X862900Y563000D01*
G01X867200Y563333D02*
Y560000D01*
G01Y564667D02*
X867067Y564750D01*
Y564917D01*
X867200Y565000D01*
X867333Y564917D01*
Y564750D01*
X867200Y564667D01*
G01X871300Y563333D02*
X873300D01*
X871300Y560000D01*
X873300D01*
G01X876400Y562250D02*
X878533D01*
X878333Y562833D01*
X878000Y563167D01*
X877533Y563333D01*
X877067Y563250D01*
X876667Y563000D01*
X876400Y562417D01*
X876267Y561917D01*
Y561417D01*
X876400Y560917D01*
X876733Y560417D01*
X877133Y560083D01*
X877600Y560000D01*
X878067Y560167D01*
X878533Y560667D01*
G01X887600Y563333D02*
Y560000D01*
G01Y564667D02*
X887467Y564750D01*
Y564917D01*
X887600Y565000D01*
X887733Y564917D01*
Y564750D01*
X887600Y564667D01*
G01X891700Y560583D02*
X892033Y560250D01*
X892500Y560000D01*
X892900D01*
X893300Y560167D01*
X893567Y560417D01*
X893700Y560750D01*
X893633Y561250D01*
X893367Y561500D01*
X892167Y562000D01*
X891900Y562583D01*
X892033Y563000D01*
X892300Y563250D01*
X892700Y563333D01*
X893100Y563250D01*
X893500Y563000D01*
G01X901700Y560000D02*
Y565000D01*
G01Y562500D02*
X902033Y563000D01*
X902433Y563250D01*
X902833Y563333D01*
X903433Y563167D01*
X903833Y562833D01*
X904100Y562250D01*
Y561583D01*
X903967Y560917D01*
X903700Y560417D01*
X903233Y560083D01*
X902833Y560000D01*
X902433Y560083D01*
X902033Y560333D01*
X901700Y560750D01*
G01X908000Y563333D02*
Y560000D01*
G01Y564667D02*
X907867Y564750D01*
Y564917D01*
X908000Y565000D01*
X908133Y564917D01*
Y564750D01*
X908000Y564667D01*
G01X912167Y558750D02*
X912633Y558417D01*
X913167Y558333D01*
X913633Y558417D01*
X914033Y558833D01*
X914300Y559417D01*
Y563333D01*
G01Y562667D02*
X914033Y563000D01*
X913633Y563250D01*
X913167Y563333D01*
X912633Y563167D01*
X912300Y562833D01*
X912033Y562250D01*
X911900Y561667D01*
X911967Y561167D01*
X912233Y560583D01*
X912633Y560167D01*
X913167Y560000D01*
X913567Y560083D01*
X914033Y560417D01*
X914300Y560750D01*
G01X917267Y558750D02*
X917733Y558417D01*
X918267Y558333D01*
X918733Y558417D01*
X919133Y558833D01*
X919400Y559417D01*
Y563333D01*
G01Y562667D02*
X919133Y563000D01*
X918733Y563250D01*
X918267Y563333D01*
X917733Y563167D01*
X917400Y562833D01*
X917133Y562250D01*
X917000Y561667D01*
X917067Y561167D01*
X917333Y560583D01*
X917733Y560167D01*
X918267Y560000D01*
X918667Y560083D01*
X919133Y560417D01*
X919400Y560750D01*
G01X922300Y562250D02*
X924433D01*
X924233Y562833D01*
X923900Y563167D01*
X923433Y563333D01*
X922967Y563250D01*
X922567Y563000D01*
X922300Y562417D01*
X922167Y561917D01*
Y561417D01*
X922300Y560917D01*
X922633Y560417D01*
X923033Y560083D01*
X923500Y560000D01*
X923967Y560167D01*
X924433Y560667D01*
G01X927467Y560000D02*
Y563333D01*
G01Y562667D02*
X927800Y563000D01*
X928133Y563250D01*
X928600Y563333D01*
X928933Y563250D01*
X929333Y563000D01*
G01X938600Y565000D02*
Y560000D01*
G01X937667Y563333D02*
X939533D01*
G01X942567Y560000D02*
Y565000D01*
G01Y562583D02*
X942900Y563000D01*
X943233Y563250D01*
X943767Y563333D01*
X944167Y563250D01*
X944633Y562917D01*
X944833Y562417D01*
Y560000D01*
G01X950000D02*
Y563333D01*
G01Y562750D02*
X949733Y563083D01*
X949333Y563250D01*
X948867Y563333D01*
X948400Y563167D01*
X948000Y562833D01*
X947733Y562333D01*
X947600Y561667D01*
X947733Y561000D01*
X948000Y560500D01*
X948400Y560167D01*
X948867Y560000D01*
X949333Y560083D01*
X949733Y560333D01*
X950000Y560667D01*
G01X952767Y560000D02*
Y563333D01*
G01Y562500D02*
X953033Y562917D01*
X953433Y563250D01*
X953967Y563333D01*
X954433Y563250D01*
X954833Y562917D01*
X955033Y562333D01*
Y560000D01*
G01X965300D02*
Y563333D01*
G01Y562750D02*
X965033Y563083D01*
X964633Y563250D01*
X964167Y563333D01*
X963700Y563167D01*
X963300Y562833D01*
X963033Y562333D01*
X962900Y561667D01*
X963033Y561000D01*
X963300Y560500D01*
X963700Y560167D01*
X964167Y560000D01*
X964633Y560083D01*
X965033Y560333D01*
X965300Y560667D01*
G01X968067Y560000D02*
Y563333D01*
G01Y562500D02*
X968333Y562917D01*
X968733Y563250D01*
X969267Y563333D01*
X969733Y563250D01*
X970133Y562917D01*
X970333Y562333D01*
Y560000D01*
G01X973167D02*
Y563333D01*
G01Y562500D02*
X973433Y562917D01*
X973833Y563250D01*
X974367Y563333D01*
X974833Y563250D01*
X975233Y562917D01*
X975433Y562333D01*
Y560000D01*
G01X978267Y563333D02*
Y561000D01*
X978533Y560417D01*
X978933Y560083D01*
X979400Y560000D01*
X979867Y560083D01*
X980267Y560417D01*
X980533Y561000D01*
G01Y560000D02*
Y563333D01*
G01X985700Y560000D02*
Y563333D01*
G01Y562750D02*
X985433Y563083D01*
X985033Y563250D01*
X984567Y563333D01*
X984100Y563167D01*
X983700Y562833D01*
X983433Y562333D01*
X983300Y561667D01*
X983433Y561000D01*
X983700Y560500D01*
X984100Y560167D01*
X984567Y560000D01*
X985033Y560083D01*
X985433Y560333D01*
X985700Y560667D01*
G01X989600Y560000D02*
Y565000D01*
G01X821500Y569000D02*
Y574000D01*
X820700Y573000D01*
G01Y569000D02*
X822300D01*
G01X826600Y568833D02*
X826467Y568917D01*
Y569083D01*
X826600Y569167D01*
X826733Y569083D01*
Y568917D01*
X826600Y568833D01*
G01X831700Y569000D02*
X831167Y569083D01*
X830700Y569417D01*
X830300Y569917D01*
X830033Y570500D01*
X829900Y571167D01*
Y571833D01*
X830033Y572500D01*
X830300Y573083D01*
X830700Y573583D01*
X831167Y573917D01*
X831700Y574000D01*
X832233Y573917D01*
X832700Y573583D01*
X833100Y573083D01*
X833367Y572500D01*
X833500Y571833D01*
Y571167D01*
X833367Y570500D01*
X833100Y569917D01*
X832700Y569417D01*
X832233Y569083D01*
X831700Y569000D01*
G01X835667D02*
Y572333D01*
G01Y571500D02*
X835933Y571917D01*
X836333Y572250D01*
X836867Y572333D01*
X837333Y572250D01*
X837733Y571917D01*
X837933Y571333D01*
Y569000D01*
G01X840900Y571250D02*
X843033D01*
X842833Y571833D01*
X842500Y572167D01*
X842033Y572333D01*
X841567Y572250D01*
X841167Y572000D01*
X840900Y571417D01*
X840767Y570917D01*
Y570417D01*
X840900Y569917D01*
X841233Y569417D01*
X841633Y569083D01*
X842100Y569000D01*
X842567Y569167D01*
X843033Y569667D01*
G01X851100Y569583D02*
X851433Y569250D01*
X851900Y569000D01*
X852300D01*
X852700Y569167D01*
X852967Y569417D01*
X853100Y569750D01*
X853033Y570250D01*
X852767Y570500D01*
X851567Y571000D01*
X851300Y571583D01*
X851433Y572000D01*
X851700Y572250D01*
X852100Y572333D01*
X852500Y572250D01*
X852900Y572000D01*
G01X857200Y572333D02*
Y569000D01*
G01Y573667D02*
X857067Y573750D01*
Y573917D01*
X857200Y574000D01*
X857333Y573917D01*
Y573750D01*
X857200Y573667D01*
G01X863500Y574000D02*
Y569000D01*
G01Y569750D02*
X863233Y569333D01*
X862833Y569083D01*
X862367Y569000D01*
X861833Y569167D01*
X861433Y569583D01*
X861167Y570083D01*
X861100Y570667D01*
X861167Y571250D01*
X861433Y571750D01*
X861833Y572167D01*
X862367Y572333D01*
X862833Y572250D01*
X863167Y572083D01*
X863500Y571750D01*
G01X866400Y571250D02*
X868533D01*
X868333Y571833D01*
X868000Y572167D01*
X867533Y572333D01*
X867067Y572250D01*
X866667Y572000D01*
X866400Y571417D01*
X866267Y570917D01*
Y570417D01*
X866400Y569917D01*
X866733Y569417D01*
X867133Y569083D01*
X867600Y569000D01*
X868067Y569167D01*
X868533Y569667D01*
G01X875933Y572333D02*
X876733Y569000D01*
X877600Y572333D01*
X878467Y569000D01*
X879267Y572333D01*
G01X882700D02*
Y569000D01*
G01Y573667D02*
X882567Y573750D01*
Y573917D01*
X882700Y574000D01*
X882833Y573917D01*
Y573750D01*
X882700Y573667D01*
G01X887800Y574000D02*
Y569000D01*
G01X886867Y572333D02*
X888733D01*
G01X891767Y569000D02*
Y574000D01*
G01Y571583D02*
X892100Y572000D01*
X892433Y572250D01*
X892967Y572333D01*
X893367Y572250D01*
X893833Y571917D01*
X894033Y571417D01*
Y569000D01*
G01X902100Y569583D02*
X902433Y569250D01*
X902900Y569000D01*
X903300D01*
X903700Y569167D01*
X903967Y569417D01*
X904100Y569750D01*
X904033Y570250D01*
X903767Y570500D01*
X902567Y571000D01*
X902300Y571583D01*
X902433Y572000D01*
X902700Y572250D01*
X903100Y572333D01*
X903500Y572250D01*
X903900Y572000D01*
G01X908200Y569000D02*
X907800Y569083D01*
X907400Y569417D01*
X907133Y570000D01*
X907000Y570667D01*
X907133Y571333D01*
X907400Y571917D01*
X907800Y572250D01*
X908200Y572333D01*
X908600Y572250D01*
X909000Y571917D01*
X909267Y571333D01*
X909333Y570667D01*
X909267Y570000D01*
X909000Y569417D01*
X908600Y569083D01*
X908200Y569000D01*
G01X913300D02*
Y574000D01*
G01X919600D02*
Y569000D01*
G01Y569750D02*
X919333Y569333D01*
X918933Y569083D01*
X918467Y569000D01*
X917933Y569167D01*
X917533Y569583D01*
X917267Y570083D01*
X917200Y570667D01*
X917267Y571250D01*
X917533Y571750D01*
X917933Y572167D01*
X918467Y572333D01*
X918933Y572250D01*
X919267Y572083D01*
X919600Y571750D01*
G01X922500Y571250D02*
X924633D01*
X924433Y571833D01*
X924100Y572167D01*
X923633Y572333D01*
X923167Y572250D01*
X922767Y572000D01*
X922500Y571417D01*
X922367Y570917D01*
Y570417D01*
X922500Y569917D01*
X922833Y569417D01*
X923233Y569083D01*
X923700Y569000D01*
X924167Y569167D01*
X924633Y569667D01*
G01X927667Y569000D02*
Y572333D01*
G01Y571667D02*
X928000Y572000D01*
X928333Y572250D01*
X928800Y572333D01*
X929133Y572250D01*
X929533Y572000D01*
G01X936800Y569000D02*
Y572333D01*
G01Y571417D02*
X937000Y571833D01*
X937333Y572167D01*
X937800Y572333D01*
X938267Y572167D01*
X938600Y571833D01*
X938800Y571417D01*
Y569000D01*
G01Y571417D02*
X939000Y571833D01*
X939333Y572167D01*
X939800Y572333D01*
X940267Y572167D01*
X940600Y571833D01*
X940800Y571333D01*
Y569000D01*
G01X945100D02*
Y572333D01*
G01Y571750D02*
X944833Y572083D01*
X944433Y572250D01*
X943967Y572333D01*
X943500Y572167D01*
X943100Y571833D01*
X942833Y571333D01*
X942700Y570667D01*
X942833Y570000D01*
X943100Y569500D01*
X943500Y569167D01*
X943967Y569000D01*
X944433Y569083D01*
X944833Y569333D01*
X945100Y569667D01*
G01X948000Y569583D02*
X948333Y569250D01*
X948800Y569000D01*
X949200D01*
X949600Y569167D01*
X949867Y569417D01*
X950000Y569750D01*
X949933Y570250D01*
X949667Y570500D01*
X948467Y571000D01*
X948200Y571583D01*
X948333Y572000D01*
X948600Y572250D01*
X949000Y572333D01*
X949400Y572250D01*
X949800Y572000D01*
G01X952967Y569000D02*
Y574000D01*
G01X955100Y572333D02*
X952967Y570417D01*
G01X953833Y571167D02*
X955233Y569000D01*
G01X963100Y567333D02*
Y572333D01*
G01Y571583D02*
X963433Y572000D01*
X963767Y572250D01*
X964300Y572333D01*
X964767Y572250D01*
X965233Y571833D01*
X965433Y571250D01*
X965500Y570667D01*
X965433Y570083D01*
X965233Y569500D01*
X964833Y569167D01*
X964300Y569000D01*
X963833Y569083D01*
X963367Y569333D01*
X963100Y569667D01*
G01X970600Y569000D02*
Y572333D01*
G01Y571750D02*
X970333Y572083D01*
X969933Y572250D01*
X969467Y572333D01*
X969000Y572167D01*
X968600Y571833D01*
X968333Y571333D01*
X968200Y570667D01*
X968333Y570000D01*
X968600Y569500D01*
X969000Y569167D01*
X969467Y569000D01*
X969933Y569083D01*
X970333Y569333D01*
X970600Y569667D01*
G01X975700Y574000D02*
Y569000D01*
G01Y569750D02*
X975433Y569333D01*
X975033Y569083D01*
X974567Y569000D01*
X974033Y569167D01*
X973633Y569583D01*
X973367Y570083D01*
X973300Y570667D01*
X973367Y571250D01*
X973633Y571750D01*
X974033Y572167D01*
X974567Y572333D01*
X975033Y572250D01*
X975367Y572083D01*
X975700Y571750D01*
G01X831067Y551000D02*
Y554333D01*
G01Y553667D02*
X831400Y554000D01*
X831733Y554250D01*
X832200Y554333D01*
X832533Y554250D01*
X832933Y554000D01*
G01X837100Y554333D02*
Y551000D01*
G01Y555667D02*
X836967Y555750D01*
Y555917D01*
X837100Y556000D01*
X837233Y555917D01*
Y555750D01*
X837100Y555667D01*
G01X841067Y551000D02*
Y554333D01*
G01Y553500D02*
X841333Y553917D01*
X841733Y554250D01*
X842267Y554333D01*
X842733Y554250D01*
X843133Y553917D01*
X843333Y553333D01*
Y551000D01*
G01X846367Y549750D02*
X846833Y549417D01*
X847367Y549333D01*
X847833Y549417D01*
X848233Y549833D01*
X848500Y550417D01*
Y554333D01*
G01Y553667D02*
X848233Y554000D01*
X847833Y554250D01*
X847367Y554333D01*
X846833Y554167D01*
X846500Y553833D01*
X846233Y553250D01*
X846100Y552667D01*
X846167Y552167D01*
X846433Y551583D01*
X846833Y551167D01*
X847367Y551000D01*
X847767Y551083D01*
X848233Y551417D01*
X848500Y551750D01*
G01X856500Y551583D02*
X856833Y551250D01*
X857300Y551000D01*
X857700D01*
X858100Y551167D01*
X858367Y551417D01*
X858500Y551750D01*
X858433Y552250D01*
X858167Y552500D01*
X856967Y553000D01*
X856700Y553583D01*
X856833Y554000D01*
X857100Y554250D01*
X857500Y554333D01*
X857900Y554250D01*
X858300Y554000D01*
G01X862600Y554333D02*
Y551000D01*
G01Y555667D02*
X862467Y555750D01*
Y555917D01*
X862600Y556000D01*
X862733Y555917D01*
Y555750D01*
X862600Y555667D01*
G01X866700Y554333D02*
X868700D01*
X866700Y551000D01*
X868700D01*
G01X871800Y553250D02*
X873933D01*
X873733Y553833D01*
X873400Y554167D01*
X872933Y554333D01*
X872467Y554250D01*
X872067Y554000D01*
X871800Y553417D01*
X871667Y552917D01*
Y552417D01*
X871800Y551917D01*
X872133Y551417D01*
X872533Y551083D01*
X873000Y551000D01*
X873467Y551167D01*
X873933Y551667D01*
G01X882867Y550083D02*
X883133Y551167D01*
G01X794000Y674500D02*
Y669500D01*
G01X793067Y672833D02*
X794933D01*
G01X797967Y669500D02*
Y674500D01*
G01Y672083D02*
X798300Y672500D01*
X798633Y672750D01*
X799167Y672833D01*
X799567Y672750D01*
X800033Y672417D01*
X800233Y671917D01*
Y669500D01*
G01X804200Y672833D02*
Y669500D01*
G01Y674167D02*
X804067Y674250D01*
Y674417D01*
X804200Y674500D01*
X804333Y674417D01*
Y674250D01*
X804200Y674167D01*
G01X810367Y672417D02*
X809900Y672750D01*
X809500Y672833D01*
X808967Y672667D01*
X808567Y672333D01*
X808300Y671750D01*
X808233Y671167D01*
X808300Y670583D01*
X808567Y670083D01*
X808967Y669667D01*
X809500Y669500D01*
X809967Y669667D01*
X810367Y670000D01*
G01X813267Y669500D02*
Y674500D01*
G01X815400Y672833D02*
X813267Y670917D01*
G01X814133Y671667D02*
X815533Y669500D01*
G01X818367D02*
Y672833D01*
G01Y672000D02*
X818633Y672417D01*
X819033Y672750D01*
X819567Y672833D01*
X820033Y672750D01*
X820433Y672417D01*
X820633Y671833D01*
Y669500D01*
G01X823600Y671750D02*
X825733D01*
X825533Y672333D01*
X825200Y672667D01*
X824733Y672833D01*
X824267Y672750D01*
X823867Y672500D01*
X823600Y671917D01*
X823467Y671417D01*
Y670917D01*
X823600Y670417D01*
X823933Y669917D01*
X824333Y669583D01*
X824800Y669500D01*
X825267Y669667D01*
X825733Y670167D01*
G01X828700Y670083D02*
X829033Y669750D01*
X829500Y669500D01*
X829900D01*
X830300Y669667D01*
X830567Y669917D01*
X830700Y670250D01*
X830633Y670750D01*
X830367Y671000D01*
X829167Y671500D01*
X828900Y672083D01*
X829033Y672500D01*
X829300Y672750D01*
X829700Y672833D01*
X830100Y672750D01*
X830500Y672500D01*
G01X833800Y670083D02*
X834133Y669750D01*
X834600Y669500D01*
X835000D01*
X835400Y669667D01*
X835667Y669917D01*
X835800Y670250D01*
X835733Y670750D01*
X835467Y671000D01*
X834267Y671500D01*
X834000Y672083D01*
X834133Y672500D01*
X834400Y672750D01*
X834800Y672833D01*
X835200Y672750D01*
X835600Y672500D01*
G01X808800Y686500D02*
Y691500D01*
G01Y689000D02*
X809133Y689500D01*
X809533Y689750D01*
X809933Y689833D01*
X810533Y689667D01*
X810933Y689333D01*
X811200Y688750D01*
Y688083D01*
X811067Y687417D01*
X810800Y686917D01*
X810333Y686583D01*
X809933Y686500D01*
X809533Y686583D01*
X809133Y686833D01*
X808800Y687250D01*
G01X815100Y686500D02*
X814700Y686583D01*
X814300Y686917D01*
X814033Y687500D01*
X813900Y688167D01*
X814033Y688833D01*
X814300Y689417D01*
X814700Y689750D01*
X815100Y689833D01*
X815500Y689750D01*
X815900Y689417D01*
X816167Y688833D01*
X816233Y688167D01*
X816167Y687500D01*
X815900Y686917D01*
X815500Y686583D01*
X815100Y686500D01*
G01X821400D02*
Y689833D01*
G01Y689250D02*
X821133Y689583D01*
X820733Y689750D01*
X820267Y689833D01*
X819800Y689667D01*
X819400Y689333D01*
X819133Y688833D01*
X819000Y688167D01*
X819133Y687500D01*
X819400Y687000D01*
X819800Y686667D01*
X820267Y686500D01*
X820733Y686583D01*
X821133Y686833D01*
X821400Y687167D01*
G01X824367Y686500D02*
Y689833D01*
G01Y689167D02*
X824700Y689500D01*
X825033Y689750D01*
X825500Y689833D01*
X825833Y689750D01*
X826233Y689500D01*
G01X831600Y691500D02*
Y686500D01*
G01Y687250D02*
X831333Y686833D01*
X830933Y686583D01*
X830467Y686500D01*
X829933Y686667D01*
X829533Y687083D01*
X829267Y687583D01*
X829200Y688167D01*
X829267Y688750D01*
X829533Y689250D01*
X829933Y689667D01*
X830467Y689833D01*
X830933Y689750D01*
X831267Y689583D01*
X831600Y689250D01*
G01X842867Y734500D02*
Y739500D01*
G01Y737083D02*
X843200Y737500D01*
X843533Y737750D01*
X844067Y737833D01*
X844467Y737750D01*
X844933Y737417D01*
X845133Y736917D01*
Y734500D01*
G01X850300D02*
Y737833D01*
G01Y737250D02*
X850033Y737583D01*
X849633Y737750D01*
X849167Y737833D01*
X848700Y737667D01*
X848300Y737333D01*
X848033Y736833D01*
X847900Y736167D01*
X848033Y735500D01*
X848300Y735000D01*
X848700Y734667D01*
X849167Y734500D01*
X849633Y734583D01*
X850033Y734833D01*
X850300Y735167D01*
G01X854200Y734500D02*
Y739500D01*
G01X858900Y734500D02*
Y738750D01*
X859033Y739167D01*
X859300Y739417D01*
X859700Y739500D01*
X860100Y739333D01*
X860300Y738917D01*
G01X859500Y737500D02*
X858167D01*
G01X868300Y732833D02*
Y737833D01*
G01Y737083D02*
X868633Y737500D01*
X868967Y737750D01*
X869500Y737833D01*
X869967Y737750D01*
X870433Y737333D01*
X870633Y736750D01*
X870700Y736167D01*
X870633Y735583D01*
X870433Y735000D01*
X870033Y734667D01*
X869500Y734500D01*
X869033Y734583D01*
X868567Y734833D01*
X868300Y735167D01*
G01X874600Y734500D02*
Y739500D01*
G01X878567Y737833D02*
Y735500D01*
X878833Y734917D01*
X879233Y734583D01*
X879700Y734500D01*
X880167Y734583D01*
X880567Y734917D01*
X880833Y735500D01*
G01Y734500D02*
Y737833D01*
G01X883867Y733250D02*
X884333Y732917D01*
X884867Y732833D01*
X885333Y732917D01*
X885733Y733333D01*
X886000Y733917D01*
Y737833D01*
G01Y737167D02*
X885733Y737500D01*
X885333Y737750D01*
X884867Y737833D01*
X884333Y737667D01*
X884000Y737333D01*
X883733Y736750D01*
X883600Y736167D01*
X883667Y735667D01*
X883933Y735083D01*
X884333Y734667D01*
X884867Y734500D01*
X885267Y734583D01*
X885733Y734917D01*
X886000Y735250D01*
G01X888967Y733250D02*
X889433Y732917D01*
X889967Y732833D01*
X890433Y732917D01*
X890833Y733333D01*
X891100Y733917D01*
Y737833D01*
G01Y737167D02*
X890833Y737500D01*
X890433Y737750D01*
X889967Y737833D01*
X889433Y737667D01*
X889100Y737333D01*
X888833Y736750D01*
X888700Y736167D01*
X888767Y735667D01*
X889033Y735083D01*
X889433Y734667D01*
X889967Y734500D01*
X890367Y734583D01*
X890833Y734917D01*
X891100Y735250D01*
G01X895000Y737833D02*
Y734500D01*
G01Y739167D02*
X894867Y739250D01*
Y739417D01*
X895000Y739500D01*
X895133Y739417D01*
Y739250D01*
X895000Y739167D01*
G01X898967Y734500D02*
Y737833D01*
G01Y737000D02*
X899233Y737417D01*
X899633Y737750D01*
X900167Y737833D01*
X900633Y737750D01*
X901033Y737417D01*
X901233Y736833D01*
Y734500D01*
G01X904267Y733250D02*
X904733Y732917D01*
X905267Y732833D01*
X905733Y732917D01*
X906133Y733333D01*
X906400Y733917D01*
Y737833D01*
G01Y737167D02*
X906133Y737500D01*
X905733Y737750D01*
X905267Y737833D01*
X904733Y737667D01*
X904400Y737333D01*
X904133Y736750D01*
X904000Y736167D01*
X904067Y735667D01*
X904333Y735083D01*
X904733Y734667D01*
X905267Y734500D01*
X905667Y734583D01*
X906133Y734917D01*
X906400Y735250D01*
G01X798000Y795500D02*
Y790500D01*
G01X796467Y795500D02*
X799533D01*
G01X801433Y793833D02*
X802233Y790500D01*
X803100Y793833D01*
X803967Y790500D01*
X804767Y793833D01*
G01X808200D02*
Y790500D01*
G01Y795167D02*
X808067Y795250D01*
Y795417D01*
X808200Y795500D01*
X808333Y795417D01*
Y795250D01*
X808200Y795167D01*
G01X812300Y791083D02*
X812633Y790750D01*
X813100Y790500D01*
X813500D01*
X813900Y790667D01*
X814167Y790917D01*
X814300Y791250D01*
X814233Y791750D01*
X813967Y792000D01*
X812767Y792500D01*
X812500Y793083D01*
X812633Y793500D01*
X812900Y793750D01*
X813300Y793833D01*
X813700Y793750D01*
X814100Y793500D01*
G01X818400Y795500D02*
Y790500D01*
G01X817467Y793833D02*
X819333D01*
G01X829800Y790500D02*
Y793833D01*
G01Y793250D02*
X829533Y793583D01*
X829133Y793750D01*
X828667Y793833D01*
X828200Y793667D01*
X827800Y793333D01*
X827533Y792833D01*
X827400Y792167D01*
X827533Y791500D01*
X827800Y791000D01*
X828200Y790667D01*
X828667Y790500D01*
X829133Y790583D01*
X829533Y790833D01*
X829800Y791167D01*
G01X832567Y790500D02*
Y793833D01*
G01Y793000D02*
X832833Y793417D01*
X833233Y793750D01*
X833767Y793833D01*
X834233Y793750D01*
X834633Y793417D01*
X834833Y792833D01*
Y790500D01*
G01X840000Y795500D02*
Y790500D01*
G01Y791250D02*
X839733Y790833D01*
X839333Y790583D01*
X838867Y790500D01*
X838333Y790667D01*
X837933Y791083D01*
X837667Y791583D01*
X837600Y792167D01*
X837667Y792750D01*
X837933Y793250D01*
X838333Y793667D01*
X838867Y793833D01*
X839333Y793750D01*
X839667Y793583D01*
X840000Y793250D01*
G01X847800Y790500D02*
Y795500D01*
G01Y793000D02*
X848133Y793500D01*
X848533Y793750D01*
X848933Y793833D01*
X849533Y793667D01*
X849933Y793333D01*
X850200Y792750D01*
Y792083D01*
X850067Y791417D01*
X849800Y790917D01*
X849333Y790583D01*
X848933Y790500D01*
X848533Y790583D01*
X848133Y790833D01*
X847800Y791250D01*
G01X854100Y790500D02*
X853700Y790583D01*
X853300Y790917D01*
X853033Y791500D01*
X852900Y792167D01*
X853033Y792833D01*
X853300Y793417D01*
X853700Y793750D01*
X854100Y793833D01*
X854500Y793750D01*
X854900Y793417D01*
X855167Y792833D01*
X855233Y792167D01*
X855167Y791500D01*
X854900Y790917D01*
X854500Y790583D01*
X854100Y790500D01*
G01X857533Y793833D02*
X858333Y790500D01*
X859200Y793833D01*
X860067Y790500D01*
X860867Y793833D01*
G01X796667Y826500D02*
Y831500D01*
X798333D01*
X798867Y831250D01*
X799200Y830917D01*
X799333Y830250D01*
X799200Y829583D01*
X798800Y829167D01*
X798333Y828917D01*
X796667D01*
G01X798333D02*
X799333Y826500D01*
G01X803100D02*
X802700Y826583D01*
X802300Y826917D01*
X802033Y827500D01*
X801900Y828167D01*
X802033Y828833D01*
X802300Y829417D01*
X802700Y829750D01*
X803100Y829833D01*
X803500Y829750D01*
X803900Y829417D01*
X804167Y828833D01*
X804233Y828167D01*
X804167Y827500D01*
X803900Y826917D01*
X803500Y826583D01*
X803100Y826500D01*
G01X807067Y829833D02*
Y827500D01*
X807333Y826917D01*
X807733Y826583D01*
X808200Y826500D01*
X808667Y826583D01*
X809067Y826917D01*
X809333Y827500D01*
G01Y826500D02*
Y829833D01*
G01X813300Y831500D02*
Y826500D01*
G01X812367Y829833D02*
X814233D01*
G01X818400D02*
Y826500D01*
G01Y831167D02*
X818267Y831250D01*
Y831417D01*
X818400Y831500D01*
X818533Y831417D01*
Y831250D01*
X818400Y831167D01*
G01X822367Y826500D02*
Y829833D01*
G01Y829000D02*
X822633Y829417D01*
X823033Y829750D01*
X823567Y829833D01*
X824033Y829750D01*
X824433Y829417D01*
X824633Y828833D01*
Y826500D01*
G01X827667Y825250D02*
X828133Y824917D01*
X828667Y824833D01*
X829133Y824917D01*
X829533Y825333D01*
X829800Y825917D01*
Y829833D01*
G01Y829167D02*
X829533Y829500D01*
X829133Y829750D01*
X828667Y829833D01*
X828133Y829667D01*
X827800Y829333D01*
X827533Y828750D01*
X827400Y828167D01*
X827467Y827667D01*
X827733Y827083D01*
X828133Y826667D01*
X828667Y826500D01*
X829067Y826583D01*
X829533Y826917D01*
X829800Y827250D01*
G01X838800Y831500D02*
Y826500D01*
G01X837867Y829833D02*
X839733D01*
G01X843900Y826500D02*
X843500Y826583D01*
X843100Y826917D01*
X842833Y827500D01*
X842700Y828167D01*
X842833Y828833D01*
X843100Y829417D01*
X843500Y829750D01*
X843900Y829833D01*
X844300Y829750D01*
X844700Y829417D01*
X844967Y828833D01*
X845033Y828167D01*
X844967Y827500D01*
X844700Y826917D01*
X844300Y826583D01*
X843900Y826500D01*
G01X849000D02*
Y831500D01*
G01X853100Y828750D02*
X855233D01*
X855033Y829333D01*
X854700Y829667D01*
X854233Y829833D01*
X853767Y829750D01*
X853367Y829500D01*
X853100Y828917D01*
X852967Y828417D01*
Y827917D01*
X853100Y827417D01*
X853433Y826917D01*
X853833Y826583D01*
X854300Y826500D01*
X854767Y826667D01*
X855233Y827167D01*
G01X858267Y826500D02*
Y829833D01*
G01Y829167D02*
X858600Y829500D01*
X858933Y829750D01*
X859400Y829833D01*
X859733Y829750D01*
X860133Y829500D01*
G01X865500Y826500D02*
Y829833D01*
G01Y829250D02*
X865233Y829583D01*
X864833Y829750D01*
X864367Y829833D01*
X863900Y829667D01*
X863500Y829333D01*
X863233Y828833D01*
X863100Y828167D01*
X863233Y827500D01*
X863500Y827000D01*
X863900Y826667D01*
X864367Y826500D01*
X864833Y826583D01*
X865233Y826833D01*
X865500Y827167D01*
G01X868267Y826500D02*
Y829833D01*
G01Y829000D02*
X868533Y829417D01*
X868933Y829750D01*
X869467Y829833D01*
X869933Y829750D01*
X870333Y829417D01*
X870533Y828833D01*
Y826500D01*
G01X875567Y829417D02*
X875100Y829750D01*
X874700Y829833D01*
X874167Y829667D01*
X873767Y829333D01*
X873500Y828750D01*
X873433Y828167D01*
X873500Y827583D01*
X873767Y827083D01*
X874167Y826667D01*
X874700Y826500D01*
X875167Y826667D01*
X875567Y827000D01*
G01X878600Y828750D02*
X880733D01*
X880533Y829333D01*
X880200Y829667D01*
X879733Y829833D01*
X879267Y829750D01*
X878867Y829500D01*
X878600Y828917D01*
X878467Y828417D01*
Y827917D01*
X878600Y827417D01*
X878933Y826917D01*
X879333Y826583D01*
X879800Y826500D01*
X880267Y826667D01*
X880733Y827167D01*
G01X788000Y850610D02*
Y782110D01*
G01Y805500D02*
X1343000D01*
G01X908300Y67500D02*
Y72500D01*
X905833Y68917D01*
X909167D01*
G01X911133Y68250D02*
X911533Y67833D01*
X912000Y67583D01*
X912600Y67500D01*
X913200Y67667D01*
X913667Y68000D01*
X914000Y68583D01*
X914067Y69250D01*
X913933Y69917D01*
X913600Y70333D01*
X913133Y70667D01*
X912667Y70750D01*
X912200Y70667D01*
X911600Y70333D01*
X911800Y72500D01*
X913600D01*
G01X868100Y152000D02*
Y157000D01*
G01X870900D02*
Y152000D01*
G01Y154500D02*
X868100D01*
G01X874600Y152000D02*
X874067Y152083D01*
X873600Y152417D01*
X873200Y152917D01*
X872933Y153500D01*
X872800Y154167D01*
Y154833D01*
X872933Y155500D01*
X873200Y156083D01*
X873600Y156583D01*
X874067Y156917D01*
X874600Y157000D01*
X875133Y156917D01*
X875600Y156583D01*
X876000Y156083D01*
X876267Y155500D01*
X876400Y154833D01*
Y154167D01*
X876267Y153500D01*
X876000Y152917D01*
X875600Y152417D01*
X875133Y152083D01*
X874600Y152000D01*
G01X878367Y157000D02*
Y152000D01*
X881033D01*
G01X886133D02*
X883467D01*
Y157000D01*
X886133D01*
G01X885067Y154583D02*
X883467D01*
G01X908300Y152000D02*
Y155333D01*
G01Y154417D02*
X908500Y154833D01*
X908833Y155167D01*
X909300Y155333D01*
X909767Y155167D01*
X910100Y154833D01*
X910300Y154417D01*
Y152000D01*
G01Y154417D02*
X910500Y154833D01*
X910833Y155167D01*
X911300Y155333D01*
X911767Y155167D01*
X912100Y154833D01*
X912300Y154333D01*
Y152000D01*
G01X915400Y155333D02*
Y152000D01*
G01Y156667D02*
X915267Y156750D01*
Y156917D01*
X915400Y157000D01*
X915533Y156917D01*
Y156750D01*
X915400Y156667D01*
G01X920500Y152000D02*
Y157000D01*
G01X924600Y152583D02*
X924933Y152250D01*
X925400Y152000D01*
X925800D01*
X926200Y152167D01*
X926467Y152417D01*
X926600Y152750D01*
X926533Y153250D01*
X926267Y153500D01*
X925067Y154000D01*
X924800Y154583D01*
X924933Y155000D01*
X925200Y155250D01*
X925600Y155333D01*
X926000Y155250D01*
X926400Y155000D01*
G01X930367Y150333D02*
X929700Y151167D01*
X929367Y152000D01*
Y155333D01*
X929700Y156167D01*
X930367Y157000D01*
G01X934467Y152000D02*
Y157000D01*
X936067D01*
X936600Y156750D01*
X937000Y156167D01*
X937133Y155500D01*
X937000Y154833D01*
X936667Y154333D01*
X936067Y154083D01*
X934467D01*
G01X940900Y157000D02*
Y152000D01*
G01X939367Y157000D02*
X942433D01*
G01X944600Y152000D02*
Y157000D01*
G01X947400D02*
Y152000D01*
G01Y154500D02*
X944600D01*
G01X951433Y150333D02*
X952100Y151167D01*
X952433Y152000D01*
Y155333D01*
X952100Y156167D01*
X951433Y157000D01*
G01X909000Y184083D02*
X909333Y183750D01*
X909800Y183500D01*
X910200D01*
X910600Y183667D01*
X910867Y183917D01*
X911000Y184250D01*
X910933Y184750D01*
X910667Y185000D01*
X909467Y185500D01*
X909200Y186083D01*
X909333Y186500D01*
X909600Y186750D01*
X910000Y186833D01*
X910400Y186750D01*
X910800Y186500D01*
G01X915100Y188500D02*
Y183500D01*
G01X914167Y186833D02*
X916033D01*
G01X919067D02*
Y184500D01*
X919333Y183917D01*
X919733Y183583D01*
X920200Y183500D01*
X920667Y183583D01*
X921067Y183917D01*
X921333Y184500D01*
G01Y183500D02*
Y186833D01*
G01X924100Y183500D02*
Y188500D01*
G01Y186000D02*
X924433Y186500D01*
X924833Y186750D01*
X925233Y186833D01*
X925833Y186667D01*
X926233Y186333D01*
X926500Y185750D01*
Y185083D01*
X926367Y184417D01*
X926100Y183917D01*
X925633Y183583D01*
X925233Y183500D01*
X924833Y183583D01*
X924433Y183833D01*
X924100Y184250D01*
G01X935500Y183500D02*
Y188500D01*
G01X939600Y185750D02*
X941733D01*
X941533Y186333D01*
X941200Y186667D01*
X940733Y186833D01*
X940267Y186750D01*
X939867Y186500D01*
X939600Y185917D01*
X939467Y185417D01*
Y184917D01*
X939600Y184417D01*
X939933Y183917D01*
X940333Y183583D01*
X940800Y183500D01*
X941267Y183667D01*
X941733Y184167D01*
G01X944567Y183500D02*
Y186833D01*
G01Y186000D02*
X944833Y186417D01*
X945233Y186750D01*
X945767Y186833D01*
X946233Y186750D01*
X946633Y186417D01*
X946833Y185833D01*
Y183500D01*
G01X949867Y182250D02*
X950333Y181917D01*
X950867Y181833D01*
X951333Y181917D01*
X951733Y182333D01*
X952000Y182917D01*
Y186833D01*
G01Y186167D02*
X951733Y186500D01*
X951333Y186750D01*
X950867Y186833D01*
X950333Y186667D01*
X950000Y186333D01*
X949733Y185750D01*
X949600Y185167D01*
X949667Y184667D01*
X949933Y184083D01*
X950333Y183667D01*
X950867Y183500D01*
X951267Y183583D01*
X951733Y183917D01*
X952000Y184250D01*
G01X955900Y188500D02*
Y183500D01*
G01X954967Y186833D02*
X956833D01*
G01X959867Y183500D02*
Y188500D01*
G01Y186083D02*
X960200Y186500D01*
X960533Y186750D01*
X961067Y186833D01*
X961467Y186750D01*
X961933Y186417D01*
X962133Y185917D01*
Y183500D01*
G01X965233Y184417D02*
X966967D01*
G01Y185917D02*
X965233D01*
G01X969933Y185583D02*
X970400Y186167D01*
X970800Y186500D01*
X971333Y186667D01*
X971800Y186500D01*
X972133Y186167D01*
X972400Y185667D01*
X972467Y185083D01*
X972400Y184583D01*
X972133Y184083D01*
X971733Y183667D01*
X971267Y183500D01*
X970733Y183667D01*
X970267Y184167D01*
X970000Y184917D01*
X969933Y185750D01*
X970067Y186833D01*
X970267Y187417D01*
X970600Y188000D01*
X971067Y188417D01*
X971533Y188500D01*
X972000Y188333D01*
X972333Y187917D01*
G01X975567Y185167D02*
X977167D01*
G01X976300Y186250D02*
Y184083D01*
G01X980200Y183333D02*
X982600Y188500D01*
G01X985633Y185167D02*
X987367D01*
G01X990133Y184250D02*
X990533Y183833D01*
X991000Y183583D01*
X991600Y183500D01*
X992200Y183667D01*
X992667Y184000D01*
X993000Y184583D01*
X993067Y185250D01*
X992933Y185917D01*
X992600Y186333D01*
X992133Y186667D01*
X991667Y186750D01*
X991200Y186667D01*
X990600Y186333D01*
X990800Y188500D01*
X992600D01*
G01X994700Y183500D02*
Y186833D01*
G01Y185917D02*
X994900Y186333D01*
X995233Y186667D01*
X995700Y186833D01*
X996167Y186667D01*
X996500Y186333D01*
X996700Y185917D01*
Y183500D01*
G01Y185917D02*
X996900Y186333D01*
X997233Y186667D01*
X997700Y186833D01*
X998167Y186667D01*
X998500Y186333D01*
X998700Y185833D01*
Y183500D01*
G01X1001800Y186833D02*
Y183500D01*
G01Y188167D02*
X1001667Y188250D01*
Y188417D01*
X1001800Y188500D01*
X1001933Y188417D01*
Y188250D01*
X1001800Y188167D01*
G01X1006900Y183500D02*
Y188500D01*
G01X900667Y214500D02*
Y209500D01*
X903333D01*
G01X905967D02*
Y212833D01*
G01Y212000D02*
X906233Y212417D01*
X906633Y212750D01*
X907167Y212833D01*
X907633Y212750D01*
X908033Y212417D01*
X908233Y211833D01*
Y209500D01*
G01X902667Y255500D02*
Y250500D01*
X905333D01*
G01X908100Y253833D02*
X910100Y250500D01*
G01Y253833D02*
X908100Y250500D01*
G01X867533Y308167D02*
X867800Y308417D01*
X868000Y308833D01*
X868133Y309417D01*
X868000Y309917D01*
X867733Y310250D01*
X867267Y310500D01*
X865467D01*
Y305500D01*
X867667D01*
X868133Y305833D01*
X868400Y306333D01*
X868533Y306917D01*
X868400Y307500D01*
X868000Y308000D01*
X867533Y308167D01*
X865467D01*
G01X870433Y305500D02*
X872100Y310500D01*
X873767Y305500D01*
G01X873167Y307250D02*
X871033D01*
G01X878667Y310083D02*
X878267Y310333D01*
X877800Y310500D01*
X877267D01*
X876667Y310250D01*
X876200Y309833D01*
X875867Y309333D01*
X875600Y308500D01*
X875533Y307750D01*
X875667Y307000D01*
X875867Y306500D01*
X876267Y306000D01*
X876733Y305667D01*
X877200Y305500D01*
X877667D01*
X878133Y305667D01*
X878533Y305917D01*
X878867Y306250D01*
G01X880833Y305500D02*
Y310500D01*
G01X883367D02*
X880833Y307417D01*
G01X883767Y305500D02*
X881967Y308833D01*
G01X891033Y305500D02*
Y310500D01*
X892367D01*
X892900Y310250D01*
X893300Y309917D01*
X893633Y309417D01*
X893900Y308833D01*
X893967Y308000D01*
X893900Y307167D01*
X893633Y306583D01*
X893300Y306083D01*
X892900Y305750D01*
X892367Y305500D01*
X891033D01*
G01X896267D02*
Y310500D01*
X897933D01*
X898467Y310250D01*
X898800Y309917D01*
X898933Y309250D01*
X898800Y308583D01*
X898400Y308167D01*
X897933Y307917D01*
X896267D01*
G01X897933D02*
X898933Y305500D01*
G01X901900Y310500D02*
X903500D01*
G01X902700D02*
Y305500D01*
G01X901900D02*
X903500D01*
G01X906467Y310500D02*
Y305500D01*
X909133D01*
G01X911567Y310500D02*
Y305500D01*
X914233D01*
G01X936400D02*
Y308833D01*
G01Y307917D02*
X936600Y308333D01*
X936933Y308667D01*
X937400Y308833D01*
X937867Y308667D01*
X938200Y308333D01*
X938400Y307917D01*
Y305500D01*
G01Y307917D02*
X938600Y308333D01*
X938933Y308667D01*
X939400Y308833D01*
X939867Y308667D01*
X940200Y308333D01*
X940400Y307833D01*
Y305500D01*
G01X943500Y308833D02*
Y305500D01*
G01Y310167D02*
X943367Y310250D01*
Y310417D01*
X943500Y310500D01*
X943633Y310417D01*
Y310250D01*
X943500Y310167D01*
G01X948600Y305500D02*
Y310500D01*
G01X952700Y306083D02*
X953033Y305750D01*
X953500Y305500D01*
X953900D01*
X954300Y305667D01*
X954567Y305917D01*
X954700Y306250D01*
X954633Y306750D01*
X954367Y307000D01*
X953167Y307500D01*
X952900Y308083D01*
X953033Y308500D01*
X953300Y308750D01*
X953700Y308833D01*
X954100Y308750D01*
X954500Y308500D01*
G01X958467Y303833D02*
X957800Y304667D01*
X957467Y305500D01*
Y308833D01*
X957800Y309667D01*
X958467Y310500D01*
G01X962367Y305500D02*
Y310500D01*
X965433Y305500D01*
Y310500D01*
G01X967667Y305500D02*
Y310500D01*
X969267D01*
X969800Y310250D01*
X970200Y309667D01*
X970333Y309000D01*
X970200Y308333D01*
X969867Y307833D01*
X969267Y307583D01*
X967667D01*
G01X974100Y310500D02*
Y305500D01*
G01X972567Y310500D02*
X975633D01*
G01X977800Y305500D02*
Y310500D01*
G01X980600D02*
Y305500D01*
G01Y308000D02*
X977800D01*
G01X984633Y303833D02*
X985300Y304667D01*
X985633Y305500D01*
Y308833D01*
X985300Y309667D01*
X984633Y310500D01*
G01X888633Y349073D02*
X891567Y352740D01*
G01X890100Y353407D02*
Y348407D01*
G01X891567Y349073D02*
X888633Y352740D01*
G01X888100Y350907D02*
X892100D01*
G01X894867Y347573D02*
X894200Y348407D01*
X893867Y349240D01*
Y352573D01*
X894200Y353407D01*
X894867Y354240D01*
G01X898833Y349990D02*
X899233Y349573D01*
X899700Y349323D01*
X900300Y349240D01*
X900900Y349407D01*
X901367Y349740D01*
X901700Y350323D01*
X901767Y350990D01*
X901633Y351657D01*
X901300Y352073D01*
X900833Y352407D01*
X900367Y352490D01*
X899900Y352407D01*
X899300Y352073D01*
X899500Y354240D01*
X901300D01*
G01X905400Y349073D02*
X905267Y349157D01*
Y349323D01*
X905400Y349407D01*
X905533Y349323D01*
Y349157D01*
X905400Y349073D01*
G01X910500Y349240D02*
Y354240D01*
X909700Y353240D01*
G01Y349240D02*
X911300D01*
G01X915933Y347573D02*
X916600Y348407D01*
X916933Y349240D01*
Y352573D01*
X916600Y353407D01*
X915933Y354240D01*
G01X893500Y556000D02*
Y551000D01*
G01X892567Y554333D02*
X894433D01*
G01X897467Y551000D02*
Y556000D01*
G01Y553583D02*
X897800Y554000D01*
X898133Y554250D01*
X898667Y554333D01*
X899067Y554250D01*
X899533Y553917D01*
X899733Y553417D01*
Y551000D01*
G01X902700Y553250D02*
X904833D01*
X904633Y553833D01*
X904300Y554167D01*
X903833Y554333D01*
X903367Y554250D01*
X902967Y554000D01*
X902700Y553417D01*
X902567Y552917D01*
Y552417D01*
X902700Y551917D01*
X903033Y551417D01*
X903433Y551083D01*
X903900Y551000D01*
X904367Y551167D01*
X904833Y551667D01*
G01X913900Y551000D02*
X913500Y551083D01*
X913100Y551417D01*
X912833Y552000D01*
X912700Y552667D01*
X912833Y553333D01*
X913100Y553917D01*
X913500Y554250D01*
X913900Y554333D01*
X914300Y554250D01*
X914700Y553917D01*
X914967Y553333D01*
X915033Y552667D01*
X914967Y552000D01*
X914700Y551417D01*
X914300Y551083D01*
X913900Y551000D01*
G01X919000Y556000D02*
Y551000D01*
G01X918067Y554333D02*
X919933D01*
G01X922967Y551000D02*
Y556000D01*
G01Y553583D02*
X923300Y554000D01*
X923633Y554250D01*
X924167Y554333D01*
X924567Y554250D01*
X925033Y553917D01*
X925233Y553417D01*
Y551000D01*
G01X928200Y553250D02*
X930333D01*
X930133Y553833D01*
X929800Y554167D01*
X929333Y554333D01*
X928867Y554250D01*
X928467Y554000D01*
X928200Y553417D01*
X928067Y552917D01*
Y552417D01*
X928200Y551917D01*
X928533Y551417D01*
X928933Y551083D01*
X929400Y551000D01*
X929867Y551167D01*
X930333Y551667D01*
G01X933367Y551000D02*
Y554333D01*
G01Y553667D02*
X933700Y554000D01*
X934033Y554250D01*
X934500Y554333D01*
X934833Y554250D01*
X935233Y554000D01*
G01X943500Y551583D02*
X943833Y551250D01*
X944300Y551000D01*
X944700D01*
X945100Y551167D01*
X945367Y551417D01*
X945500Y551750D01*
X945433Y552250D01*
X945167Y552500D01*
X943967Y553000D01*
X943700Y553583D01*
X943833Y554000D01*
X944100Y554250D01*
X944500Y554333D01*
X944900Y554250D01*
X945300Y554000D01*
G01X949600Y554333D02*
Y551000D01*
G01Y555667D02*
X949467Y555750D01*
Y555917D01*
X949600Y556000D01*
X949733Y555917D01*
Y555750D01*
X949600Y555667D01*
G01X955900Y556000D02*
Y551000D01*
G01Y551750D02*
X955633Y551333D01*
X955233Y551083D01*
X954767Y551000D01*
X954233Y551167D01*
X953833Y551583D01*
X953567Y552083D01*
X953500Y552667D01*
X953567Y553250D01*
X953833Y553750D01*
X954233Y554167D01*
X954767Y554333D01*
X955233Y554250D01*
X955567Y554083D01*
X955900Y553750D01*
G01X958800Y553250D02*
X960933D01*
X960733Y553833D01*
X960400Y554167D01*
X959933Y554333D01*
X959467Y554250D01*
X959067Y554000D01*
X958800Y553417D01*
X958667Y552917D01*
Y552417D01*
X958800Y551917D01*
X959133Y551417D01*
X959533Y551083D01*
X960000Y551000D01*
X960467Y551167D01*
X960933Y551667D01*
G01X968333Y554333D02*
X969133Y551000D01*
X970000Y554333D01*
X970867Y551000D01*
X971667Y554333D01*
G01X975100D02*
Y551000D01*
G01Y555667D02*
X974967Y555750D01*
Y555917D01*
X975100Y556000D01*
X975233Y555917D01*
Y555750D01*
X975100Y555667D01*
G01X980200Y556000D02*
Y551000D01*
G01X979267Y554333D02*
X981133D01*
G01X984167Y551000D02*
Y556000D01*
G01Y553583D02*
X984500Y554000D01*
X984833Y554250D01*
X985367Y554333D01*
X985767Y554250D01*
X986233Y553917D01*
X986433Y553417D01*
Y551000D01*
G01X990400D02*
X990000Y551083D01*
X989600Y551417D01*
X989333Y552000D01*
X989200Y552667D01*
X989333Y553333D01*
X989600Y553917D01*
X990000Y554250D01*
X990400Y554333D01*
X990800Y554250D01*
X991200Y553917D01*
X991467Y553333D01*
X991533Y552667D01*
X991467Y552000D01*
X991200Y551417D01*
X990800Y551083D01*
X990400Y551000D01*
G01X994367Y554333D02*
Y552000D01*
X994633Y551417D01*
X995033Y551083D01*
X995500Y551000D01*
X995967Y551083D01*
X996367Y551417D01*
X996633Y552000D01*
G01Y551000D02*
Y554333D01*
G01X1000600Y556000D02*
Y551000D01*
G01X999667Y554333D02*
X1001533D01*
G01X877400Y591500D02*
X878733D01*
Y590000D01*
X878333Y589500D01*
X877867Y589167D01*
X877200Y589000D01*
X876533Y589167D01*
X876067Y589500D01*
X875667Y590000D01*
X875400Y590583D01*
X875267Y591250D01*
Y591833D01*
X875400Y592333D01*
X875667Y592917D01*
X876067Y593417D01*
X876467Y593750D01*
X877000Y594000D01*
X877467D01*
X878000Y593833D01*
X878400Y593500D01*
G01X881100Y591250D02*
X883233D01*
X883033Y591833D01*
X882700Y592167D01*
X882233Y592333D01*
X881767Y592250D01*
X881367Y592000D01*
X881100Y591417D01*
X880967Y590917D01*
Y590417D01*
X881100Y589917D01*
X881433Y589417D01*
X881833Y589083D01*
X882300Y589000D01*
X882767Y589167D01*
X883233Y589667D01*
G01X886267Y589000D02*
Y592333D01*
G01Y591667D02*
X886600Y592000D01*
X886933Y592250D01*
X887400Y592333D01*
X887733Y592250D01*
X888133Y592000D01*
G01X891100Y589000D02*
Y594000D01*
G01Y591500D02*
X891433Y592000D01*
X891833Y592250D01*
X892233Y592333D01*
X892833Y592167D01*
X893233Y591833D01*
X893500Y591250D01*
Y590583D01*
X893367Y589917D01*
X893100Y589417D01*
X892633Y589083D01*
X892233Y589000D01*
X891833Y589083D01*
X891433Y589333D01*
X891100Y589750D01*
G01X896400Y591250D02*
X898533D01*
X898333Y591833D01*
X898000Y592167D01*
X897533Y592333D01*
X897067Y592250D01*
X896667Y592000D01*
X896400Y591417D01*
X896267Y590917D01*
Y590417D01*
X896400Y589917D01*
X896733Y589417D01*
X897133Y589083D01*
X897600Y589000D01*
X898067Y589167D01*
X898533Y589667D01*
G01X901567Y589000D02*
Y592333D01*
G01Y591667D02*
X901900Y592000D01*
X902233Y592250D01*
X902700Y592333D01*
X903033Y592250D01*
X903433Y592000D01*
G01X913900Y594000D02*
Y589000D01*
G01Y589750D02*
X913633Y589333D01*
X913233Y589083D01*
X912767Y589000D01*
X912233Y589167D01*
X911833Y589583D01*
X911567Y590083D01*
X911500Y590667D01*
X911567Y591250D01*
X911833Y591750D01*
X912233Y592167D01*
X912767Y592333D01*
X913233Y592250D01*
X913567Y592083D01*
X913900Y591750D01*
G01X916800Y591250D02*
X918933D01*
X918733Y591833D01*
X918400Y592167D01*
X917933Y592333D01*
X917467Y592250D01*
X917067Y592000D01*
X916800Y591417D01*
X916667Y590917D01*
Y590417D01*
X916800Y589917D01*
X917133Y589417D01*
X917533Y589083D01*
X918000Y589000D01*
X918467Y589167D01*
X918933Y589667D01*
G01X921900Y589583D02*
X922233Y589250D01*
X922700Y589000D01*
X923100D01*
X923500Y589167D01*
X923767Y589417D01*
X923900Y589750D01*
X923833Y590250D01*
X923567Y590500D01*
X922367Y591000D01*
X922100Y591583D01*
X922233Y592000D01*
X922500Y592250D01*
X922900Y592333D01*
X923300Y592250D01*
X923700Y592000D01*
G01X928000Y592333D02*
Y589000D01*
G01Y593667D02*
X927867Y593750D01*
Y593917D01*
X928000Y594000D01*
X928133Y593917D01*
Y593750D01*
X928000Y593667D01*
G01X932167Y587750D02*
X932633Y587417D01*
X933167Y587333D01*
X933633Y587417D01*
X934033Y587833D01*
X934300Y588417D01*
Y592333D01*
G01Y591667D02*
X934033Y592000D01*
X933633Y592250D01*
X933167Y592333D01*
X932633Y592167D01*
X932300Y591833D01*
X932033Y591250D01*
X931900Y590667D01*
X931967Y590167D01*
X932233Y589583D01*
X932633Y589167D01*
X933167Y589000D01*
X933567Y589083D01*
X934033Y589417D01*
X934300Y589750D01*
G01X937067Y589000D02*
Y592333D01*
G01Y591500D02*
X937333Y591917D01*
X937733Y592250D01*
X938267Y592333D01*
X938733Y592250D01*
X939133Y591917D01*
X939333Y591333D01*
Y589000D01*
G01X928367Y23083D02*
X928833Y22667D01*
X929367Y22500D01*
X929900Y22667D01*
X930367Y23167D01*
X930700Y23917D01*
X930833Y24667D01*
Y25583D01*
X930700Y26333D01*
X930367Y27000D01*
X929967Y27333D01*
X929500Y27500D01*
X928967Y27333D01*
X928567Y27000D01*
X928300Y26500D01*
X928167Y25833D01*
X928300Y25250D01*
X928633Y24667D01*
X929033Y24333D01*
X929500Y24250D01*
X930033Y24417D01*
X930433Y24833D01*
X930833Y25583D01*
G01X933333Y24583D02*
X933800Y25167D01*
X934200Y25500D01*
X934733Y25667D01*
X935200Y25500D01*
X935533Y25167D01*
X935800Y24667D01*
X935867Y24083D01*
X935800Y23583D01*
X935533Y23083D01*
X935133Y22667D01*
X934667Y22500D01*
X934133Y22667D01*
X933667Y23167D01*
X933400Y23917D01*
X933333Y24750D01*
X933467Y25833D01*
X933667Y26417D01*
X934000Y27000D01*
X934467Y27417D01*
X934933Y27500D01*
X935400Y27333D01*
X935733Y26917D01*
G01X928600Y734500D02*
Y738750D01*
X928733Y739167D01*
X929000Y739417D01*
X929400Y739500D01*
X929800Y739333D01*
X930000Y738917D01*
G01X929200Y737500D02*
X927867D01*
G01X932967Y737833D02*
Y735500D01*
X933233Y734917D01*
X933633Y734583D01*
X934100Y734500D01*
X934567Y734583D01*
X934967Y734917D01*
X935233Y735500D01*
G01Y734500D02*
Y737833D01*
G01X939200Y734500D02*
Y739500D01*
G01X944300Y734500D02*
Y739500D01*
G01X953300Y732833D02*
Y737833D01*
G01Y737083D02*
X953633Y737500D01*
X953967Y737750D01*
X954500Y737833D01*
X954967Y737750D01*
X955433Y737333D01*
X955633Y736750D01*
X955700Y736167D01*
X955633Y735583D01*
X955433Y735000D01*
X955033Y734667D01*
X954500Y734500D01*
X954033Y734583D01*
X953567Y734833D01*
X953300Y735167D01*
G01X959600Y734500D02*
Y739500D01*
G01X963567Y737833D02*
Y735500D01*
X963833Y734917D01*
X964233Y734583D01*
X964700Y734500D01*
X965167Y734583D01*
X965567Y734917D01*
X965833Y735500D01*
G01Y734500D02*
Y737833D01*
G01X968867Y733250D02*
X969333Y732917D01*
X969867Y732833D01*
X970333Y732917D01*
X970733Y733333D01*
X971000Y733917D01*
Y737833D01*
G01Y737167D02*
X970733Y737500D01*
X970333Y737750D01*
X969867Y737833D01*
X969333Y737667D01*
X969000Y737333D01*
X968733Y736750D01*
X968600Y736167D01*
X968667Y735667D01*
X968933Y735083D01*
X969333Y734667D01*
X969867Y734500D01*
X970267Y734583D01*
X970733Y734917D01*
X971000Y735250D01*
G01X973967Y733250D02*
X974433Y732917D01*
X974967Y732833D01*
X975433Y732917D01*
X975833Y733333D01*
X976100Y733917D01*
Y737833D01*
G01Y737167D02*
X975833Y737500D01*
X975433Y737750D01*
X974967Y737833D01*
X974433Y737667D01*
X974100Y737333D01*
X973833Y736750D01*
X973700Y736167D01*
X973767Y735667D01*
X974033Y735083D01*
X974433Y734667D01*
X974967Y734500D01*
X975367Y734583D01*
X975833Y734917D01*
X976100Y735250D01*
G01X980000Y737833D02*
Y734500D01*
G01Y739167D02*
X979867Y739250D01*
Y739417D01*
X980000Y739500D01*
X980133Y739417D01*
Y739250D01*
X980000Y739167D01*
G01X983967Y734500D02*
Y737833D01*
G01Y737000D02*
X984233Y737417D01*
X984633Y737750D01*
X985167Y737833D01*
X985633Y737750D01*
X986033Y737417D01*
X986233Y736833D01*
Y734500D01*
G01X989267Y733250D02*
X989733Y732917D01*
X990267Y732833D01*
X990733Y732917D01*
X991133Y733333D01*
X991400Y733917D01*
Y737833D01*
G01Y737167D02*
X991133Y737500D01*
X990733Y737750D01*
X990267Y737833D01*
X989733Y737667D01*
X989400Y737333D01*
X989133Y736750D01*
X989000Y736167D01*
X989067Y735667D01*
X989333Y735083D01*
X989733Y734667D01*
X990267Y734500D01*
X990667Y734583D01*
X991133Y734917D01*
X991400Y735250D01*
G01X955500Y795980D02*
Y790980D01*
G01X953967Y795980D02*
X957033D01*
G01X958933Y794313D02*
X959733Y790980D01*
X960600Y794313D01*
X961467Y790980D01*
X962267Y794313D01*
G01X965700D02*
Y790980D01*
G01Y795647D02*
X965567Y795730D01*
Y795897D01*
X965700Y795980D01*
X965833Y795897D01*
Y795730D01*
X965700Y795647D01*
G01X969800Y791563D02*
X970133Y791230D01*
X970600Y790980D01*
X971000D01*
X971400Y791147D01*
X971667Y791397D01*
X971800Y791730D01*
X971733Y792230D01*
X971467Y792480D01*
X970267Y792980D01*
X970000Y793563D01*
X970133Y793980D01*
X970400Y794230D01*
X970800Y794313D01*
X971200Y794230D01*
X971600Y793980D01*
G01X975900Y795980D02*
Y790980D01*
G01X974967Y794313D02*
X976833D01*
G01X987300Y790980D02*
Y794313D01*
G01Y793730D02*
X987033Y794063D01*
X986633Y794230D01*
X986167Y794313D01*
X985700Y794147D01*
X985300Y793813D01*
X985033Y793313D01*
X984900Y792647D01*
X985033Y791980D01*
X985300Y791480D01*
X985700Y791147D01*
X986167Y790980D01*
X986633Y791063D01*
X987033Y791313D01*
X987300Y791647D01*
G01X990067Y790980D02*
Y794313D01*
G01Y793480D02*
X990333Y793897D01*
X990733Y794230D01*
X991267Y794313D01*
X991733Y794230D01*
X992133Y793897D01*
X992333Y793313D01*
Y790980D01*
G01X997500Y795980D02*
Y790980D01*
G01Y791730D02*
X997233Y791313D01*
X996833Y791063D01*
X996367Y790980D01*
X995833Y791147D01*
X995433Y791563D01*
X995167Y792063D01*
X995100Y792647D01*
X995167Y793230D01*
X995433Y793730D01*
X995833Y794147D01*
X996367Y794313D01*
X996833Y794230D01*
X997167Y794063D01*
X997500Y793730D01*
G01X1005300Y790980D02*
Y795980D01*
G01Y793480D02*
X1005633Y793980D01*
X1006033Y794230D01*
X1006433Y794313D01*
X1007033Y794147D01*
X1007433Y793813D01*
X1007700Y793230D01*
Y792563D01*
X1007567Y791897D01*
X1007300Y791397D01*
X1006833Y791063D01*
X1006433Y790980D01*
X1006033Y791063D01*
X1005633Y791313D01*
X1005300Y791730D01*
G01X1011600Y790980D02*
X1011200Y791063D01*
X1010800Y791397D01*
X1010533Y791980D01*
X1010400Y792647D01*
X1010533Y793313D01*
X1010800Y793897D01*
X1011200Y794230D01*
X1011600Y794313D01*
X1012000Y794230D01*
X1012400Y793897D01*
X1012667Y793313D01*
X1012733Y792647D01*
X1012667Y791980D01*
X1012400Y791397D01*
X1012000Y791063D01*
X1011600Y790980D01*
G01X1015033Y794313D02*
X1015833Y790980D01*
X1016700Y794313D01*
X1017567Y790980D01*
X1018367Y794313D01*
G01X956900Y811500D02*
X958233D01*
Y810000D01*
X957833Y809500D01*
X957367Y809167D01*
X956700Y809000D01*
X956033Y809167D01*
X955567Y809500D01*
X955167Y810000D01*
X954900Y810583D01*
X954767Y811250D01*
Y811833D01*
X954900Y812333D01*
X955167Y812917D01*
X955567Y813417D01*
X955967Y813750D01*
X956500Y814000D01*
X956967D01*
X957500Y813833D01*
X957900Y813500D01*
G01X960400Y808833D02*
X962800Y814000D01*
G01X965433Y809000D02*
Y814000D01*
X967967D01*
G01X967033Y811583D02*
X965433D01*
G01X975500Y809667D02*
X976033Y809250D01*
X976633Y809000D01*
X977167D01*
X977700Y809250D01*
X978100Y809667D01*
X978300Y810250D01*
X978167Y810833D01*
X977833Y811333D01*
X977233Y811667D01*
X976433Y811833D01*
X975967Y812167D01*
X975767Y812750D01*
X975900Y813333D01*
X976233Y813750D01*
X976700Y814000D01*
X977167D01*
X977633Y813833D01*
X978033Y813417D01*
G01X982000Y809000D02*
Y814000D01*
G01X987100Y809000D02*
X986700Y809083D01*
X986300Y809417D01*
X986033Y810000D01*
X985900Y810667D01*
X986033Y811333D01*
X986300Y811917D01*
X986700Y812250D01*
X987100Y812333D01*
X987500Y812250D01*
X987900Y811917D01*
X988167Y811333D01*
X988233Y810667D01*
X988167Y810000D01*
X987900Y809417D01*
X987500Y809083D01*
X987100Y809000D01*
G01X992200Y814000D02*
Y809000D01*
G01X991267Y812333D02*
X993133D01*
G01X955500Y826250D02*
X957633D01*
X957433Y826833D01*
X957100Y827167D01*
X956633Y827333D01*
X956167Y827250D01*
X955767Y827000D01*
X955500Y826417D01*
X955367Y825917D01*
Y825417D01*
X955500Y824917D01*
X955833Y824417D01*
X956233Y824083D01*
X956700Y824000D01*
X957167Y824167D01*
X957633Y824667D01*
G01X962800Y829000D02*
Y824000D01*
G01Y824750D02*
X962533Y824333D01*
X962133Y824083D01*
X961667Y824000D01*
X961133Y824167D01*
X960733Y824583D01*
X960467Y825083D01*
X960400Y825667D01*
X960467Y826250D01*
X960733Y826750D01*
X961133Y827167D01*
X961667Y827333D01*
X962133Y827250D01*
X962467Y827083D01*
X962800Y826750D01*
G01X965767Y822750D02*
X966233Y822417D01*
X966767Y822333D01*
X967233Y822417D01*
X967633Y822833D01*
X967900Y823417D01*
Y827333D01*
G01Y826667D02*
X967633Y827000D01*
X967233Y827250D01*
X966767Y827333D01*
X966233Y827167D01*
X965900Y826833D01*
X965633Y826250D01*
X965500Y825667D01*
X965567Y825167D01*
X965833Y824583D01*
X966233Y824167D01*
X966767Y824000D01*
X967167Y824083D01*
X967633Y824417D01*
X967900Y824750D01*
G01X970800Y826250D02*
X972933D01*
X972733Y826833D01*
X972400Y827167D01*
X971933Y827333D01*
X971467Y827250D01*
X971067Y827000D01*
X970800Y826417D01*
X970667Y825917D01*
Y825417D01*
X970800Y824917D01*
X971133Y824417D01*
X971533Y824083D01*
X972000Y824000D01*
X972467Y824167D01*
X972933Y824667D01*
G01X982000Y829000D02*
Y824000D01*
G01X981067Y827333D02*
X982933D01*
G01X987100Y824000D02*
X986700Y824083D01*
X986300Y824417D01*
X986033Y825000D01*
X985900Y825667D01*
X986033Y826333D01*
X986300Y826917D01*
X986700Y827250D01*
X987100Y827333D01*
X987500Y827250D01*
X987900Y826917D01*
X988167Y826333D01*
X988233Y825667D01*
X988167Y825000D01*
X987900Y824417D01*
X987500Y824083D01*
X987100Y824000D01*
G01X996167D02*
Y829000D01*
G01Y826583D02*
X996500Y827000D01*
X996833Y827250D01*
X997367Y827333D01*
X997767Y827250D01*
X998233Y826917D01*
X998433Y826417D01*
Y824000D01*
G01X1002400D02*
X1002000Y824083D01*
X1001600Y824417D01*
X1001333Y825000D01*
X1001200Y825667D01*
X1001333Y826333D01*
X1001600Y826917D01*
X1002000Y827250D01*
X1002400Y827333D01*
X1002800Y827250D01*
X1003200Y826917D01*
X1003467Y826333D01*
X1003533Y825667D01*
X1003467Y825000D01*
X1003200Y824417D01*
X1002800Y824083D01*
X1002400Y824000D01*
G01X1007500D02*
Y829000D01*
G01X1011600Y826250D02*
X1013733D01*
X1013533Y826833D01*
X1013200Y827167D01*
X1012733Y827333D01*
X1012267Y827250D01*
X1011867Y827000D01*
X1011600Y826417D01*
X1011467Y825917D01*
Y825417D01*
X1011600Y824917D01*
X1011933Y824417D01*
X1012333Y824083D01*
X1012800Y824000D01*
X1013267Y824167D01*
X1013733Y824667D01*
G01X948000Y850610D02*
Y782110D01*
G01X948500Y819500D02*
X1343000D01*
G01X948500Y834500D02*
X1343000D01*
G01X955500Y842750D02*
X957633D01*
X957433Y843333D01*
X957100Y843667D01*
X956633Y843833D01*
X956167Y843750D01*
X955767Y843500D01*
X955500Y842917D01*
X955367Y842417D01*
Y841917D01*
X955500Y841417D01*
X955833Y840917D01*
X956233Y840583D01*
X956700Y840500D01*
X957167Y840667D01*
X957633Y841167D01*
G01X962800Y845500D02*
Y840500D01*
G01Y841250D02*
X962533Y840833D01*
X962133Y840583D01*
X961667Y840500D01*
X961133Y840667D01*
X960733Y841083D01*
X960467Y841583D01*
X960400Y842167D01*
X960467Y842750D01*
X960733Y843250D01*
X961133Y843667D01*
X961667Y843833D01*
X962133Y843750D01*
X962467Y843583D01*
X962800Y843250D01*
G01X965767Y839250D02*
X966233Y838917D01*
X966767Y838833D01*
X967233Y838917D01*
X967633Y839333D01*
X967900Y839917D01*
Y843833D01*
G01Y843167D02*
X967633Y843500D01*
X967233Y843750D01*
X966767Y843833D01*
X966233Y843667D01*
X965900Y843333D01*
X965633Y842750D01*
X965500Y842167D01*
X965567Y841667D01*
X965833Y841083D01*
X966233Y840667D01*
X966767Y840500D01*
X967167Y840583D01*
X967633Y840917D01*
X967900Y841250D01*
G01X970800Y842750D02*
X972933D01*
X972733Y843333D01*
X972400Y843667D01*
X971933Y843833D01*
X971467Y843750D01*
X971067Y843500D01*
X970800Y842917D01*
X970667Y842417D01*
Y841917D01*
X970800Y841417D01*
X971133Y840917D01*
X971533Y840583D01*
X972000Y840500D01*
X972467Y840667D01*
X972933Y841167D01*
G01X982000Y845500D02*
Y840500D01*
G01X981067Y843833D02*
X982933D01*
G01X987100Y840500D02*
X986700Y840583D01*
X986300Y840917D01*
X986033Y841500D01*
X985900Y842167D01*
X986033Y842833D01*
X986300Y843417D01*
X986700Y843750D01*
X987100Y843833D01*
X987500Y843750D01*
X987900Y843417D01*
X988167Y842833D01*
X988233Y842167D01*
X988167Y841500D01*
X987900Y840917D01*
X987500Y840583D01*
X987100Y840500D01*
G01X996300Y842750D02*
X998433D01*
X998233Y843333D01*
X997900Y843667D01*
X997433Y843833D01*
X996967Y843750D01*
X996567Y843500D01*
X996300Y842917D01*
X996167Y842417D01*
Y841917D01*
X996300Y841417D01*
X996633Y840917D01*
X997033Y840583D01*
X997500Y840500D01*
X997967Y840667D01*
X998433Y841167D01*
G01X1003600Y845500D02*
Y840500D01*
G01Y841250D02*
X1003333Y840833D01*
X1002933Y840583D01*
X1002467Y840500D01*
X1001933Y840667D01*
X1001533Y841083D01*
X1001267Y841583D01*
X1001200Y842167D01*
X1001267Y842750D01*
X1001533Y843250D01*
X1001933Y843667D01*
X1002467Y843833D01*
X1002933Y843750D01*
X1003267Y843583D01*
X1003600Y843250D01*
G01X1006567Y839250D02*
X1007033Y838917D01*
X1007567Y838833D01*
X1008033Y838917D01*
X1008433Y839333D01*
X1008700Y839917D01*
Y843833D01*
G01Y843167D02*
X1008433Y843500D01*
X1008033Y843750D01*
X1007567Y843833D01*
X1007033Y843667D01*
X1006700Y843333D01*
X1006433Y842750D01*
X1006300Y842167D01*
X1006367Y841667D01*
X1006633Y841083D01*
X1007033Y840667D01*
X1007567Y840500D01*
X1007967Y840583D01*
X1008433Y840917D01*
X1008700Y841250D01*
G01X1011600Y842750D02*
X1013733D01*
X1013533Y843333D01*
X1013200Y843667D01*
X1012733Y843833D01*
X1012267Y843750D01*
X1011867Y843500D01*
X1011600Y842917D01*
X1011467Y842417D01*
Y841917D01*
X1011600Y841417D01*
X1011933Y840917D01*
X1012333Y840583D01*
X1012800Y840500D01*
X1013267Y840667D01*
X1013733Y841167D01*
G01X995533Y5500D02*
Y10500D01*
X996867D01*
X997400Y10250D01*
X997800Y9917D01*
X998133Y9417D01*
X998400Y8833D01*
X998467Y8000D01*
X998400Y7167D01*
X998133Y6583D01*
X997800Y6083D01*
X997400Y5750D01*
X996867Y5500D01*
X995533D01*
G01X1002100D02*
Y10500D01*
X1001300Y9500D01*
G01Y5500D02*
X1002900D01*
G01X1005933Y7583D02*
X1006400Y8167D01*
X1006800Y8500D01*
X1007333Y8667D01*
X1007800Y8500D01*
X1008133Y8167D01*
X1008400Y7667D01*
X1008467Y7083D01*
X1008400Y6583D01*
X1008133Y6083D01*
X1007733Y5667D01*
X1007267Y5500D01*
X1006733Y5667D01*
X1006267Y6167D01*
X1006000Y6917D01*
X1005933Y7750D01*
X1006067Y8833D01*
X1006267Y9417D01*
X1006600Y10000D01*
X1007067Y10417D01*
X1007533Y10500D01*
X1008000Y10333D01*
X1008333Y9917D01*
G01X1012300Y5333D02*
X1012167Y5417D01*
Y5583D01*
X1012300Y5667D01*
X1012433Y5583D01*
Y5417D01*
X1012300Y5333D01*
G01Y7583D02*
X1012167Y7667D01*
Y7833D01*
X1012300Y7917D01*
X1012433Y7833D01*
Y7667D01*
X1012300Y7583D01*
G01X1015933Y5500D02*
Y10500D01*
X1017267D01*
X1017800Y10250D01*
X1018200Y9917D01*
X1018533Y9417D01*
X1018800Y8833D01*
X1018867Y8000D01*
X1018800Y7167D01*
X1018533Y6583D01*
X1018200Y6083D01*
X1017800Y5750D01*
X1017267Y5500D01*
X1015933D01*
G01X1022500Y8833D02*
Y5500D01*
G01Y10167D02*
X1022367Y10250D01*
Y10417D01*
X1022500Y10500D01*
X1022633Y10417D01*
Y10250D01*
X1022500Y10167D01*
G01X1028800Y5500D02*
Y8833D01*
G01Y8250D02*
X1028533Y8583D01*
X1028133Y8750D01*
X1027667Y8833D01*
X1027200Y8667D01*
X1026800Y8333D01*
X1026533Y7833D01*
X1026400Y7167D01*
X1026533Y6500D01*
X1026800Y6000D01*
X1027200Y5667D01*
X1027667Y5500D01*
X1028133Y5583D01*
X1028533Y5833D01*
X1028800Y6167D01*
G01X1030700Y5500D02*
Y8833D01*
G01Y7917D02*
X1030900Y8333D01*
X1031233Y8667D01*
X1031700Y8833D01*
X1032167Y8667D01*
X1032500Y8333D01*
X1032700Y7917D01*
Y5500D01*
G01Y7917D02*
X1032900Y8333D01*
X1033233Y8667D01*
X1033700Y8833D01*
X1034167Y8667D01*
X1034500Y8333D01*
X1034700Y7833D01*
Y5500D01*
G01X1036800Y7750D02*
X1038933D01*
X1038733Y8333D01*
X1038400Y8667D01*
X1037933Y8833D01*
X1037467Y8750D01*
X1037067Y8500D01*
X1036800Y7917D01*
X1036667Y7417D01*
Y6917D01*
X1036800Y6417D01*
X1037133Y5917D01*
X1037533Y5583D01*
X1038000Y5500D01*
X1038467Y5667D01*
X1038933Y6167D01*
G01X1042900Y10500D02*
Y5500D01*
G01X1041967Y8833D02*
X1043833D01*
G01X1047000Y7750D02*
X1049133D01*
X1048933Y8333D01*
X1048600Y8667D01*
X1048133Y8833D01*
X1047667Y8750D01*
X1047267Y8500D01*
X1047000Y7917D01*
X1046867Y7417D01*
Y6917D01*
X1047000Y6417D01*
X1047333Y5917D01*
X1047733Y5583D01*
X1048200Y5500D01*
X1048667Y5667D01*
X1049133Y6167D01*
G01X1052167Y5500D02*
Y8833D01*
G01Y8167D02*
X1052500Y8500D01*
X1052833Y8750D01*
X1053300Y8833D01*
X1053633Y8750D01*
X1054033Y8500D01*
G01X1063300Y5500D02*
Y10500D01*
X1062500Y9500D01*
G01Y5500D02*
X1064100D01*
G01X1067133Y7583D02*
X1067600Y8167D01*
X1068000Y8500D01*
X1068533Y8667D01*
X1069000Y8500D01*
X1069333Y8167D01*
X1069600Y7667D01*
X1069667Y7083D01*
X1069600Y6583D01*
X1069333Y6083D01*
X1068933Y5667D01*
X1068467Y5500D01*
X1067933Y5667D01*
X1067467Y6167D01*
X1067200Y6917D01*
X1067133Y7750D01*
X1067267Y8833D01*
X1067467Y9417D01*
X1067800Y10000D01*
X1068267Y10417D01*
X1068733Y10500D01*
X1069200Y10333D01*
X1069533Y9917D01*
G01X1071500Y5500D02*
Y8833D01*
G01Y7917D02*
X1071700Y8333D01*
X1072033Y8667D01*
X1072500Y8833D01*
X1072967Y8667D01*
X1073300Y8333D01*
X1073500Y7917D01*
Y5500D01*
G01Y7917D02*
X1073700Y8333D01*
X1074033Y8667D01*
X1074500Y8833D01*
X1074967Y8667D01*
X1075300Y8333D01*
X1075500Y7833D01*
Y5500D01*
G01X1078600Y8833D02*
Y5500D01*
G01Y10167D02*
X1078467Y10250D01*
Y10417D01*
X1078600Y10500D01*
X1078733Y10417D01*
Y10250D01*
X1078600Y10167D01*
G01X1083700Y5500D02*
Y10500D01*
G01X979833Y16500D02*
X977167D01*
Y21500D01*
X979833D01*
G01X978767Y19083D02*
X977167D01*
G01X982600Y19833D02*
X984600Y16500D01*
G01Y19833D02*
X982600Y16500D01*
G01X988700Y16333D02*
X988567Y16417D01*
Y16583D01*
X988700Y16667D01*
X988833Y16583D01*
Y16417D01*
X988700Y16333D01*
G01X992400Y16500D02*
Y21500D01*
G01X995200D02*
Y16500D01*
G01Y19000D02*
X992400D01*
G01X997567Y16500D02*
Y21500D01*
X999233D01*
X999767Y21250D01*
X1000100Y20917D01*
X1000233Y20250D01*
X1000100Y19583D01*
X999700Y19167D01*
X999233Y18917D01*
X997567D01*
G01X999233D02*
X1000233Y16500D01*
G01X1005333D02*
X1002667D01*
Y21500D01*
X1005333D01*
G01X1004267Y19083D02*
X1002667D01*
G01X1009900Y16500D02*
Y21500D01*
X1007433Y17917D01*
X1010767D01*
G01X1012733Y17250D02*
X1013133Y16833D01*
X1013600Y16583D01*
X1014200Y16500D01*
X1014800Y16667D01*
X1015267Y17000D01*
X1015600Y17583D01*
X1015667Y18250D01*
X1015533Y18917D01*
X1015200Y19333D01*
X1014733Y19667D01*
X1014267Y19750D01*
X1013800Y19667D01*
X1013200Y19333D01*
X1013400Y21500D01*
X1015200D01*
G01X1017900Y16500D02*
X1020700Y21500D01*
G01X1017900D02*
X1020700Y16500D01*
G01X1023267Y17083D02*
X1023733Y16667D01*
X1024267Y16500D01*
X1024800Y16667D01*
X1025267Y17167D01*
X1025600Y17917D01*
X1025733Y18667D01*
Y19583D01*
X1025600Y20333D01*
X1025267Y21000D01*
X1024867Y21333D01*
X1024400Y21500D01*
X1023867Y21333D01*
X1023467Y21000D01*
X1023200Y20500D01*
X1023067Y19833D01*
X1023200Y19250D01*
X1023533Y18667D01*
X1023933Y18333D01*
X1024400Y18250D01*
X1024933Y18417D01*
X1025333Y18833D01*
X1025733Y19583D01*
G01X1028233Y18583D02*
X1028700Y19167D01*
X1029100Y19500D01*
X1029633Y19667D01*
X1030100Y19500D01*
X1030433Y19167D01*
X1030700Y18667D01*
X1030767Y18083D01*
X1030700Y17583D01*
X1030433Y17083D01*
X1030033Y16667D01*
X1029567Y16500D01*
X1029033Y16667D01*
X1028567Y17167D01*
X1028300Y17917D01*
X1028233Y18750D01*
X1028367Y19833D01*
X1028567Y20417D01*
X1028900Y21000D01*
X1029367Y21417D01*
X1029833Y21500D01*
X1030300Y21333D01*
X1030633Y20917D01*
G01X1034267Y14833D02*
X1033600Y15667D01*
X1033267Y16500D01*
Y19833D01*
X1033600Y20667D01*
X1034267Y21500D01*
G01X1038233Y16500D02*
Y21500D01*
X1039567D01*
X1040100Y21250D01*
X1040500Y20917D01*
X1040833Y20417D01*
X1041100Y19833D01*
X1041167Y19000D01*
X1041100Y18167D01*
X1040833Y17583D01*
X1040500Y17083D01*
X1040100Y16750D01*
X1039567Y16500D01*
X1038233D01*
G01X1044800D02*
Y21500D01*
X1044000Y20500D01*
G01Y16500D02*
X1045600D01*
G01X1048633Y18583D02*
X1049100Y19167D01*
X1049500Y19500D01*
X1050033Y19667D01*
X1050500Y19500D01*
X1050833Y19167D01*
X1051100Y18667D01*
X1051167Y18083D01*
X1051100Y17583D01*
X1050833Y17083D01*
X1050433Y16667D01*
X1049967Y16500D01*
X1049433Y16667D01*
X1048967Y17167D01*
X1048700Y17917D01*
X1048633Y18750D01*
X1048767Y19833D01*
X1048967Y20417D01*
X1049300Y21000D01*
X1049767Y21417D01*
X1050233Y21500D01*
X1050700Y21333D01*
X1051033Y20917D01*
G01X1053600Y16500D02*
X1056400Y21500D01*
G01X1053600D02*
X1056400Y16500D01*
G01X1060900D02*
Y21500D01*
X1058433Y17917D01*
X1061767D01*
G01X1065533Y14833D02*
X1066200Y15667D01*
X1066533Y16500D01*
Y19833D01*
X1066200Y20667D01*
X1065533Y21500D01*
G01X977167Y65500D02*
Y70500D01*
X978833D01*
X979367Y70250D01*
X979700Y69917D01*
X979833Y69250D01*
X979700Y68583D01*
X979300Y68167D01*
X978833Y67917D01*
X977167D01*
G01X978833D02*
X979833Y65500D01*
G01X984933D02*
X982267D01*
Y70500D01*
X984933D01*
G01X983867Y68083D02*
X982267D01*
G01X990167Y70083D02*
X989767Y70333D01*
X989300Y70500D01*
X988767D01*
X988167Y70250D01*
X987700Y69833D01*
X987367Y69333D01*
X987100Y68500D01*
X987033Y67750D01*
X987167Y67000D01*
X987367Y66500D01*
X987767Y66000D01*
X988233Y65667D01*
X988700Y65500D01*
X989167D01*
X989633Y65667D01*
X990033Y65917D01*
X990367Y66250D01*
G01X993800Y70500D02*
Y65500D01*
G01X992267Y70500D02*
X995333D01*
G01X997233Y65500D02*
X998900Y70500D01*
X1000567Y65500D01*
G01X999967Y67250D02*
X997833D01*
G01X1002467Y65500D02*
Y70500D01*
X1005533Y65500D01*
Y70500D01*
G01X1009500Y68000D02*
X1010833D01*
Y66500D01*
X1010433Y66000D01*
X1009967Y65667D01*
X1009300Y65500D01*
X1008633Y65667D01*
X1008167Y66000D01*
X1007767Y66500D01*
X1007500Y67083D01*
X1007367Y67750D01*
Y68333D01*
X1007500Y68833D01*
X1007767Y69417D01*
X1008167Y69917D01*
X1008567Y70250D01*
X1009100Y70500D01*
X1009567D01*
X1010100Y70333D01*
X1010500Y70000D01*
G01X1012867Y70500D02*
Y65500D01*
X1015533D01*
G01X1020633D02*
X1017967D01*
Y70500D01*
X1020633D01*
G01X1019567Y68083D02*
X1017967D01*
G01X1028033Y65500D02*
Y70500D01*
X1029367D01*
X1029900Y70250D01*
X1030300Y69917D01*
X1030633Y69417D01*
X1030900Y68833D01*
X1030967Y68000D01*
X1030900Y67167D01*
X1030633Y66583D01*
X1030300Y66083D01*
X1029900Y65750D01*
X1029367Y65500D01*
X1028033D01*
G01X1033267D02*
Y70500D01*
X1034933D01*
X1035467Y70250D01*
X1035800Y69917D01*
X1035933Y69250D01*
X1035800Y68583D01*
X1035400Y68167D01*
X1034933Y67917D01*
X1033267D01*
G01X1034933D02*
X1035933Y65500D01*
G01X1038900Y70500D02*
X1040500D01*
G01X1039700D02*
Y65500D01*
G01X1038900D02*
X1040500D01*
G01X1043467Y70500D02*
Y65500D01*
X1046133D01*
G01X1048567Y70500D02*
Y65500D01*
X1051233D01*
G01X1058700D02*
Y70500D01*
G01X1061500D02*
Y65500D01*
G01Y68000D02*
X1058700D01*
G01X1065200Y65500D02*
X1064667Y65583D01*
X1064200Y65917D01*
X1063800Y66417D01*
X1063533Y67000D01*
X1063400Y67667D01*
Y68333D01*
X1063533Y69000D01*
X1063800Y69583D01*
X1064200Y70083D01*
X1064667Y70417D01*
X1065200Y70500D01*
X1065733Y70417D01*
X1066200Y70083D01*
X1066600Y69583D01*
X1066867Y69000D01*
X1067000Y68333D01*
Y67667D01*
X1066867Y67000D01*
X1066600Y66417D01*
X1066200Y65917D01*
X1065733Y65583D01*
X1065200Y65500D01*
G01X1068967Y70500D02*
Y65500D01*
X1071633D01*
G01X1076733D02*
X1074067D01*
Y70500D01*
X1076733D01*
G01X1075667Y68083D02*
X1074067D01*
G01X1084133Y65500D02*
Y70500D01*
X1085467D01*
X1086000Y70250D01*
X1086400Y69917D01*
X1086733Y69417D01*
X1087000Y68833D01*
X1087067Y68000D01*
X1087000Y67167D01*
X1086733Y66583D01*
X1086400Y66083D01*
X1086000Y65750D01*
X1085467Y65500D01*
X1084133D01*
G01X1092033D02*
X1089367D01*
Y70500D01*
X1092033D01*
G01X1090967Y68083D02*
X1089367D01*
G01X1094533Y65500D02*
Y70500D01*
X1097067D01*
G01X1096133Y68083D02*
X1094533D01*
G01X1100100Y70500D02*
X1101700D01*
G01X1100900D02*
Y65500D01*
G01X1100100D02*
X1101700D01*
G01X1104467D02*
Y70500D01*
X1107533Y65500D01*
Y70500D01*
G01X1112433Y65500D02*
X1109767D01*
Y70500D01*
X1112433D01*
G01X1111367Y68083D02*
X1109767D01*
G01X1026000Y336000D02*
Y86000D01*
G01X1033300Y370500D02*
Y375500D01*
G01Y373000D02*
X1033633Y373500D01*
X1034033Y373750D01*
X1034433Y373833D01*
X1035033Y373667D01*
X1035433Y373333D01*
X1035700Y372750D01*
Y372083D01*
X1035567Y371417D01*
X1035300Y370917D01*
X1034833Y370583D01*
X1034433Y370500D01*
X1034033Y370583D01*
X1033633Y370833D01*
X1033300Y371250D01*
G01X1038467Y373833D02*
Y371500D01*
X1038733Y370917D01*
X1039133Y370583D01*
X1039600Y370500D01*
X1040067Y370583D01*
X1040467Y370917D01*
X1040733Y371500D01*
G01Y370500D02*
Y373833D01*
G01X1043500Y370500D02*
Y375500D01*
G01Y373000D02*
X1043833Y373500D01*
X1044233Y373750D01*
X1044633Y373833D01*
X1045233Y373667D01*
X1045633Y373333D01*
X1045900Y372750D01*
Y372083D01*
X1045767Y371417D01*
X1045500Y370917D01*
X1045033Y370583D01*
X1044633Y370500D01*
X1044233Y370583D01*
X1043833Y370833D01*
X1043500Y371250D01*
G01X1048600Y370500D02*
Y375500D01*
G01Y373000D02*
X1048933Y373500D01*
X1049333Y373750D01*
X1049733Y373833D01*
X1050333Y373667D01*
X1050733Y373333D01*
X1051000Y372750D01*
Y372083D01*
X1050867Y371417D01*
X1050600Y370917D01*
X1050133Y370583D01*
X1049733Y370500D01*
X1049333Y370583D01*
X1048933Y370833D01*
X1048600Y371250D01*
G01X1054900Y370500D02*
Y375500D01*
G01X1059000Y372750D02*
X1061133D01*
X1060933Y373333D01*
X1060600Y373667D01*
X1060133Y373833D01*
X1059667Y373750D01*
X1059267Y373500D01*
X1059000Y372917D01*
X1058867Y372417D01*
Y371917D01*
X1059000Y371417D01*
X1059333Y370917D01*
X1059733Y370583D01*
X1060200Y370500D01*
X1060667Y370667D01*
X1061133Y371167D01*
G01X1070200Y373833D02*
Y370500D01*
G01Y375167D02*
X1070067Y375250D01*
Y375417D01*
X1070200Y375500D01*
X1070333Y375417D01*
Y375250D01*
X1070200Y375167D01*
G01X1074167Y370500D02*
Y373833D01*
G01Y373000D02*
X1074433Y373417D01*
X1074833Y373750D01*
X1075367Y373833D01*
X1075833Y373750D01*
X1076233Y373417D01*
X1076433Y372833D01*
Y370500D01*
G01X1079400Y371083D02*
X1079733Y370750D01*
X1080200Y370500D01*
X1080600D01*
X1081000Y370667D01*
X1081267Y370917D01*
X1081400Y371250D01*
X1081333Y371750D01*
X1081067Y372000D01*
X1079867Y372500D01*
X1079600Y373083D01*
X1079733Y373500D01*
X1080000Y373750D01*
X1080400Y373833D01*
X1080800Y373750D01*
X1081200Y373500D01*
G01X1085500Y373833D02*
Y370500D01*
G01Y375167D02*
X1085367Y375250D01*
Y375417D01*
X1085500Y375500D01*
X1085633Y375417D01*
Y375250D01*
X1085500Y375167D01*
G01X1091800Y375500D02*
Y370500D01*
G01Y371250D02*
X1091533Y370833D01*
X1091133Y370583D01*
X1090667Y370500D01*
X1090133Y370667D01*
X1089733Y371083D01*
X1089467Y371583D01*
X1089400Y372167D01*
X1089467Y372750D01*
X1089733Y373250D01*
X1090133Y373667D01*
X1090667Y373833D01*
X1091133Y373750D01*
X1091467Y373583D01*
X1091800Y373250D01*
G01X1094700Y372750D02*
X1096833D01*
X1096633Y373333D01*
X1096300Y373667D01*
X1095833Y373833D01*
X1095367Y373750D01*
X1094967Y373500D01*
X1094700Y372917D01*
X1094567Y372417D01*
Y371917D01*
X1094700Y371417D01*
X1095033Y370917D01*
X1095433Y370583D01*
X1095900Y370500D01*
X1096367Y370667D01*
X1096833Y371167D01*
G01X1105900Y375500D02*
Y370500D01*
G01X1104967Y373833D02*
X1106833D01*
G01X1109867Y370500D02*
Y375500D01*
G01Y373083D02*
X1110200Y373500D01*
X1110533Y373750D01*
X1111067Y373833D01*
X1111467Y373750D01*
X1111933Y373417D01*
X1112133Y372917D01*
Y370500D01*
G01X1115100Y372750D02*
X1117233D01*
X1117033Y373333D01*
X1116700Y373667D01*
X1116233Y373833D01*
X1115767Y373750D01*
X1115367Y373500D01*
X1115100Y372917D01*
X1114967Y372417D01*
Y371917D01*
X1115100Y371417D01*
X1115433Y370917D01*
X1115833Y370583D01*
X1116300Y370500D01*
X1116767Y370667D01*
X1117233Y371167D01*
G01X1125367Y370500D02*
Y373833D01*
G01Y373167D02*
X1125700Y373500D01*
X1126033Y373750D01*
X1126500Y373833D01*
X1126833Y373750D01*
X1127233Y373500D01*
G01X1130400Y372750D02*
X1132533D01*
X1132333Y373333D01*
X1132000Y373667D01*
X1131533Y373833D01*
X1131067Y373750D01*
X1130667Y373500D01*
X1130400Y372917D01*
X1130267Y372417D01*
Y371917D01*
X1130400Y371417D01*
X1130733Y370917D01*
X1131133Y370583D01*
X1131600Y370500D01*
X1132067Y370667D01*
X1132533Y371167D01*
G01X1135500Y371083D02*
X1135833Y370750D01*
X1136300Y370500D01*
X1136700D01*
X1137100Y370667D01*
X1137367Y370917D01*
X1137500Y371250D01*
X1137433Y371750D01*
X1137167Y372000D01*
X1135967Y372500D01*
X1135700Y373083D01*
X1135833Y373500D01*
X1136100Y373750D01*
X1136500Y373833D01*
X1136900Y373750D01*
X1137300Y373500D01*
G01X1141600Y373833D02*
Y370500D01*
G01Y375167D02*
X1141467Y375250D01*
Y375417D01*
X1141600Y375500D01*
X1141733Y375417D01*
Y375250D01*
X1141600Y375167D01*
G01X1145567Y370500D02*
Y373833D01*
G01Y373000D02*
X1145833Y373417D01*
X1146233Y373750D01*
X1146767Y373833D01*
X1147233Y373750D01*
X1147633Y373417D01*
X1147833Y372833D01*
Y370500D01*
G01X1151800Y370333D02*
X1151667Y370417D01*
Y370583D01*
X1151800Y370667D01*
X1151933Y370583D01*
Y370417D01*
X1151800Y370333D01*
G01X1021233Y383667D02*
X1021633Y384167D01*
X1022100Y384417D01*
X1022633Y384500D01*
X1023300Y384333D01*
X1023767Y383917D01*
X1023900Y383417D01*
X1023833Y382917D01*
X1023567Y382500D01*
X1022233Y381667D01*
X1021633Y381083D01*
X1021233Y380250D01*
X1021100Y379500D01*
X1023900D01*
G01X1027600Y379333D02*
X1027467Y379417D01*
Y379583D01*
X1027600Y379667D01*
X1027733Y379583D01*
Y379417D01*
X1027600Y379333D01*
G01X1031033Y384500D02*
X1032700Y379500D01*
X1034367Y384500D01*
G01X1037800Y382833D02*
Y379500D01*
G01Y384167D02*
X1037667Y384250D01*
Y384417D01*
X1037800Y384500D01*
X1037933Y384417D01*
Y384250D01*
X1037800Y384167D01*
G01X1044100Y379500D02*
Y382833D01*
G01Y382250D02*
X1043833Y382583D01*
X1043433Y382750D01*
X1042967Y382833D01*
X1042500Y382667D01*
X1042100Y382333D01*
X1041833Y381833D01*
X1041700Y381167D01*
X1041833Y380500D01*
X1042100Y380000D01*
X1042500Y379667D01*
X1042967Y379500D01*
X1043433Y379583D01*
X1043833Y379833D01*
X1044100Y380167D01*
G01X1052100Y380083D02*
X1052433Y379750D01*
X1052900Y379500D01*
X1053300D01*
X1053700Y379667D01*
X1053967Y379917D01*
X1054100Y380250D01*
X1054033Y380750D01*
X1053767Y381000D01*
X1052567Y381500D01*
X1052300Y382083D01*
X1052433Y382500D01*
X1052700Y382750D01*
X1053100Y382833D01*
X1053500Y382750D01*
X1053900Y382500D01*
G01X1057067Y379500D02*
Y384500D01*
G01Y382083D02*
X1057400Y382500D01*
X1057733Y382750D01*
X1058267Y382833D01*
X1058667Y382750D01*
X1059133Y382417D01*
X1059333Y381917D01*
Y379500D01*
G01X1063300D02*
X1062900Y379583D01*
X1062500Y379917D01*
X1062233Y380500D01*
X1062100Y381167D01*
X1062233Y381833D01*
X1062500Y382417D01*
X1062900Y382750D01*
X1063300Y382833D01*
X1063700Y382750D01*
X1064100Y382417D01*
X1064367Y381833D01*
X1064433Y381167D01*
X1064367Y380500D01*
X1064100Y379917D01*
X1063700Y379583D01*
X1063300Y379500D01*
G01X1067267Y382833D02*
Y380500D01*
X1067533Y379917D01*
X1067933Y379583D01*
X1068400Y379500D01*
X1068867Y379583D01*
X1069267Y379917D01*
X1069533Y380500D01*
G01Y379500D02*
Y382833D01*
G01X1073500Y379500D02*
Y384500D01*
G01X1079800D02*
Y379500D01*
G01Y380250D02*
X1079533Y379833D01*
X1079133Y379583D01*
X1078667Y379500D01*
X1078133Y379667D01*
X1077733Y380083D01*
X1077467Y380583D01*
X1077400Y381167D01*
X1077467Y381750D01*
X1077733Y382250D01*
X1078133Y382667D01*
X1078667Y382833D01*
X1079133Y382750D01*
X1079467Y382583D01*
X1079800Y382250D01*
G01X1087600Y379500D02*
Y384500D01*
G01Y382000D02*
X1087933Y382500D01*
X1088333Y382750D01*
X1088733Y382833D01*
X1089333Y382667D01*
X1089733Y382333D01*
X1090000Y381750D01*
Y381083D01*
X1089867Y380417D01*
X1089600Y379917D01*
X1089133Y379583D01*
X1088733Y379500D01*
X1088333Y379583D01*
X1087933Y379833D01*
X1087600Y380250D01*
G01X1092900Y381750D02*
X1095033D01*
X1094833Y382333D01*
X1094500Y382667D01*
X1094033Y382833D01*
X1093567Y382750D01*
X1093167Y382500D01*
X1092900Y381917D01*
X1092767Y381417D01*
Y380917D01*
X1092900Y380417D01*
X1093233Y379917D01*
X1093633Y379583D01*
X1094100Y379500D01*
X1094567Y379667D01*
X1095033Y380167D01*
G01X1102900Y377833D02*
Y382833D01*
G01Y382083D02*
X1103233Y382500D01*
X1103567Y382750D01*
X1104100Y382833D01*
X1104567Y382750D01*
X1105033Y382333D01*
X1105233Y381750D01*
X1105300Y381167D01*
X1105233Y380583D01*
X1105033Y380000D01*
X1104633Y379667D01*
X1104100Y379500D01*
X1103633Y379583D01*
X1103167Y379833D01*
X1102900Y380167D01*
G01X1109200Y379500D02*
Y384500D01*
G01X1113167Y382833D02*
Y380500D01*
X1113433Y379917D01*
X1113833Y379583D01*
X1114300Y379500D01*
X1114767Y379583D01*
X1115167Y379917D01*
X1115433Y380500D01*
G01Y379500D02*
Y382833D01*
G01X1118467Y378250D02*
X1118933Y377917D01*
X1119467Y377833D01*
X1119933Y377917D01*
X1120333Y378333D01*
X1120600Y378917D01*
Y382833D01*
G01Y382167D02*
X1120333Y382500D01*
X1119933Y382750D01*
X1119467Y382833D01*
X1118933Y382667D01*
X1118600Y382333D01*
X1118333Y381750D01*
X1118200Y381167D01*
X1118267Y380667D01*
X1118533Y380083D01*
X1118933Y379667D01*
X1119467Y379500D01*
X1119867Y379583D01*
X1120333Y379917D01*
X1120600Y380250D01*
G01X1123567Y378250D02*
X1124033Y377917D01*
X1124567Y377833D01*
X1125033Y377917D01*
X1125433Y378333D01*
X1125700Y378917D01*
Y382833D01*
G01Y382167D02*
X1125433Y382500D01*
X1125033Y382750D01*
X1124567Y382833D01*
X1124033Y382667D01*
X1123700Y382333D01*
X1123433Y381750D01*
X1123300Y381167D01*
X1123367Y380667D01*
X1123633Y380083D01*
X1124033Y379667D01*
X1124567Y379500D01*
X1124967Y379583D01*
X1125433Y379917D01*
X1125700Y380250D01*
G01X1128600Y381750D02*
X1130733D01*
X1130533Y382333D01*
X1130200Y382667D01*
X1129733Y382833D01*
X1129267Y382750D01*
X1128867Y382500D01*
X1128600Y381917D01*
X1128467Y381417D01*
Y380917D01*
X1128600Y380417D01*
X1128933Y379917D01*
X1129333Y379583D01*
X1129800Y379500D01*
X1130267Y379667D01*
X1130733Y380167D01*
G01X1135900Y384500D02*
Y379500D01*
G01Y380250D02*
X1135633Y379833D01*
X1135233Y379583D01*
X1134767Y379500D01*
X1134233Y379667D01*
X1133833Y380083D01*
X1133567Y380583D01*
X1133500Y381167D01*
X1133567Y381750D01*
X1133833Y382250D01*
X1134233Y382667D01*
X1134767Y382833D01*
X1135233Y382750D01*
X1135567Y382583D01*
X1135900Y382250D01*
G01X1143233Y382833D02*
X1144033Y379500D01*
X1144900Y382833D01*
X1145767Y379500D01*
X1146567Y382833D01*
G01X1150000D02*
Y379500D01*
G01Y384167D02*
X1149867Y384250D01*
Y384417D01*
X1150000Y384500D01*
X1150133Y384417D01*
Y384250D01*
X1150000Y384167D01*
G01X1155100Y384500D02*
Y379500D01*
G01X1154167Y382833D02*
X1156033D01*
G01X1159067Y379500D02*
Y384500D01*
G01Y382083D02*
X1159400Y382500D01*
X1159733Y382750D01*
X1160267Y382833D01*
X1160667Y382750D01*
X1161133Y382417D01*
X1161333Y381917D01*
Y379500D01*
G01X1169067D02*
X1171733Y381167D01*
X1169067Y382833D01*
G01X1174367Y380083D02*
X1174833Y379667D01*
X1175367Y379500D01*
X1175900Y379667D01*
X1176367Y380167D01*
X1176700Y380917D01*
X1176833Y381667D01*
Y382583D01*
X1176700Y383333D01*
X1176367Y384000D01*
X1175967Y384333D01*
X1175500Y384500D01*
X1174967Y384333D01*
X1174567Y384000D01*
X1174300Y383500D01*
X1174167Y382833D01*
X1174300Y382250D01*
X1174633Y381667D01*
X1175033Y381333D01*
X1175500Y381250D01*
X1176033Y381417D01*
X1176433Y381833D01*
X1176833Y382583D01*
G01X1180600Y384500D02*
X1180067Y384333D01*
X1179667Y383917D01*
X1179400Y383417D01*
X1179200Y382750D01*
X1179133Y382000D01*
X1179200Y381250D01*
X1179400Y380583D01*
X1179667Y380083D01*
X1180067Y379667D01*
X1180600Y379500D01*
X1181133Y379667D01*
X1181533Y380083D01*
X1181800Y380583D01*
X1182000Y381250D01*
X1182067Y382000D01*
X1182000Y382750D01*
X1181800Y383417D01*
X1181533Y383917D01*
X1181133Y384333D01*
X1180600Y384500D01*
G01X1184500Y379333D02*
X1186900Y384500D01*
G01X1184500D02*
X1184100Y384333D01*
X1183900Y384083D01*
X1183767Y383583D01*
X1183900Y383083D01*
X1184100Y382833D01*
X1184500Y382667D01*
X1184900Y382833D01*
X1185100Y383083D01*
X1185233Y383583D01*
X1185100Y384083D01*
X1184900Y384333D01*
X1184500Y384500D01*
G01X1186900Y381167D02*
X1186500Y381000D01*
X1186300Y380750D01*
X1186167Y380250D01*
X1186300Y379750D01*
X1186500Y379500D01*
X1186900Y379333D01*
X1187300Y379500D01*
X1187500Y379750D01*
X1187633Y380250D01*
X1187500Y380750D01*
X1187300Y381000D01*
X1186900Y381167D01*
G01X1194967Y379500D02*
Y382833D01*
G01Y382167D02*
X1195300Y382500D01*
X1195633Y382750D01*
X1196100Y382833D01*
X1196433Y382750D01*
X1196833Y382500D01*
G01X1200000Y381750D02*
X1202133D01*
X1201933Y382333D01*
X1201600Y382667D01*
X1201133Y382833D01*
X1200667Y382750D01*
X1200267Y382500D01*
X1200000Y381917D01*
X1199867Y381417D01*
Y380917D01*
X1200000Y380417D01*
X1200333Y379917D01*
X1200733Y379583D01*
X1201200Y379500D01*
X1201667Y379667D01*
X1202133Y380167D01*
G01X1205100Y380083D02*
X1205433Y379750D01*
X1205900Y379500D01*
X1206300D01*
X1206700Y379667D01*
X1206967Y379917D01*
X1207100Y380250D01*
X1207033Y380750D01*
X1206767Y381000D01*
X1205567Y381500D01*
X1205300Y382083D01*
X1205433Y382500D01*
X1205700Y382750D01*
X1206100Y382833D01*
X1206500Y382750D01*
X1206900Y382500D01*
G01X1211200Y382833D02*
Y379500D01*
G01Y384167D02*
X1211067Y384250D01*
Y384417D01*
X1211200Y384500D01*
X1211333Y384417D01*
Y384250D01*
X1211200Y384167D01*
G01X1215167Y379500D02*
Y382833D01*
G01Y382000D02*
X1215433Y382417D01*
X1215833Y382750D01*
X1216367Y382833D01*
X1216833Y382750D01*
X1217233Y382417D01*
X1217433Y381833D01*
Y379500D01*
G01X1226033Y378000D02*
X1226967Y379167D01*
Y380333D01*
X1226033D01*
Y379167D01*
X1226967D01*
G01Y381167D02*
Y382333D01*
X1226033D01*
Y381167D01*
X1226967D01*
G01X1230133Y379500D02*
Y384500D01*
X1231467D01*
X1232000Y384250D01*
X1232400Y383917D01*
X1232733Y383417D01*
X1233000Y382833D01*
X1233067Y382000D01*
X1233000Y381167D01*
X1232733Y380583D01*
X1232400Y380083D01*
X1232000Y379750D01*
X1231467Y379500D01*
X1230133D01*
G01X1236700D02*
X1236300Y379583D01*
X1235900Y379917D01*
X1235633Y380500D01*
X1235500Y381167D01*
X1235633Y381833D01*
X1235900Y382417D01*
X1236300Y382750D01*
X1236700Y382833D01*
X1237100Y382750D01*
X1237500Y382417D01*
X1237767Y381833D01*
X1237833Y381167D01*
X1237767Y380500D01*
X1237500Y379917D01*
X1237100Y379583D01*
X1236700Y379500D01*
G01X1245767D02*
Y382833D01*
G01Y382000D02*
X1246033Y382417D01*
X1246433Y382750D01*
X1246967Y382833D01*
X1247433Y382750D01*
X1247833Y382417D01*
X1248033Y381833D01*
Y379500D01*
G01X1252000D02*
X1251600Y379583D01*
X1251200Y379917D01*
X1250933Y380500D01*
X1250800Y381167D01*
X1250933Y381833D01*
X1251200Y382417D01*
X1251600Y382750D01*
X1252000Y382833D01*
X1252400Y382750D01*
X1252800Y382417D01*
X1253067Y381833D01*
X1253133Y381167D01*
X1253067Y380500D01*
X1252800Y379917D01*
X1252400Y379583D01*
X1252000Y379500D01*
G01X1257100Y384500D02*
Y379500D01*
G01X1256167Y382833D02*
X1258033D01*
G01X1268500Y379500D02*
Y382833D01*
G01Y382250D02*
X1268233Y382583D01*
X1267833Y382750D01*
X1267367Y382833D01*
X1266900Y382667D01*
X1266500Y382333D01*
X1266233Y381833D01*
X1266100Y381167D01*
X1266233Y380500D01*
X1266500Y380000D01*
X1266900Y379667D01*
X1267367Y379500D01*
X1267833Y379583D01*
X1268233Y379833D01*
X1268500Y380167D01*
G01X1272400Y379500D02*
Y384500D01*
G01X1277500Y379500D02*
Y384500D01*
G01X1282600Y379500D02*
X1282200Y379583D01*
X1281800Y379917D01*
X1281533Y380500D01*
X1281400Y381167D01*
X1281533Y381833D01*
X1281800Y382417D01*
X1282200Y382750D01*
X1282600Y382833D01*
X1283000Y382750D01*
X1283400Y382417D01*
X1283667Y381833D01*
X1283733Y381167D01*
X1283667Y380500D01*
X1283400Y379917D01*
X1283000Y379583D01*
X1282600Y379500D01*
G01X1286033Y382833D02*
X1286833Y379500D01*
X1287700Y382833D01*
X1288567Y379500D01*
X1289367Y382833D01*
G01X1022500Y390000D02*
Y395000D01*
X1021700Y394000D01*
G01Y390000D02*
X1023300D01*
G01X1027600Y389833D02*
X1027467Y389917D01*
Y390083D01*
X1027600Y390167D01*
X1027733Y390083D01*
Y389917D01*
X1027600Y389833D01*
G01X1031233Y390000D02*
Y395000D01*
X1032567D01*
X1033100Y394750D01*
X1033500Y394417D01*
X1033833Y393917D01*
X1034100Y393333D01*
X1034167Y392500D01*
X1034100Y391667D01*
X1033833Y391083D01*
X1033500Y390583D01*
X1033100Y390250D01*
X1032567Y390000D01*
X1031233D01*
G01X1037800Y393333D02*
Y390000D01*
G01Y394667D02*
X1037667Y394750D01*
Y394917D01*
X1037800Y395000D01*
X1037933Y394917D01*
Y394750D01*
X1037800Y394667D01*
G01X1040900Y390000D02*
Y393333D01*
G01Y392417D02*
X1041100Y392833D01*
X1041433Y393167D01*
X1041900Y393333D01*
X1042367Y393167D01*
X1042700Y392833D01*
X1042900Y392417D01*
Y390000D01*
G01Y392417D02*
X1043100Y392833D01*
X1043433Y393167D01*
X1043900Y393333D01*
X1044367Y393167D01*
X1044700Y392833D01*
X1044900Y392333D01*
Y390000D01*
G01X1046800Y388333D02*
Y393333D01*
G01Y392583D02*
X1047133Y393000D01*
X1047467Y393250D01*
X1048000Y393333D01*
X1048467Y393250D01*
X1048933Y392833D01*
X1049133Y392250D01*
X1049200Y391667D01*
X1049133Y391083D01*
X1048933Y390500D01*
X1048533Y390167D01*
X1048000Y390000D01*
X1047533Y390083D01*
X1047067Y390333D01*
X1046800Y390667D01*
G01X1053100Y390000D02*
Y395000D01*
G01X1057200Y392250D02*
X1059333D01*
X1059133Y392833D01*
X1058800Y393167D01*
X1058333Y393333D01*
X1057867Y393250D01*
X1057467Y393000D01*
X1057200Y392417D01*
X1057067Y391917D01*
Y391417D01*
X1057200Y390917D01*
X1057533Y390417D01*
X1057933Y390083D01*
X1058400Y390000D01*
X1058867Y390167D01*
X1059333Y390667D01*
G01X1069733Y390000D02*
X1067067Y391667D01*
X1069733Y393333D01*
G01X1078600Y390000D02*
Y395000D01*
X1077800Y394000D01*
G01Y390000D02*
X1079400D01*
G01X1086800D02*
Y393333D01*
G01Y392417D02*
X1087000Y392833D01*
X1087333Y393167D01*
X1087800Y393333D01*
X1088267Y393167D01*
X1088600Y392833D01*
X1088800Y392417D01*
Y390000D01*
G01Y392417D02*
X1089000Y392833D01*
X1089333Y393167D01*
X1089800Y393333D01*
X1090267Y393167D01*
X1090600Y392833D01*
X1090800Y392333D01*
Y390000D01*
G01X1093900Y393333D02*
Y390000D01*
G01Y394667D02*
X1093767Y394750D01*
Y394917D01*
X1093900Y395000D01*
X1094033Y394917D01*
Y394750D01*
X1093900Y394667D01*
G01X1099000Y390000D02*
Y395000D01*
G01X1108733Y388500D02*
X1109667Y389667D01*
Y390833D01*
X1108733D01*
Y389667D01*
X1109667D01*
G01Y391667D02*
Y392833D01*
X1108733D01*
Y391667D01*
X1109667D01*
G01X1016000Y604500D02*
Y366000D01*
G01X1033300Y413500D02*
Y418500D01*
G01Y416000D02*
X1033633Y416500D01*
X1034033Y416750D01*
X1034433Y416833D01*
X1035033Y416667D01*
X1035433Y416333D01*
X1035700Y415750D01*
Y415083D01*
X1035567Y414417D01*
X1035300Y413917D01*
X1034833Y413583D01*
X1034433Y413500D01*
X1034033Y413583D01*
X1033633Y413833D01*
X1033300Y414250D01*
G01X1038467Y416833D02*
Y414500D01*
X1038733Y413917D01*
X1039133Y413583D01*
X1039600Y413500D01*
X1040067Y413583D01*
X1040467Y413917D01*
X1040733Y414500D01*
G01Y413500D02*
Y416833D01*
G01X1043500Y413500D02*
Y418500D01*
G01Y416000D02*
X1043833Y416500D01*
X1044233Y416750D01*
X1044633Y416833D01*
X1045233Y416667D01*
X1045633Y416333D01*
X1045900Y415750D01*
Y415083D01*
X1045767Y414417D01*
X1045500Y413917D01*
X1045033Y413583D01*
X1044633Y413500D01*
X1044233Y413583D01*
X1043833Y413833D01*
X1043500Y414250D01*
G01X1048600Y413500D02*
Y418500D01*
G01Y416000D02*
X1048933Y416500D01*
X1049333Y416750D01*
X1049733Y416833D01*
X1050333Y416667D01*
X1050733Y416333D01*
X1051000Y415750D01*
Y415083D01*
X1050867Y414417D01*
X1050600Y413917D01*
X1050133Y413583D01*
X1049733Y413500D01*
X1049333Y413583D01*
X1048933Y413833D01*
X1048600Y414250D01*
G01X1054900Y413500D02*
Y418500D01*
G01X1059000Y415750D02*
X1061133D01*
X1060933Y416333D01*
X1060600Y416667D01*
X1060133Y416833D01*
X1059667Y416750D01*
X1059267Y416500D01*
X1059000Y415917D01*
X1058867Y415417D01*
Y414917D01*
X1059000Y414417D01*
X1059333Y413917D01*
X1059733Y413583D01*
X1060200Y413500D01*
X1060667Y413667D01*
X1061133Y414167D01*
G01X1070200Y416833D02*
Y413500D01*
G01Y418167D02*
X1070067Y418250D01*
Y418417D01*
X1070200Y418500D01*
X1070333Y418417D01*
Y418250D01*
X1070200Y418167D01*
G01X1074167Y413500D02*
Y416833D01*
G01Y416000D02*
X1074433Y416417D01*
X1074833Y416750D01*
X1075367Y416833D01*
X1075833Y416750D01*
X1076233Y416417D01*
X1076433Y415833D01*
Y413500D01*
G01X1079400Y414083D02*
X1079733Y413750D01*
X1080200Y413500D01*
X1080600D01*
X1081000Y413667D01*
X1081267Y413917D01*
X1081400Y414250D01*
X1081333Y414750D01*
X1081067Y415000D01*
X1079867Y415500D01*
X1079600Y416083D01*
X1079733Y416500D01*
X1080000Y416750D01*
X1080400Y416833D01*
X1080800Y416750D01*
X1081200Y416500D01*
G01X1085500Y416833D02*
Y413500D01*
G01Y418167D02*
X1085367Y418250D01*
Y418417D01*
X1085500Y418500D01*
X1085633Y418417D01*
Y418250D01*
X1085500Y418167D01*
G01X1091800Y418500D02*
Y413500D01*
G01Y414250D02*
X1091533Y413833D01*
X1091133Y413583D01*
X1090667Y413500D01*
X1090133Y413667D01*
X1089733Y414083D01*
X1089467Y414583D01*
X1089400Y415167D01*
X1089467Y415750D01*
X1089733Y416250D01*
X1090133Y416667D01*
X1090667Y416833D01*
X1091133Y416750D01*
X1091467Y416583D01*
X1091800Y416250D01*
G01X1094700Y415750D02*
X1096833D01*
X1096633Y416333D01*
X1096300Y416667D01*
X1095833Y416833D01*
X1095367Y416750D01*
X1094967Y416500D01*
X1094700Y415917D01*
X1094567Y415417D01*
Y414917D01*
X1094700Y414417D01*
X1095033Y413917D01*
X1095433Y413583D01*
X1095900Y413500D01*
X1096367Y413667D01*
X1096833Y414167D01*
G01X1105900Y418500D02*
Y413500D01*
G01X1104967Y416833D02*
X1106833D01*
G01X1109867Y413500D02*
Y418500D01*
G01Y416083D02*
X1110200Y416500D01*
X1110533Y416750D01*
X1111067Y416833D01*
X1111467Y416750D01*
X1111933Y416417D01*
X1112133Y415917D01*
Y413500D01*
G01X1115100Y415750D02*
X1117233D01*
X1117033Y416333D01*
X1116700Y416667D01*
X1116233Y416833D01*
X1115767Y416750D01*
X1115367Y416500D01*
X1115100Y415917D01*
X1114967Y415417D01*
Y414917D01*
X1115100Y414417D01*
X1115433Y413917D01*
X1115833Y413583D01*
X1116300Y413500D01*
X1116767Y413667D01*
X1117233Y414167D01*
G01X1125367Y413500D02*
Y416833D01*
G01Y416167D02*
X1125700Y416500D01*
X1126033Y416750D01*
X1126500Y416833D01*
X1126833Y416750D01*
X1127233Y416500D01*
G01X1130400Y415750D02*
X1132533D01*
X1132333Y416333D01*
X1132000Y416667D01*
X1131533Y416833D01*
X1131067Y416750D01*
X1130667Y416500D01*
X1130400Y415917D01*
X1130267Y415417D01*
Y414917D01*
X1130400Y414417D01*
X1130733Y413917D01*
X1131133Y413583D01*
X1131600Y413500D01*
X1132067Y413667D01*
X1132533Y414167D01*
G01X1135500Y414083D02*
X1135833Y413750D01*
X1136300Y413500D01*
X1136700D01*
X1137100Y413667D01*
X1137367Y413917D01*
X1137500Y414250D01*
X1137433Y414750D01*
X1137167Y415000D01*
X1135967Y415500D01*
X1135700Y416083D01*
X1135833Y416500D01*
X1136100Y416750D01*
X1136500Y416833D01*
X1136900Y416750D01*
X1137300Y416500D01*
G01X1141600Y416833D02*
Y413500D01*
G01Y418167D02*
X1141467Y418250D01*
Y418417D01*
X1141600Y418500D01*
X1141733Y418417D01*
Y418250D01*
X1141600Y418167D01*
G01X1145567Y413500D02*
Y416833D01*
G01Y416000D02*
X1145833Y416417D01*
X1146233Y416750D01*
X1146767Y416833D01*
X1147233Y416750D01*
X1147633Y416417D01*
X1147833Y415833D01*
Y413500D01*
G01X1151800Y413333D02*
X1151667Y413417D01*
Y413583D01*
X1151800Y413667D01*
X1151933Y413583D01*
Y413417D01*
X1151800Y413333D01*
G01X1022500Y424000D02*
Y429000D01*
X1021700Y428000D01*
G01Y424000D02*
X1023300D01*
G01X1027600Y423833D02*
X1027467Y423917D01*
Y424083D01*
X1027600Y424167D01*
X1027733Y424083D01*
Y423917D01*
X1027600Y423833D01*
G01X1031033Y429000D02*
X1032700Y424000D01*
X1034367Y429000D01*
G01X1037800Y427333D02*
Y424000D01*
G01Y428667D02*
X1037667Y428750D01*
Y428917D01*
X1037800Y429000D01*
X1037933Y428917D01*
Y428750D01*
X1037800Y428667D01*
G01X1044100Y424000D02*
Y427333D01*
G01Y426750D02*
X1043833Y427083D01*
X1043433Y427250D01*
X1042967Y427333D01*
X1042500Y427167D01*
X1042100Y426833D01*
X1041833Y426333D01*
X1041700Y425667D01*
X1041833Y425000D01*
X1042100Y424500D01*
X1042500Y424167D01*
X1042967Y424000D01*
X1043433Y424083D01*
X1043833Y424333D01*
X1044100Y424667D01*
G01X1052100Y424583D02*
X1052433Y424250D01*
X1052900Y424000D01*
X1053300D01*
X1053700Y424167D01*
X1053967Y424417D01*
X1054100Y424750D01*
X1054033Y425250D01*
X1053767Y425500D01*
X1052567Y426000D01*
X1052300Y426583D01*
X1052433Y427000D01*
X1052700Y427250D01*
X1053100Y427333D01*
X1053500Y427250D01*
X1053900Y427000D01*
G01X1057067Y424000D02*
Y429000D01*
G01Y426583D02*
X1057400Y427000D01*
X1057733Y427250D01*
X1058267Y427333D01*
X1058667Y427250D01*
X1059133Y426917D01*
X1059333Y426417D01*
Y424000D01*
G01X1063300D02*
X1062900Y424083D01*
X1062500Y424417D01*
X1062233Y425000D01*
X1062100Y425667D01*
X1062233Y426333D01*
X1062500Y426917D01*
X1062900Y427250D01*
X1063300Y427333D01*
X1063700Y427250D01*
X1064100Y426917D01*
X1064367Y426333D01*
X1064433Y425667D01*
X1064367Y425000D01*
X1064100Y424417D01*
X1063700Y424083D01*
X1063300Y424000D01*
G01X1067267Y427333D02*
Y425000D01*
X1067533Y424417D01*
X1067933Y424083D01*
X1068400Y424000D01*
X1068867Y424083D01*
X1069267Y424417D01*
X1069533Y425000D01*
G01Y424000D02*
Y427333D01*
G01X1073500Y424000D02*
Y429000D01*
G01X1079800D02*
Y424000D01*
G01Y424750D02*
X1079533Y424333D01*
X1079133Y424083D01*
X1078667Y424000D01*
X1078133Y424167D01*
X1077733Y424583D01*
X1077467Y425083D01*
X1077400Y425667D01*
X1077467Y426250D01*
X1077733Y426750D01*
X1078133Y427167D01*
X1078667Y427333D01*
X1079133Y427250D01*
X1079467Y427083D01*
X1079800Y426750D01*
G01X1087600Y424000D02*
Y429000D01*
G01Y426500D02*
X1087933Y427000D01*
X1088333Y427250D01*
X1088733Y427333D01*
X1089333Y427167D01*
X1089733Y426833D01*
X1090000Y426250D01*
Y425583D01*
X1089867Y424917D01*
X1089600Y424417D01*
X1089133Y424083D01*
X1088733Y424000D01*
X1088333Y424083D01*
X1087933Y424333D01*
X1087600Y424750D01*
G01X1092900Y426250D02*
X1095033D01*
X1094833Y426833D01*
X1094500Y427167D01*
X1094033Y427333D01*
X1093567Y427250D01*
X1093167Y427000D01*
X1092900Y426417D01*
X1092767Y425917D01*
Y425417D01*
X1092900Y424917D01*
X1093233Y424417D01*
X1093633Y424083D01*
X1094100Y424000D01*
X1094567Y424167D01*
X1095033Y424667D01*
G01X1102900Y422333D02*
Y427333D01*
G01Y426583D02*
X1103233Y427000D01*
X1103567Y427250D01*
X1104100Y427333D01*
X1104567Y427250D01*
X1105033Y426833D01*
X1105233Y426250D01*
X1105300Y425667D01*
X1105233Y425083D01*
X1105033Y424500D01*
X1104633Y424167D01*
X1104100Y424000D01*
X1103633Y424083D01*
X1103167Y424333D01*
X1102900Y424667D01*
G01X1109200Y424000D02*
Y429000D01*
G01X1113167Y427333D02*
Y425000D01*
X1113433Y424417D01*
X1113833Y424083D01*
X1114300Y424000D01*
X1114767Y424083D01*
X1115167Y424417D01*
X1115433Y425000D01*
G01Y424000D02*
Y427333D01*
G01X1118467Y422750D02*
X1118933Y422417D01*
X1119467Y422333D01*
X1119933Y422417D01*
X1120333Y422833D01*
X1120600Y423417D01*
Y427333D01*
G01Y426667D02*
X1120333Y427000D01*
X1119933Y427250D01*
X1119467Y427333D01*
X1118933Y427167D01*
X1118600Y426833D01*
X1118333Y426250D01*
X1118200Y425667D01*
X1118267Y425167D01*
X1118533Y424583D01*
X1118933Y424167D01*
X1119467Y424000D01*
X1119867Y424083D01*
X1120333Y424417D01*
X1120600Y424750D01*
G01X1123567Y422750D02*
X1124033Y422417D01*
X1124567Y422333D01*
X1125033Y422417D01*
X1125433Y422833D01*
X1125700Y423417D01*
Y427333D01*
G01Y426667D02*
X1125433Y427000D01*
X1125033Y427250D01*
X1124567Y427333D01*
X1124033Y427167D01*
X1123700Y426833D01*
X1123433Y426250D01*
X1123300Y425667D01*
X1123367Y425167D01*
X1123633Y424583D01*
X1124033Y424167D01*
X1124567Y424000D01*
X1124967Y424083D01*
X1125433Y424417D01*
X1125700Y424750D01*
G01X1128600Y426250D02*
X1130733D01*
X1130533Y426833D01*
X1130200Y427167D01*
X1129733Y427333D01*
X1129267Y427250D01*
X1128867Y427000D01*
X1128600Y426417D01*
X1128467Y425917D01*
Y425417D01*
X1128600Y424917D01*
X1128933Y424417D01*
X1129333Y424083D01*
X1129800Y424000D01*
X1130267Y424167D01*
X1130733Y424667D01*
G01X1135900Y429000D02*
Y424000D01*
G01Y424750D02*
X1135633Y424333D01*
X1135233Y424083D01*
X1134767Y424000D01*
X1134233Y424167D01*
X1133833Y424583D01*
X1133567Y425083D01*
X1133500Y425667D01*
X1133567Y426250D01*
X1133833Y426750D01*
X1134233Y427167D01*
X1134767Y427333D01*
X1135233Y427250D01*
X1135567Y427083D01*
X1135900Y426750D01*
G01X1143233Y427333D02*
X1144033Y424000D01*
X1144900Y427333D01*
X1145767Y424000D01*
X1146567Y427333D01*
G01X1150000D02*
Y424000D01*
G01Y428667D02*
X1149867Y428750D01*
Y428917D01*
X1150000Y429000D01*
X1150133Y428917D01*
Y428750D01*
X1150000Y428667D01*
G01X1155100Y429000D02*
Y424000D01*
G01X1154167Y427333D02*
X1156033D01*
G01X1159067Y424000D02*
Y429000D01*
G01Y426583D02*
X1159400Y427000D01*
X1159733Y427250D01*
X1160267Y427333D01*
X1160667Y427250D01*
X1161133Y426917D01*
X1161333Y426417D01*
Y424000D01*
G01X1169067D02*
X1171733Y425667D01*
X1169067Y427333D01*
G01X1174367Y424583D02*
X1174833Y424167D01*
X1175367Y424000D01*
X1175900Y424167D01*
X1176367Y424667D01*
X1176700Y425417D01*
X1176833Y426167D01*
Y427083D01*
X1176700Y427833D01*
X1176367Y428500D01*
X1175967Y428833D01*
X1175500Y429000D01*
X1174967Y428833D01*
X1174567Y428500D01*
X1174300Y428000D01*
X1174167Y427333D01*
X1174300Y426750D01*
X1174633Y426167D01*
X1175033Y425833D01*
X1175500Y425750D01*
X1176033Y425917D01*
X1176433Y426333D01*
X1176833Y427083D01*
G01X1180600Y429000D02*
X1180067Y428833D01*
X1179667Y428417D01*
X1179400Y427917D01*
X1179200Y427250D01*
X1179133Y426500D01*
X1179200Y425750D01*
X1179400Y425083D01*
X1179667Y424583D01*
X1180067Y424167D01*
X1180600Y424000D01*
X1181133Y424167D01*
X1181533Y424583D01*
X1181800Y425083D01*
X1182000Y425750D01*
X1182067Y426500D01*
X1182000Y427250D01*
X1181800Y427917D01*
X1181533Y428417D01*
X1181133Y428833D01*
X1180600Y429000D01*
G01X1184500Y423833D02*
X1186900Y429000D01*
G01X1184500D02*
X1184100Y428833D01*
X1183900Y428583D01*
X1183767Y428083D01*
X1183900Y427583D01*
X1184100Y427333D01*
X1184500Y427167D01*
X1184900Y427333D01*
X1185100Y427583D01*
X1185233Y428083D01*
X1185100Y428583D01*
X1184900Y428833D01*
X1184500Y429000D01*
G01X1186900Y425667D02*
X1186500Y425500D01*
X1186300Y425250D01*
X1186167Y424750D01*
X1186300Y424250D01*
X1186500Y424000D01*
X1186900Y423833D01*
X1187300Y424000D01*
X1187500Y424250D01*
X1187633Y424750D01*
X1187500Y425250D01*
X1187300Y425500D01*
X1186900Y425667D01*
G01X1194967Y424000D02*
Y427333D01*
G01Y426667D02*
X1195300Y427000D01*
X1195633Y427250D01*
X1196100Y427333D01*
X1196433Y427250D01*
X1196833Y427000D01*
G01X1200000Y426250D02*
X1202133D01*
X1201933Y426833D01*
X1201600Y427167D01*
X1201133Y427333D01*
X1200667Y427250D01*
X1200267Y427000D01*
X1200000Y426417D01*
X1199867Y425917D01*
Y425417D01*
X1200000Y424917D01*
X1200333Y424417D01*
X1200733Y424083D01*
X1201200Y424000D01*
X1201667Y424167D01*
X1202133Y424667D01*
G01X1205100Y424583D02*
X1205433Y424250D01*
X1205900Y424000D01*
X1206300D01*
X1206700Y424167D01*
X1206967Y424417D01*
X1207100Y424750D01*
X1207033Y425250D01*
X1206767Y425500D01*
X1205567Y426000D01*
X1205300Y426583D01*
X1205433Y427000D01*
X1205700Y427250D01*
X1206100Y427333D01*
X1206500Y427250D01*
X1206900Y427000D01*
G01X1211200Y427333D02*
Y424000D01*
G01Y428667D02*
X1211067Y428750D01*
Y428917D01*
X1211200Y429000D01*
X1211333Y428917D01*
Y428750D01*
X1211200Y428667D01*
G01X1215167Y424000D02*
Y427333D01*
G01Y426500D02*
X1215433Y426917D01*
X1215833Y427250D01*
X1216367Y427333D01*
X1216833Y427250D01*
X1217233Y426917D01*
X1217433Y426333D01*
Y424000D01*
G01X1226033Y422500D02*
X1226967Y423667D01*
Y424833D01*
X1226033D01*
Y423667D01*
X1226967D01*
G01Y425667D02*
Y426833D01*
X1226033D01*
Y425667D01*
X1226967D01*
G01X1230133Y424000D02*
Y429000D01*
X1231467D01*
X1232000Y428750D01*
X1232400Y428417D01*
X1232733Y427917D01*
X1233000Y427333D01*
X1233067Y426500D01*
X1233000Y425667D01*
X1232733Y425083D01*
X1232400Y424583D01*
X1232000Y424250D01*
X1231467Y424000D01*
X1230133D01*
G01X1236700D02*
X1236300Y424083D01*
X1235900Y424417D01*
X1235633Y425000D01*
X1235500Y425667D01*
X1235633Y426333D01*
X1235900Y426917D01*
X1236300Y427250D01*
X1236700Y427333D01*
X1237100Y427250D01*
X1237500Y426917D01*
X1237767Y426333D01*
X1237833Y425667D01*
X1237767Y425000D01*
X1237500Y424417D01*
X1237100Y424083D01*
X1236700Y424000D01*
G01X1245767D02*
Y427333D01*
G01Y426500D02*
X1246033Y426917D01*
X1246433Y427250D01*
X1246967Y427333D01*
X1247433Y427250D01*
X1247833Y426917D01*
X1248033Y426333D01*
Y424000D01*
G01X1252000D02*
X1251600Y424083D01*
X1251200Y424417D01*
X1250933Y425000D01*
X1250800Y425667D01*
X1250933Y426333D01*
X1251200Y426917D01*
X1251600Y427250D01*
X1252000Y427333D01*
X1252400Y427250D01*
X1252800Y426917D01*
X1253067Y426333D01*
X1253133Y425667D01*
X1253067Y425000D01*
X1252800Y424417D01*
X1252400Y424083D01*
X1252000Y424000D01*
G01X1257100Y429000D02*
Y424000D01*
G01X1256167Y427333D02*
X1258033D01*
G01X1268500Y424000D02*
Y427333D01*
G01Y426750D02*
X1268233Y427083D01*
X1267833Y427250D01*
X1267367Y427333D01*
X1266900Y427167D01*
X1266500Y426833D01*
X1266233Y426333D01*
X1266100Y425667D01*
X1266233Y425000D01*
X1266500Y424500D01*
X1266900Y424167D01*
X1267367Y424000D01*
X1267833Y424083D01*
X1268233Y424333D01*
X1268500Y424667D01*
G01X1272400Y424000D02*
Y429000D01*
G01X1277500Y424000D02*
Y429000D01*
G01X1282600Y424000D02*
X1282200Y424083D01*
X1281800Y424417D01*
X1281533Y425000D01*
X1281400Y425667D01*
X1281533Y426333D01*
X1281800Y426917D01*
X1282200Y427250D01*
X1282600Y427333D01*
X1283000Y427250D01*
X1283400Y426917D01*
X1283667Y426333D01*
X1283733Y425667D01*
X1283667Y425000D01*
X1283400Y424417D01*
X1283000Y424083D01*
X1282600Y424000D01*
G01X1286033Y427333D02*
X1286833Y424000D01*
X1287700Y427333D01*
X1288567Y424000D01*
X1289367Y427333D01*
G01X1025333Y445500D02*
X1027000Y440500D01*
X1028667Y445500D01*
G01X1032100Y443833D02*
Y440500D01*
G01Y445167D02*
X1031967Y445250D01*
Y445417D01*
X1032100Y445500D01*
X1032233Y445417D01*
Y445250D01*
X1032100Y445167D01*
G01X1038400Y440500D02*
Y443833D01*
G01Y443250D02*
X1038133Y443583D01*
X1037733Y443750D01*
X1037267Y443833D01*
X1036800Y443667D01*
X1036400Y443333D01*
X1036133Y442833D01*
X1036000Y442167D01*
X1036133Y441500D01*
X1036400Y441000D01*
X1036800Y440667D01*
X1037267Y440500D01*
X1037733Y440583D01*
X1038133Y440833D01*
X1038400Y441167D01*
G01X1046400Y441083D02*
X1046733Y440750D01*
X1047200Y440500D01*
X1047600D01*
X1048000Y440667D01*
X1048267Y440917D01*
X1048400Y441250D01*
X1048333Y441750D01*
X1048067Y442000D01*
X1046867Y442500D01*
X1046600Y443083D01*
X1046733Y443500D01*
X1047000Y443750D01*
X1047400Y443833D01*
X1047800Y443750D01*
X1048200Y443500D01*
G01X1051367Y440500D02*
Y445500D01*
G01Y443083D02*
X1051700Y443500D01*
X1052033Y443750D01*
X1052567Y443833D01*
X1052967Y443750D01*
X1053433Y443417D01*
X1053633Y442917D01*
Y440500D01*
G01X1057600D02*
X1057200Y440583D01*
X1056800Y440917D01*
X1056533Y441500D01*
X1056400Y442167D01*
X1056533Y442833D01*
X1056800Y443417D01*
X1057200Y443750D01*
X1057600Y443833D01*
X1058000Y443750D01*
X1058400Y443417D01*
X1058667Y442833D01*
X1058733Y442167D01*
X1058667Y441500D01*
X1058400Y440917D01*
X1058000Y440583D01*
X1057600Y440500D01*
G01X1061567Y443833D02*
Y441500D01*
X1061833Y440917D01*
X1062233Y440583D01*
X1062700Y440500D01*
X1063167Y440583D01*
X1063567Y440917D01*
X1063833Y441500D01*
G01Y440500D02*
Y443833D01*
G01X1067800Y440500D02*
Y445500D01*
G01X1074100D02*
Y440500D01*
G01Y441250D02*
X1073833Y440833D01*
X1073433Y440583D01*
X1072967Y440500D01*
X1072433Y440667D01*
X1072033Y441083D01*
X1071767Y441583D01*
X1071700Y442167D01*
X1071767Y442750D01*
X1072033Y443250D01*
X1072433Y443667D01*
X1072967Y443833D01*
X1073433Y443750D01*
X1073767Y443583D01*
X1074100Y443250D01*
G01X1081900Y440500D02*
Y445500D01*
G01Y443000D02*
X1082233Y443500D01*
X1082633Y443750D01*
X1083033Y443833D01*
X1083633Y443667D01*
X1084033Y443333D01*
X1084300Y442750D01*
Y442083D01*
X1084167Y441417D01*
X1083900Y440917D01*
X1083433Y440583D01*
X1083033Y440500D01*
X1082633Y440583D01*
X1082233Y440833D01*
X1081900Y441250D01*
G01X1087200Y442750D02*
X1089333D01*
X1089133Y443333D01*
X1088800Y443667D01*
X1088333Y443833D01*
X1087867Y443750D01*
X1087467Y443500D01*
X1087200Y442917D01*
X1087067Y442417D01*
Y441917D01*
X1087200Y441417D01*
X1087533Y440917D01*
X1087933Y440583D01*
X1088400Y440500D01*
X1088867Y440667D01*
X1089333Y441167D01*
G01X1097200Y438833D02*
Y443833D01*
G01Y443083D02*
X1097533Y443500D01*
X1097867Y443750D01*
X1098400Y443833D01*
X1098867Y443750D01*
X1099333Y443333D01*
X1099533Y442750D01*
X1099600Y442167D01*
X1099533Y441583D01*
X1099333Y441000D01*
X1098933Y440667D01*
X1098400Y440500D01*
X1097933Y440583D01*
X1097467Y440833D01*
X1097200Y441167D01*
G01X1103500Y440500D02*
Y445500D01*
G01X1107467Y443833D02*
Y441500D01*
X1107733Y440917D01*
X1108133Y440583D01*
X1108600Y440500D01*
X1109067Y440583D01*
X1109467Y440917D01*
X1109733Y441500D01*
G01Y440500D02*
Y443833D01*
G01X1112767Y439250D02*
X1113233Y438917D01*
X1113767Y438833D01*
X1114233Y438917D01*
X1114633Y439333D01*
X1114900Y439917D01*
Y443833D01*
G01Y443167D02*
X1114633Y443500D01*
X1114233Y443750D01*
X1113767Y443833D01*
X1113233Y443667D01*
X1112900Y443333D01*
X1112633Y442750D01*
X1112500Y442167D01*
X1112567Y441667D01*
X1112833Y441083D01*
X1113233Y440667D01*
X1113767Y440500D01*
X1114167Y440583D01*
X1114633Y440917D01*
X1114900Y441250D01*
G01X1117867Y439250D02*
X1118333Y438917D01*
X1118867Y438833D01*
X1119333Y438917D01*
X1119733Y439333D01*
X1120000Y439917D01*
Y443833D01*
G01Y443167D02*
X1119733Y443500D01*
X1119333Y443750D01*
X1118867Y443833D01*
X1118333Y443667D01*
X1118000Y443333D01*
X1117733Y442750D01*
X1117600Y442167D01*
X1117667Y441667D01*
X1117933Y441083D01*
X1118333Y440667D01*
X1118867Y440500D01*
X1119267Y440583D01*
X1119733Y440917D01*
X1120000Y441250D01*
G01X1122900Y442750D02*
X1125033D01*
X1124833Y443333D01*
X1124500Y443667D01*
X1124033Y443833D01*
X1123567Y443750D01*
X1123167Y443500D01*
X1122900Y442917D01*
X1122767Y442417D01*
Y441917D01*
X1122900Y441417D01*
X1123233Y440917D01*
X1123633Y440583D01*
X1124100Y440500D01*
X1124567Y440667D01*
X1125033Y441167D01*
G01X1130200Y445500D02*
Y440500D01*
G01Y441250D02*
X1129933Y440833D01*
X1129533Y440583D01*
X1129067Y440500D01*
X1128533Y440667D01*
X1128133Y441083D01*
X1127867Y441583D01*
X1127800Y442167D01*
X1127867Y442750D01*
X1128133Y443250D01*
X1128533Y443667D01*
X1129067Y443833D01*
X1129533Y443750D01*
X1129867Y443583D01*
X1130200Y443250D01*
G01X1137533Y443833D02*
X1138333Y440500D01*
X1139200Y443833D01*
X1140067Y440500D01*
X1140867Y443833D01*
G01X1144300D02*
Y440500D01*
G01Y445167D02*
X1144167Y445250D01*
Y445417D01*
X1144300Y445500D01*
X1144433Y445417D01*
Y445250D01*
X1144300Y445167D01*
G01X1149400Y445500D02*
Y440500D01*
G01X1148467Y443833D02*
X1150333D01*
G01X1153367Y440500D02*
Y445500D01*
G01Y443083D02*
X1153700Y443500D01*
X1154033Y443750D01*
X1154567Y443833D01*
X1154967Y443750D01*
X1155433Y443417D01*
X1155633Y442917D01*
Y440500D01*
G01X1163367D02*
X1166033Y442167D01*
X1163367Y443833D01*
G01X1168667Y441083D02*
X1169133Y440667D01*
X1169667Y440500D01*
X1170200Y440667D01*
X1170667Y441167D01*
X1171000Y441917D01*
X1171133Y442667D01*
Y443583D01*
X1171000Y444333D01*
X1170667Y445000D01*
X1170267Y445333D01*
X1169800Y445500D01*
X1169267Y445333D01*
X1168867Y445000D01*
X1168600Y444500D01*
X1168467Y443833D01*
X1168600Y443250D01*
X1168933Y442667D01*
X1169333Y442333D01*
X1169800Y442250D01*
X1170333Y442417D01*
X1170733Y442833D01*
X1171133Y443583D01*
G01X1174900Y445500D02*
X1174367Y445333D01*
X1173967Y444917D01*
X1173700Y444417D01*
X1173500Y443750D01*
X1173433Y443000D01*
X1173500Y442250D01*
X1173700Y441583D01*
X1173967Y441083D01*
X1174367Y440667D01*
X1174900Y440500D01*
X1175433Y440667D01*
X1175833Y441083D01*
X1176100Y441583D01*
X1176300Y442250D01*
X1176367Y443000D01*
X1176300Y443750D01*
X1176100Y444417D01*
X1175833Y444917D01*
X1175433Y445333D01*
X1174900Y445500D01*
G01X1178800Y440333D02*
X1181200Y445500D01*
G01X1178800D02*
X1178400Y445333D01*
X1178200Y445083D01*
X1178067Y444583D01*
X1178200Y444083D01*
X1178400Y443833D01*
X1178800Y443667D01*
X1179200Y443833D01*
X1179400Y444083D01*
X1179533Y444583D01*
X1179400Y445083D01*
X1179200Y445333D01*
X1178800Y445500D01*
G01X1181200Y442167D02*
X1180800Y442000D01*
X1180600Y441750D01*
X1180467Y441250D01*
X1180600Y440750D01*
X1180800Y440500D01*
X1181200Y440333D01*
X1181600Y440500D01*
X1181800Y440750D01*
X1181933Y441250D01*
X1181800Y441750D01*
X1181600Y442000D01*
X1181200Y442167D01*
G01X1189267Y440500D02*
Y443833D01*
G01Y443167D02*
X1189600Y443500D01*
X1189933Y443750D01*
X1190400Y443833D01*
X1190733Y443750D01*
X1191133Y443500D01*
G01X1194300Y442750D02*
X1196433D01*
X1196233Y443333D01*
X1195900Y443667D01*
X1195433Y443833D01*
X1194967Y443750D01*
X1194567Y443500D01*
X1194300Y442917D01*
X1194167Y442417D01*
Y441917D01*
X1194300Y441417D01*
X1194633Y440917D01*
X1195033Y440583D01*
X1195500Y440500D01*
X1195967Y440667D01*
X1196433Y441167D01*
G01X1199400Y441083D02*
X1199733Y440750D01*
X1200200Y440500D01*
X1200600D01*
X1201000Y440667D01*
X1201267Y440917D01*
X1201400Y441250D01*
X1201333Y441750D01*
X1201067Y442000D01*
X1199867Y442500D01*
X1199600Y443083D01*
X1199733Y443500D01*
X1200000Y443750D01*
X1200400Y443833D01*
X1200800Y443750D01*
X1201200Y443500D01*
G01X1205500Y443833D02*
Y440500D01*
G01Y445167D02*
X1205367Y445250D01*
Y445417D01*
X1205500Y445500D01*
X1205633Y445417D01*
Y445250D01*
X1205500Y445167D01*
G01X1209467Y440500D02*
Y443833D01*
G01Y443000D02*
X1209733Y443417D01*
X1210133Y443750D01*
X1210667Y443833D01*
X1211133Y443750D01*
X1211533Y443417D01*
X1211733Y442833D01*
Y440500D01*
G01X1023833Y466500D02*
X1025500Y461500D01*
X1027167Y466500D01*
G01X1030600Y464833D02*
Y461500D01*
G01Y466167D02*
X1030467Y466250D01*
Y466417D01*
X1030600Y466500D01*
X1030733Y466417D01*
Y466250D01*
X1030600Y466167D01*
G01X1036900Y461500D02*
Y464833D01*
G01Y464250D02*
X1036633Y464583D01*
X1036233Y464750D01*
X1035767Y464833D01*
X1035300Y464667D01*
X1034900Y464333D01*
X1034633Y463833D01*
X1034500Y463167D01*
X1034633Y462500D01*
X1034900Y462000D01*
X1035300Y461667D01*
X1035767Y461500D01*
X1036233Y461583D01*
X1036633Y461833D01*
X1036900Y462167D01*
G01X1044900Y462083D02*
X1045233Y461750D01*
X1045700Y461500D01*
X1046100D01*
X1046500Y461667D01*
X1046767Y461917D01*
X1046900Y462250D01*
X1046833Y462750D01*
X1046567Y463000D01*
X1045367Y463500D01*
X1045100Y464083D01*
X1045233Y464500D01*
X1045500Y464750D01*
X1045900Y464833D01*
X1046300Y464750D01*
X1046700Y464500D01*
G01X1049867Y461500D02*
Y466500D01*
G01Y464083D02*
X1050200Y464500D01*
X1050533Y464750D01*
X1051067Y464833D01*
X1051467Y464750D01*
X1051933Y464417D01*
X1052133Y463917D01*
Y461500D01*
G01X1056100D02*
X1055700Y461583D01*
X1055300Y461917D01*
X1055033Y462500D01*
X1054900Y463167D01*
X1055033Y463833D01*
X1055300Y464417D01*
X1055700Y464750D01*
X1056100Y464833D01*
X1056500Y464750D01*
X1056900Y464417D01*
X1057167Y463833D01*
X1057233Y463167D01*
X1057167Y462500D01*
X1056900Y461917D01*
X1056500Y461583D01*
X1056100Y461500D01*
G01X1060067Y464833D02*
Y462500D01*
X1060333Y461917D01*
X1060733Y461583D01*
X1061200Y461500D01*
X1061667Y461583D01*
X1062067Y461917D01*
X1062333Y462500D01*
G01Y461500D02*
Y464833D01*
G01X1066300Y461500D02*
Y466500D01*
G01X1072600D02*
Y461500D01*
G01Y462250D02*
X1072333Y461833D01*
X1071933Y461583D01*
X1071467Y461500D01*
X1070933Y461667D01*
X1070533Y462083D01*
X1070267Y462583D01*
X1070200Y463167D01*
X1070267Y463750D01*
X1070533Y464250D01*
X1070933Y464667D01*
X1071467Y464833D01*
X1071933Y464750D01*
X1072267Y464583D01*
X1072600Y464250D01*
G01X1080400Y461500D02*
Y466500D01*
G01Y464000D02*
X1080733Y464500D01*
X1081133Y464750D01*
X1081533Y464833D01*
X1082133Y464667D01*
X1082533Y464333D01*
X1082800Y463750D01*
Y463083D01*
X1082667Y462417D01*
X1082400Y461917D01*
X1081933Y461583D01*
X1081533Y461500D01*
X1081133Y461583D01*
X1080733Y461833D01*
X1080400Y462250D01*
G01X1085700Y463750D02*
X1087833D01*
X1087633Y464333D01*
X1087300Y464667D01*
X1086833Y464833D01*
X1086367Y464750D01*
X1085967Y464500D01*
X1085700Y463917D01*
X1085567Y463417D01*
Y462917D01*
X1085700Y462417D01*
X1086033Y461917D01*
X1086433Y461583D01*
X1086900Y461500D01*
X1087367Y461667D01*
X1087833Y462167D01*
G01X1095700Y459833D02*
Y464833D01*
G01Y464083D02*
X1096033Y464500D01*
X1096367Y464750D01*
X1096900Y464833D01*
X1097367Y464750D01*
X1097833Y464333D01*
X1098033Y463750D01*
X1098100Y463167D01*
X1098033Y462583D01*
X1097833Y462000D01*
X1097433Y461667D01*
X1096900Y461500D01*
X1096433Y461583D01*
X1095967Y461833D01*
X1095700Y462167D01*
G01X1102000Y461500D02*
Y466500D01*
G01X1105967Y464833D02*
Y462500D01*
X1106233Y461917D01*
X1106633Y461583D01*
X1107100Y461500D01*
X1107567Y461583D01*
X1107967Y461917D01*
X1108233Y462500D01*
G01Y461500D02*
Y464833D01*
G01X1111267Y460250D02*
X1111733Y459917D01*
X1112267Y459833D01*
X1112733Y459917D01*
X1113133Y460333D01*
X1113400Y460917D01*
Y464833D01*
G01Y464167D02*
X1113133Y464500D01*
X1112733Y464750D01*
X1112267Y464833D01*
X1111733Y464667D01*
X1111400Y464333D01*
X1111133Y463750D01*
X1111000Y463167D01*
X1111067Y462667D01*
X1111333Y462083D01*
X1111733Y461667D01*
X1112267Y461500D01*
X1112667Y461583D01*
X1113133Y461917D01*
X1113400Y462250D01*
G01X1116367Y460250D02*
X1116833Y459917D01*
X1117367Y459833D01*
X1117833Y459917D01*
X1118233Y460333D01*
X1118500Y460917D01*
Y464833D01*
G01Y464167D02*
X1118233Y464500D01*
X1117833Y464750D01*
X1117367Y464833D01*
X1116833Y464667D01*
X1116500Y464333D01*
X1116233Y463750D01*
X1116100Y463167D01*
X1116167Y462667D01*
X1116433Y462083D01*
X1116833Y461667D01*
X1117367Y461500D01*
X1117767Y461583D01*
X1118233Y461917D01*
X1118500Y462250D01*
G01X1121400Y463750D02*
X1123533D01*
X1123333Y464333D01*
X1123000Y464667D01*
X1122533Y464833D01*
X1122067Y464750D01*
X1121667Y464500D01*
X1121400Y463917D01*
X1121267Y463417D01*
Y462917D01*
X1121400Y462417D01*
X1121733Y461917D01*
X1122133Y461583D01*
X1122600Y461500D01*
X1123067Y461667D01*
X1123533Y462167D01*
G01X1128700Y466500D02*
Y461500D01*
G01Y462250D02*
X1128433Y461833D01*
X1128033Y461583D01*
X1127567Y461500D01*
X1127033Y461667D01*
X1126633Y462083D01*
X1126367Y462583D01*
X1126300Y463167D01*
X1126367Y463750D01*
X1126633Y464250D01*
X1127033Y464667D01*
X1127567Y464833D01*
X1128033Y464750D01*
X1128367Y464583D01*
X1128700Y464250D01*
G01X1138500Y461500D02*
Y466500D01*
X1136033Y462917D01*
X1139367D01*
G01X1142800Y466500D02*
X1142267Y466333D01*
X1141867Y465917D01*
X1141600Y465417D01*
X1141400Y464750D01*
X1141333Y464000D01*
X1141400Y463250D01*
X1141600Y462583D01*
X1141867Y462083D01*
X1142267Y461667D01*
X1142800Y461500D01*
X1143333Y461667D01*
X1143733Y462083D01*
X1144000Y462583D01*
X1144200Y463250D01*
X1144267Y464000D01*
X1144200Y464750D01*
X1144000Y465417D01*
X1143733Y465917D01*
X1143333Y466333D01*
X1142800Y466500D01*
G01X1146700Y461333D02*
X1149100Y466500D01*
G01X1146700D02*
X1146300Y466333D01*
X1146100Y466083D01*
X1145967Y465583D01*
X1146100Y465083D01*
X1146300Y464833D01*
X1146700Y464667D01*
X1147100Y464833D01*
X1147300Y465083D01*
X1147433Y465583D01*
X1147300Y466083D01*
X1147100Y466333D01*
X1146700Y466500D01*
G01X1149100Y463167D02*
X1148700Y463000D01*
X1148500Y462750D01*
X1148367Y462250D01*
X1148500Y461750D01*
X1148700Y461500D01*
X1149100Y461333D01*
X1149500Y461500D01*
X1149700Y461750D01*
X1149833Y462250D01*
X1149700Y462750D01*
X1149500Y463000D01*
X1149100Y463167D01*
G01X1156100D02*
X1156767Y464833D01*
X1157433D01*
X1158767Y461500D01*
X1159433D01*
X1160100Y463167D01*
G01X1168300Y461500D02*
Y466500D01*
X1167500Y465500D01*
G01Y461500D02*
X1169100D01*
G01X1173400Y466500D02*
X1172867Y466333D01*
X1172467Y465917D01*
X1172200Y465417D01*
X1172000Y464750D01*
X1171933Y464000D01*
X1172000Y463250D01*
X1172200Y462583D01*
X1172467Y462083D01*
X1172867Y461667D01*
X1173400Y461500D01*
X1173933Y461667D01*
X1174333Y462083D01*
X1174600Y462583D01*
X1174800Y463250D01*
X1174867Y464000D01*
X1174800Y464750D01*
X1174600Y465417D01*
X1174333Y465917D01*
X1173933Y466333D01*
X1173400Y466500D01*
G01X1178500D02*
X1177967Y466333D01*
X1177567Y465917D01*
X1177300Y465417D01*
X1177100Y464750D01*
X1177033Y464000D01*
X1177100Y463250D01*
X1177300Y462583D01*
X1177567Y462083D01*
X1177967Y461667D01*
X1178500Y461500D01*
X1179033Y461667D01*
X1179433Y462083D01*
X1179700Y462583D01*
X1179900Y463250D01*
X1179967Y464000D01*
X1179900Y464750D01*
X1179700Y465417D01*
X1179433Y465917D01*
X1179033Y466333D01*
X1178500Y466500D01*
G01X1182400Y461333D02*
X1184800Y466500D01*
G01X1182400D02*
X1182000Y466333D01*
X1181800Y466083D01*
X1181667Y465583D01*
X1181800Y465083D01*
X1182000Y464833D01*
X1182400Y464667D01*
X1182800Y464833D01*
X1183000Y465083D01*
X1183133Y465583D01*
X1183000Y466083D01*
X1182800Y466333D01*
X1182400Y466500D01*
G01X1184800Y463167D02*
X1184400Y463000D01*
X1184200Y462750D01*
X1184067Y462250D01*
X1184200Y461750D01*
X1184400Y461500D01*
X1184800Y461333D01*
X1185200Y461500D01*
X1185400Y461750D01*
X1185533Y462250D01*
X1185400Y462750D01*
X1185200Y463000D01*
X1184800Y463167D01*
G01X1192800Y462083D02*
X1193133Y461750D01*
X1193600Y461500D01*
X1194000D01*
X1194400Y461667D01*
X1194667Y461917D01*
X1194800Y462250D01*
X1194733Y462750D01*
X1194467Y463000D01*
X1193267Y463500D01*
X1193000Y464083D01*
X1193133Y464500D01*
X1193400Y464750D01*
X1193800Y464833D01*
X1194200Y464750D01*
X1194600Y464500D01*
G01X1198900Y461500D02*
X1198500Y461583D01*
X1198100Y461917D01*
X1197833Y462500D01*
X1197700Y463167D01*
X1197833Y463833D01*
X1198100Y464417D01*
X1198500Y464750D01*
X1198900Y464833D01*
X1199300Y464750D01*
X1199700Y464417D01*
X1199967Y463833D01*
X1200033Y463167D01*
X1199967Y462500D01*
X1199700Y461917D01*
X1199300Y461583D01*
X1198900Y461500D01*
G01X1204000D02*
Y466500D01*
G01X1210300D02*
Y461500D01*
G01Y462250D02*
X1210033Y461833D01*
X1209633Y461583D01*
X1209167Y461500D01*
X1208633Y461667D01*
X1208233Y462083D01*
X1207967Y462583D01*
X1207900Y463167D01*
X1207967Y463750D01*
X1208233Y464250D01*
X1208633Y464667D01*
X1209167Y464833D01*
X1209633Y464750D01*
X1209967Y464583D01*
X1210300Y464250D01*
G01X1213200Y463750D02*
X1215333D01*
X1215133Y464333D01*
X1214800Y464667D01*
X1214333Y464833D01*
X1213867Y464750D01*
X1213467Y464500D01*
X1213200Y463917D01*
X1213067Y463417D01*
Y462917D01*
X1213200Y462417D01*
X1213533Y461917D01*
X1213933Y461583D01*
X1214400Y461500D01*
X1214867Y461667D01*
X1215333Y462167D01*
G01X1218367Y461500D02*
Y464833D01*
G01Y464167D02*
X1218700Y464500D01*
X1219033Y464750D01*
X1219500Y464833D01*
X1219833Y464750D01*
X1220233Y464500D01*
G01X1227500Y461500D02*
Y464833D01*
G01Y463917D02*
X1227700Y464333D01*
X1228033Y464667D01*
X1228500Y464833D01*
X1228967Y464667D01*
X1229300Y464333D01*
X1229500Y463917D01*
Y461500D01*
G01Y463917D02*
X1229700Y464333D01*
X1230033Y464667D01*
X1230500Y464833D01*
X1230967Y464667D01*
X1231300Y464333D01*
X1231500Y463833D01*
Y461500D01*
G01X1235800D02*
Y464833D01*
G01Y464250D02*
X1235533Y464583D01*
X1235133Y464750D01*
X1234667Y464833D01*
X1234200Y464667D01*
X1233800Y464333D01*
X1233533Y463833D01*
X1233400Y463167D01*
X1233533Y462500D01*
X1233800Y462000D01*
X1234200Y461667D01*
X1234667Y461500D01*
X1235133Y461583D01*
X1235533Y461833D01*
X1235800Y462167D01*
G01X1238700Y462083D02*
X1239033Y461750D01*
X1239500Y461500D01*
X1239900D01*
X1240300Y461667D01*
X1240567Y461917D01*
X1240700Y462250D01*
X1240633Y462750D01*
X1240367Y463000D01*
X1239167Y463500D01*
X1238900Y464083D01*
X1239033Y464500D01*
X1239300Y464750D01*
X1239700Y464833D01*
X1240100Y464750D01*
X1240500Y464500D01*
G01X1243667Y461500D02*
Y466500D01*
G01X1245800Y464833D02*
X1243667Y462917D01*
G01X1244533Y463667D02*
X1245933Y461500D01*
G01X1034100Y520500D02*
Y525500D01*
G01X1036900D02*
Y520500D01*
G01Y523000D02*
X1034100D01*
G01X1041800Y520500D02*
Y523833D01*
G01Y523250D02*
X1041533Y523583D01*
X1041133Y523750D01*
X1040667Y523833D01*
X1040200Y523667D01*
X1039800Y523333D01*
X1039533Y522833D01*
X1039400Y522167D01*
X1039533Y521500D01*
X1039800Y521000D01*
X1040200Y520667D01*
X1040667Y520500D01*
X1041133Y520583D01*
X1041533Y520833D01*
X1041800Y521167D01*
G01X1045700Y520500D02*
Y525500D01*
G01X1050400Y520500D02*
Y524750D01*
X1050533Y525167D01*
X1050800Y525417D01*
X1051200Y525500D01*
X1051600Y525333D01*
X1051800Y524917D01*
G01X1051000Y523500D02*
X1049667D01*
G01X1055033Y522167D02*
X1056767D01*
G01X1059800Y518833D02*
Y523833D01*
G01Y523083D02*
X1060133Y523500D01*
X1060467Y523750D01*
X1061000Y523833D01*
X1061467Y523750D01*
X1061933Y523333D01*
X1062133Y522750D01*
X1062200Y522167D01*
X1062133Y521583D01*
X1061933Y521000D01*
X1061533Y520667D01*
X1061000Y520500D01*
X1060533Y520583D01*
X1060067Y520833D01*
X1059800Y521167D01*
G01X1066100Y520500D02*
Y525500D01*
G01X1070067Y523833D02*
Y521500D01*
X1070333Y520917D01*
X1070733Y520583D01*
X1071200Y520500D01*
X1071667Y520583D01*
X1072067Y520917D01*
X1072333Y521500D01*
G01Y520500D02*
Y523833D01*
G01X1075367Y519250D02*
X1075833Y518917D01*
X1076367Y518833D01*
X1076833Y518917D01*
X1077233Y519333D01*
X1077500Y519917D01*
Y523833D01*
G01Y523167D02*
X1077233Y523500D01*
X1076833Y523750D01*
X1076367Y523833D01*
X1075833Y523667D01*
X1075500Y523333D01*
X1075233Y522750D01*
X1075100Y522167D01*
X1075167Y521667D01*
X1075433Y521083D01*
X1075833Y520667D01*
X1076367Y520500D01*
X1076767Y520583D01*
X1077233Y520917D01*
X1077500Y521250D01*
G01X1080467Y519250D02*
X1080933Y518917D01*
X1081467Y518833D01*
X1081933Y518917D01*
X1082333Y519333D01*
X1082600Y519917D01*
Y523833D01*
G01Y523167D02*
X1082333Y523500D01*
X1081933Y523750D01*
X1081467Y523833D01*
X1080933Y523667D01*
X1080600Y523333D01*
X1080333Y522750D01*
X1080200Y522167D01*
X1080267Y521667D01*
X1080533Y521083D01*
X1080933Y520667D01*
X1081467Y520500D01*
X1081867Y520583D01*
X1082333Y520917D01*
X1082600Y521250D01*
G01X1086500Y523833D02*
Y520500D01*
G01Y525167D02*
X1086367Y525250D01*
Y525417D01*
X1086500Y525500D01*
X1086633Y525417D01*
Y525250D01*
X1086500Y525167D01*
G01X1090467Y520500D02*
Y523833D01*
G01Y523000D02*
X1090733Y523417D01*
X1091133Y523750D01*
X1091667Y523833D01*
X1092133Y523750D01*
X1092533Y523417D01*
X1092733Y522833D01*
Y520500D01*
G01X1095767Y519250D02*
X1096233Y518917D01*
X1096767Y518833D01*
X1097233Y518917D01*
X1097633Y519333D01*
X1097900Y519917D01*
Y523833D01*
G01Y523167D02*
X1097633Y523500D01*
X1097233Y523750D01*
X1096767Y523833D01*
X1096233Y523667D01*
X1095900Y523333D01*
X1095633Y522750D01*
X1095500Y522167D01*
X1095567Y521667D01*
X1095833Y521083D01*
X1096233Y520667D01*
X1096767Y520500D01*
X1097167Y520583D01*
X1097633Y520917D01*
X1097900Y521250D01*
G01X1106900Y520333D02*
X1106767Y520417D01*
Y520583D01*
X1106900Y520667D01*
X1107033Y520583D01*
Y520417D01*
X1106900Y520333D01*
G01Y522583D02*
X1106767Y522667D01*
Y522833D01*
X1106900Y522917D01*
X1107033Y522833D01*
Y522667D01*
X1106900Y522583D01*
G01X1117100Y525500D02*
Y520500D01*
G01X1116167Y523833D02*
X1118033D01*
G01X1121067Y520500D02*
Y525500D01*
G01Y523083D02*
X1121400Y523500D01*
X1121733Y523750D01*
X1122267Y523833D01*
X1122667Y523750D01*
X1123133Y523417D01*
X1123333Y522917D01*
Y520500D01*
G01X1126300Y522750D02*
X1128433D01*
X1128233Y523333D01*
X1127900Y523667D01*
X1127433Y523833D01*
X1126967Y523750D01*
X1126567Y523500D01*
X1126300Y522917D01*
X1126167Y522417D01*
Y521917D01*
X1126300Y521417D01*
X1126633Y520917D01*
X1127033Y520583D01*
X1127500Y520500D01*
X1127967Y520667D01*
X1128433Y521167D01*
G01X1136300Y518833D02*
Y523833D01*
G01Y523083D02*
X1136633Y523500D01*
X1136967Y523750D01*
X1137500Y523833D01*
X1137967Y523750D01*
X1138433Y523333D01*
X1138633Y522750D01*
X1138700Y522167D01*
X1138633Y521583D01*
X1138433Y521000D01*
X1138033Y520667D01*
X1137500Y520500D01*
X1137033Y520583D01*
X1136567Y520833D01*
X1136300Y521167D01*
G01X1142600Y520500D02*
Y525500D01*
G01X1146567Y523833D02*
Y521500D01*
X1146833Y520917D01*
X1147233Y520583D01*
X1147700Y520500D01*
X1148167Y520583D01*
X1148567Y520917D01*
X1148833Y521500D01*
G01Y520500D02*
Y523833D01*
G01X1151867Y519250D02*
X1152333Y518917D01*
X1152867Y518833D01*
X1153333Y518917D01*
X1153733Y519333D01*
X1154000Y519917D01*
Y523833D01*
G01Y523167D02*
X1153733Y523500D01*
X1153333Y523750D01*
X1152867Y523833D01*
X1152333Y523667D01*
X1152000Y523333D01*
X1151733Y522750D01*
X1151600Y522167D01*
X1151667Y521667D01*
X1151933Y521083D01*
X1152333Y520667D01*
X1152867Y520500D01*
X1153267Y520583D01*
X1153733Y520917D01*
X1154000Y521250D01*
G01X1156967Y519250D02*
X1157433Y518917D01*
X1157967Y518833D01*
X1158433Y518917D01*
X1158833Y519333D01*
X1159100Y519917D01*
Y523833D01*
G01Y523167D02*
X1158833Y523500D01*
X1158433Y523750D01*
X1157967Y523833D01*
X1157433Y523667D01*
X1157100Y523333D01*
X1156833Y522750D01*
X1156700Y522167D01*
X1156767Y521667D01*
X1157033Y521083D01*
X1157433Y520667D01*
X1157967Y520500D01*
X1158367Y520583D01*
X1158833Y520917D01*
X1159100Y521250D01*
G01X1163000Y523833D02*
Y520500D01*
G01Y525167D02*
X1162867Y525250D01*
Y525417D01*
X1163000Y525500D01*
X1163133Y525417D01*
Y525250D01*
X1163000Y525167D01*
G01X1166967Y520500D02*
Y523833D01*
G01Y523000D02*
X1167233Y523417D01*
X1167633Y523750D01*
X1168167Y523833D01*
X1168633Y523750D01*
X1169033Y523417D01*
X1169233Y522833D01*
Y520500D01*
G01X1172267Y519250D02*
X1172733Y518917D01*
X1173267Y518833D01*
X1173733Y518917D01*
X1174133Y519333D01*
X1174400Y519917D01*
Y523833D01*
G01Y523167D02*
X1174133Y523500D01*
X1173733Y523750D01*
X1173267Y523833D01*
X1172733Y523667D01*
X1172400Y523333D01*
X1172133Y522750D01*
X1172000Y522167D01*
X1172067Y521667D01*
X1172333Y521083D01*
X1172733Y520667D01*
X1173267Y520500D01*
X1173667Y520583D01*
X1174133Y520917D01*
X1174400Y521250D01*
G01X1182467Y520500D02*
Y523833D01*
G01Y523167D02*
X1182800Y523500D01*
X1183133Y523750D01*
X1183600Y523833D01*
X1183933Y523750D01*
X1184333Y523500D01*
G01X1189700Y520500D02*
Y523833D01*
G01Y523250D02*
X1189433Y523583D01*
X1189033Y523750D01*
X1188567Y523833D01*
X1188100Y523667D01*
X1187700Y523333D01*
X1187433Y522833D01*
X1187300Y522167D01*
X1187433Y521500D01*
X1187700Y521000D01*
X1188100Y520667D01*
X1188567Y520500D01*
X1189033Y520583D01*
X1189433Y520833D01*
X1189700Y521167D01*
G01X1193600Y525500D02*
Y520500D01*
G01X1192667Y523833D02*
X1194533D01*
G01X1198700D02*
Y520500D01*
G01Y525167D02*
X1198567Y525250D01*
Y525417D01*
X1198700Y525500D01*
X1198833Y525417D01*
Y525250D01*
X1198700Y525167D01*
G01X1203800Y520500D02*
X1203400Y520583D01*
X1203000Y520917D01*
X1202733Y521500D01*
X1202600Y522167D01*
X1202733Y522833D01*
X1203000Y523417D01*
X1203400Y523750D01*
X1203800Y523833D01*
X1204200Y523750D01*
X1204600Y523417D01*
X1204867Y522833D01*
X1204933Y522167D01*
X1204867Y521500D01*
X1204600Y520917D01*
X1204200Y520583D01*
X1203800Y520500D01*
G01X1212800Y518833D02*
Y523833D01*
G01Y523083D02*
X1213133Y523500D01*
X1213467Y523750D01*
X1214000Y523833D01*
X1214467Y523750D01*
X1214933Y523333D01*
X1215133Y522750D01*
X1215200Y522167D01*
X1215133Y521583D01*
X1214933Y521000D01*
X1214533Y520667D01*
X1214000Y520500D01*
X1213533Y520583D01*
X1213067Y520833D01*
X1212800Y521167D01*
G01X1218100Y522750D02*
X1220233D01*
X1220033Y523333D01*
X1219700Y523667D01*
X1219233Y523833D01*
X1218767Y523750D01*
X1218367Y523500D01*
X1218100Y522917D01*
X1217967Y522417D01*
Y521917D01*
X1218100Y521417D01*
X1218433Y520917D01*
X1218833Y520583D01*
X1219300Y520500D01*
X1219767Y520667D01*
X1220233Y521167D01*
G01X1223267Y520500D02*
Y523833D01*
G01Y523167D02*
X1223600Y523500D01*
X1223933Y523750D01*
X1224400Y523833D01*
X1224733Y523750D01*
X1225133Y523500D01*
G01X1234000Y520500D02*
Y524750D01*
X1234133Y525167D01*
X1234400Y525417D01*
X1234800Y525500D01*
X1235200Y525333D01*
X1235400Y524917D01*
G01X1234600Y523500D02*
X1233267D01*
G01X1239500Y520500D02*
X1239100Y520583D01*
X1238700Y520917D01*
X1238433Y521500D01*
X1238300Y522167D01*
X1238433Y522833D01*
X1238700Y523417D01*
X1239100Y523750D01*
X1239500Y523833D01*
X1239900Y523750D01*
X1240300Y523417D01*
X1240567Y522833D01*
X1240633Y522167D01*
X1240567Y521500D01*
X1240300Y520917D01*
X1239900Y520583D01*
X1239500Y520500D01*
G01X1244600D02*
Y525500D01*
G01X1249700Y520500D02*
Y525500D01*
G01X1254800Y520500D02*
X1254400Y520583D01*
X1254000Y520917D01*
X1253733Y521500D01*
X1253600Y522167D01*
X1253733Y522833D01*
X1254000Y523417D01*
X1254400Y523750D01*
X1254800Y523833D01*
X1255200Y523750D01*
X1255600Y523417D01*
X1255867Y522833D01*
X1255933Y522167D01*
X1255867Y521500D01*
X1255600Y520917D01*
X1255200Y520583D01*
X1254800Y520500D01*
G01X1258233Y523833D02*
X1259033Y520500D01*
X1259900Y523833D01*
X1260767Y520500D01*
X1261567Y523833D01*
G01X1265000D02*
Y520500D01*
G01Y525167D02*
X1264867Y525250D01*
Y525417D01*
X1265000Y525500D01*
X1265133Y525417D01*
Y525250D01*
X1265000Y525167D01*
G01X1268967Y520500D02*
Y523833D01*
G01Y523000D02*
X1269233Y523417D01*
X1269633Y523750D01*
X1270167Y523833D01*
X1270633Y523750D01*
X1271033Y523417D01*
X1271233Y522833D01*
Y520500D01*
G01X1274267Y519250D02*
X1274733Y518917D01*
X1275267Y518833D01*
X1275733Y518917D01*
X1276133Y519333D01*
X1276400Y519917D01*
Y523833D01*
G01Y523167D02*
X1276133Y523500D01*
X1275733Y523750D01*
X1275267Y523833D01*
X1274733Y523667D01*
X1274400Y523333D01*
X1274133Y522750D01*
X1274000Y522167D01*
X1274067Y521667D01*
X1274333Y521083D01*
X1274733Y520667D01*
X1275267Y520500D01*
X1275667Y520583D01*
X1276133Y520917D01*
X1276400Y521250D01*
G01X1280300Y520333D02*
X1280167Y520417D01*
Y520583D01*
X1280300Y520667D01*
X1280433Y520583D01*
Y520417D01*
X1280300Y520333D01*
G01Y522583D02*
X1280167Y522667D01*
Y522833D01*
X1280300Y522917D01*
X1280433Y522833D01*
Y522667D01*
X1280300Y522583D01*
G01X1033300Y529500D02*
Y534500D01*
G01Y532000D02*
X1033633Y532500D01*
X1034033Y532750D01*
X1034433Y532833D01*
X1035033Y532667D01*
X1035433Y532333D01*
X1035700Y531750D01*
Y531083D01*
X1035567Y530417D01*
X1035300Y529917D01*
X1034833Y529583D01*
X1034433Y529500D01*
X1034033Y529583D01*
X1033633Y529833D01*
X1033300Y530250D01*
G01X1038600Y531750D02*
X1040733D01*
X1040533Y532333D01*
X1040200Y532667D01*
X1039733Y532833D01*
X1039267Y532750D01*
X1038867Y532500D01*
X1038600Y531917D01*
X1038467Y531417D01*
Y530917D01*
X1038600Y530417D01*
X1038933Y529917D01*
X1039333Y529583D01*
X1039800Y529500D01*
X1040267Y529667D01*
X1040733Y530167D01*
G01X1049400Y529500D02*
Y533750D01*
X1049533Y534167D01*
X1049800Y534417D01*
X1050200Y534500D01*
X1050600Y534333D01*
X1050800Y533917D01*
G01X1050000Y532500D02*
X1048667D01*
G01X1053967Y529500D02*
Y532833D01*
G01Y532167D02*
X1054300Y532500D01*
X1054633Y532750D01*
X1055100Y532833D01*
X1055433Y532750D01*
X1055833Y532500D01*
G01X1059000Y531750D02*
X1061133D01*
X1060933Y532333D01*
X1060600Y532667D01*
X1060133Y532833D01*
X1059667Y532750D01*
X1059267Y532500D01*
X1059000Y531917D01*
X1058867Y531417D01*
Y530917D01*
X1059000Y530417D01*
X1059333Y529917D01*
X1059733Y529583D01*
X1060200Y529500D01*
X1060667Y529667D01*
X1061133Y530167D01*
G01X1064100Y531750D02*
X1066233D01*
X1066033Y532333D01*
X1065700Y532667D01*
X1065233Y532833D01*
X1064767Y532750D01*
X1064367Y532500D01*
X1064100Y531917D01*
X1063967Y531417D01*
Y530917D01*
X1064100Y530417D01*
X1064433Y529917D01*
X1064833Y529583D01*
X1065300Y529500D01*
X1065767Y529667D01*
X1066233Y530167D01*
G01X1074900Y529500D02*
Y533750D01*
X1075033Y534167D01*
X1075300Y534417D01*
X1075700Y534500D01*
X1076100Y534333D01*
X1076300Y533917D01*
G01X1075500Y532500D02*
X1074167D01*
G01X1079467Y529500D02*
Y532833D01*
G01Y532167D02*
X1079800Y532500D01*
X1080133Y532750D01*
X1080600Y532833D01*
X1080933Y532750D01*
X1081333Y532500D01*
G01X1085500Y529500D02*
X1085100Y529583D01*
X1084700Y529917D01*
X1084433Y530500D01*
X1084300Y531167D01*
X1084433Y531833D01*
X1084700Y532417D01*
X1085100Y532750D01*
X1085500Y532833D01*
X1085900Y532750D01*
X1086300Y532417D01*
X1086567Y531833D01*
X1086633Y531167D01*
X1086567Y530500D01*
X1086300Y529917D01*
X1085900Y529583D01*
X1085500Y529500D01*
G01X1088600D02*
Y532833D01*
G01Y531917D02*
X1088800Y532333D01*
X1089133Y532667D01*
X1089600Y532833D01*
X1090067Y532667D01*
X1090400Y532333D01*
X1090600Y531917D01*
Y529500D01*
G01Y531917D02*
X1090800Y532333D01*
X1091133Y532667D01*
X1091600Y532833D01*
X1092067Y532667D01*
X1092400Y532333D01*
X1092600Y531833D01*
Y529500D01*
G01X1099800Y530083D02*
X1100133Y529750D01*
X1100600Y529500D01*
X1101000D01*
X1101400Y529667D01*
X1101667Y529917D01*
X1101800Y530250D01*
X1101733Y530750D01*
X1101467Y531000D01*
X1100267Y531500D01*
X1100000Y532083D01*
X1100133Y532500D01*
X1100400Y532750D01*
X1100800Y532833D01*
X1101200Y532750D01*
X1101600Y532500D01*
G01X1105900Y529500D02*
X1105500Y529583D01*
X1105100Y529917D01*
X1104833Y530500D01*
X1104700Y531167D01*
X1104833Y531833D01*
X1105100Y532417D01*
X1105500Y532750D01*
X1105900Y532833D01*
X1106300Y532750D01*
X1106700Y532417D01*
X1106967Y531833D01*
X1107033Y531167D01*
X1106967Y530500D01*
X1106700Y529917D01*
X1106300Y529583D01*
X1105900Y529500D01*
G01X1111000D02*
Y534500D01*
G01X1117300D02*
Y529500D01*
G01Y530250D02*
X1117033Y529833D01*
X1116633Y529583D01*
X1116167Y529500D01*
X1115633Y529667D01*
X1115233Y530083D01*
X1114967Y530583D01*
X1114900Y531167D01*
X1114967Y531750D01*
X1115233Y532250D01*
X1115633Y532667D01*
X1116167Y532833D01*
X1116633Y532750D01*
X1116967Y532583D01*
X1117300Y532250D01*
G01X1120200Y531750D02*
X1122333D01*
X1122133Y532333D01*
X1121800Y532667D01*
X1121333Y532833D01*
X1120867Y532750D01*
X1120467Y532500D01*
X1120200Y531917D01*
X1120067Y531417D01*
Y530917D01*
X1120200Y530417D01*
X1120533Y529917D01*
X1120933Y529583D01*
X1121400Y529500D01*
X1121867Y529667D01*
X1122333Y530167D01*
G01X1125367Y529500D02*
Y532833D01*
G01Y532167D02*
X1125700Y532500D01*
X1126033Y532750D01*
X1126500Y532833D01*
X1126833Y532750D01*
X1127233Y532500D01*
G01X1134500Y529500D02*
Y532833D01*
G01Y531917D02*
X1134700Y532333D01*
X1135033Y532667D01*
X1135500Y532833D01*
X1135967Y532667D01*
X1136300Y532333D01*
X1136500Y531917D01*
Y529500D01*
G01Y531917D02*
X1136700Y532333D01*
X1137033Y532667D01*
X1137500Y532833D01*
X1137967Y532667D01*
X1138300Y532333D01*
X1138500Y531833D01*
Y529500D01*
G01X1142800D02*
Y532833D01*
G01Y532250D02*
X1142533Y532583D01*
X1142133Y532750D01*
X1141667Y532833D01*
X1141200Y532667D01*
X1140800Y532333D01*
X1140533Y531833D01*
X1140400Y531167D01*
X1140533Y530500D01*
X1140800Y530000D01*
X1141200Y529667D01*
X1141667Y529500D01*
X1142133Y529583D01*
X1142533Y529833D01*
X1142800Y530167D01*
G01X1145700Y530083D02*
X1146033Y529750D01*
X1146500Y529500D01*
X1146900D01*
X1147300Y529667D01*
X1147567Y529917D01*
X1147700Y530250D01*
X1147633Y530750D01*
X1147367Y531000D01*
X1146167Y531500D01*
X1145900Y532083D01*
X1146033Y532500D01*
X1146300Y532750D01*
X1146700Y532833D01*
X1147100Y532750D01*
X1147500Y532500D01*
G01X1150667Y529500D02*
Y534500D01*
G01X1152800Y532833D02*
X1150667Y530917D01*
G01X1151533Y531667D02*
X1152933Y529500D01*
G01X1156900Y529333D02*
X1156767Y529417D01*
Y529583D01*
X1156900Y529667D01*
X1157033Y529583D01*
Y529417D01*
X1156900Y529333D01*
G01X1020233Y542667D02*
X1020633Y543167D01*
X1021100Y543417D01*
X1021633Y543500D01*
X1022300Y543333D01*
X1022767Y542917D01*
X1022900Y542417D01*
X1022833Y541917D01*
X1022567Y541500D01*
X1021233Y540667D01*
X1020633Y540083D01*
X1020233Y539250D01*
X1020100Y538500D01*
X1022900D01*
G01X1026600Y538333D02*
X1026467Y538417D01*
Y538583D01*
X1026600Y538667D01*
X1026733Y538583D01*
Y538417D01*
X1026600Y538333D01*
G01X1031700Y543500D02*
Y538500D01*
G01X1030167Y543500D02*
X1033233D01*
G01X1035667Y538500D02*
Y543500D01*
G01Y541083D02*
X1036000Y541500D01*
X1036333Y541750D01*
X1036867Y541833D01*
X1037267Y541750D01*
X1037733Y541417D01*
X1037933Y540917D01*
Y538500D01*
G01X1040900Y540750D02*
X1043033D01*
X1042833Y541333D01*
X1042500Y541667D01*
X1042033Y541833D01*
X1041567Y541750D01*
X1041167Y541500D01*
X1040900Y540917D01*
X1040767Y540417D01*
Y539917D01*
X1040900Y539417D01*
X1041233Y538917D01*
X1041633Y538583D01*
X1042100Y538500D01*
X1042567Y538667D01*
X1043033Y539167D01*
G01X1051100Y539083D02*
X1051433Y538750D01*
X1051900Y538500D01*
X1052300D01*
X1052700Y538667D01*
X1052967Y538917D01*
X1053100Y539250D01*
X1053033Y539750D01*
X1052767Y540000D01*
X1051567Y540500D01*
X1051300Y541083D01*
X1051433Y541500D01*
X1051700Y541750D01*
X1052100Y541833D01*
X1052500Y541750D01*
X1052900Y541500D01*
G01X1057200Y541833D02*
Y538500D01*
G01Y543167D02*
X1057067Y543250D01*
Y543417D01*
X1057200Y543500D01*
X1057333Y543417D01*
Y543250D01*
X1057200Y543167D01*
G01X1063500Y543500D02*
Y538500D01*
G01Y539250D02*
X1063233Y538833D01*
X1062833Y538583D01*
X1062367Y538500D01*
X1061833Y538667D01*
X1061433Y539083D01*
X1061167Y539583D01*
X1061100Y540167D01*
X1061167Y540750D01*
X1061433Y541250D01*
X1061833Y541667D01*
X1062367Y541833D01*
X1062833Y541750D01*
X1063167Y541583D01*
X1063500Y541250D01*
G01X1066400Y540750D02*
X1068533D01*
X1068333Y541333D01*
X1068000Y541667D01*
X1067533Y541833D01*
X1067067Y541750D01*
X1066667Y541500D01*
X1066400Y540917D01*
X1066267Y540417D01*
Y539917D01*
X1066400Y539417D01*
X1066733Y538917D01*
X1067133Y538583D01*
X1067600Y538500D01*
X1068067Y538667D01*
X1068533Y539167D01*
G01X1075933Y541833D02*
X1076733Y538500D01*
X1077600Y541833D01*
X1078467Y538500D01*
X1079267Y541833D01*
G01X1082700D02*
Y538500D01*
G01Y543167D02*
X1082567Y543250D01*
Y543417D01*
X1082700Y543500D01*
X1082833Y543417D01*
Y543250D01*
X1082700Y543167D01*
G01X1087800Y543500D02*
Y538500D01*
G01X1086867Y541833D02*
X1088733D01*
G01X1091767Y538500D02*
Y543500D01*
G01Y541083D02*
X1092100Y541500D01*
X1092433Y541750D01*
X1092967Y541833D01*
X1093367Y541750D01*
X1093833Y541417D01*
X1094033Y540917D01*
Y538500D01*
G01X1102100Y539083D02*
X1102433Y538750D01*
X1102900Y538500D01*
X1103300D01*
X1103700Y538667D01*
X1103967Y538917D01*
X1104100Y539250D01*
X1104033Y539750D01*
X1103767Y540000D01*
X1102567Y540500D01*
X1102300Y541083D01*
X1102433Y541500D01*
X1102700Y541750D01*
X1103100Y541833D01*
X1103500Y541750D01*
X1103900Y541500D01*
G01X1108200Y538500D02*
X1107800Y538583D01*
X1107400Y538917D01*
X1107133Y539500D01*
X1107000Y540167D01*
X1107133Y540833D01*
X1107400Y541417D01*
X1107800Y541750D01*
X1108200Y541833D01*
X1108600Y541750D01*
X1109000Y541417D01*
X1109267Y540833D01*
X1109333Y540167D01*
X1109267Y539500D01*
X1109000Y538917D01*
X1108600Y538583D01*
X1108200Y538500D01*
G01X1113300D02*
Y543500D01*
G01X1119600D02*
Y538500D01*
G01Y539250D02*
X1119333Y538833D01*
X1118933Y538583D01*
X1118467Y538500D01*
X1117933Y538667D01*
X1117533Y539083D01*
X1117267Y539583D01*
X1117200Y540167D01*
X1117267Y540750D01*
X1117533Y541250D01*
X1117933Y541667D01*
X1118467Y541833D01*
X1118933Y541750D01*
X1119267Y541583D01*
X1119600Y541250D01*
G01X1122500Y540750D02*
X1124633D01*
X1124433Y541333D01*
X1124100Y541667D01*
X1123633Y541833D01*
X1123167Y541750D01*
X1122767Y541500D01*
X1122500Y540917D01*
X1122367Y540417D01*
Y539917D01*
X1122500Y539417D01*
X1122833Y538917D01*
X1123233Y538583D01*
X1123700Y538500D01*
X1124167Y538667D01*
X1124633Y539167D01*
G01X1127667Y538500D02*
Y541833D01*
G01Y541167D02*
X1128000Y541500D01*
X1128333Y541750D01*
X1128800Y541833D01*
X1129133Y541750D01*
X1129533Y541500D01*
G01X1136800Y538500D02*
Y541833D01*
G01Y540917D02*
X1137000Y541333D01*
X1137333Y541667D01*
X1137800Y541833D01*
X1138267Y541667D01*
X1138600Y541333D01*
X1138800Y540917D01*
Y538500D01*
G01Y540917D02*
X1139000Y541333D01*
X1139333Y541667D01*
X1139800Y541833D01*
X1140267Y541667D01*
X1140600Y541333D01*
X1140800Y540833D01*
Y538500D01*
G01X1145100D02*
Y541833D01*
G01Y541250D02*
X1144833Y541583D01*
X1144433Y541750D01*
X1143967Y541833D01*
X1143500Y541667D01*
X1143100Y541333D01*
X1142833Y540833D01*
X1142700Y540167D01*
X1142833Y539500D01*
X1143100Y539000D01*
X1143500Y538667D01*
X1143967Y538500D01*
X1144433Y538583D01*
X1144833Y538833D01*
X1145100Y539167D01*
G01X1148000Y539083D02*
X1148333Y538750D01*
X1148800Y538500D01*
X1149200D01*
X1149600Y538667D01*
X1149867Y538917D01*
X1150000Y539250D01*
X1149933Y539750D01*
X1149667Y540000D01*
X1148467Y540500D01*
X1148200Y541083D01*
X1148333Y541500D01*
X1148600Y541750D01*
X1149000Y541833D01*
X1149400Y541750D01*
X1149800Y541500D01*
G01X1152967Y538500D02*
Y543500D01*
G01X1155100Y541833D02*
X1152967Y539917D01*
G01X1153833Y540667D02*
X1155233Y538500D01*
G01X1163100Y536833D02*
Y541833D01*
G01Y541083D02*
X1163433Y541500D01*
X1163767Y541750D01*
X1164300Y541833D01*
X1164767Y541750D01*
X1165233Y541333D01*
X1165433Y540750D01*
X1165500Y540167D01*
X1165433Y539583D01*
X1165233Y539000D01*
X1164833Y538667D01*
X1164300Y538500D01*
X1163833Y538583D01*
X1163367Y538833D01*
X1163100Y539167D01*
G01X1170600Y538500D02*
Y541833D01*
G01Y541250D02*
X1170333Y541583D01*
X1169933Y541750D01*
X1169467Y541833D01*
X1169000Y541667D01*
X1168600Y541333D01*
X1168333Y540833D01*
X1168200Y540167D01*
X1168333Y539500D01*
X1168600Y539000D01*
X1169000Y538667D01*
X1169467Y538500D01*
X1169933Y538583D01*
X1170333Y538833D01*
X1170600Y539167D01*
G01X1175700Y543500D02*
Y538500D01*
G01Y539250D02*
X1175433Y538833D01*
X1175033Y538583D01*
X1174567Y538500D01*
X1174033Y538667D01*
X1173633Y539083D01*
X1173367Y539583D01*
X1173300Y540167D01*
X1173367Y540750D01*
X1173633Y541250D01*
X1174033Y541667D01*
X1174567Y541833D01*
X1175033Y541750D01*
X1175367Y541583D01*
X1175700Y541250D01*
G01X1179467Y537583D02*
X1179733Y538667D01*
G01X1189800Y543500D02*
Y538500D01*
G01X1188867Y541833D02*
X1190733D01*
G01X1193767Y538500D02*
Y543500D01*
G01Y541083D02*
X1194100Y541500D01*
X1194433Y541750D01*
X1194967Y541833D01*
X1195367Y541750D01*
X1195833Y541417D01*
X1196033Y540917D01*
Y538500D01*
G01X1199000Y540750D02*
X1201133D01*
X1200933Y541333D01*
X1200600Y541667D01*
X1200133Y541833D01*
X1199667Y541750D01*
X1199267Y541500D01*
X1199000Y540917D01*
X1198867Y540417D01*
Y539917D01*
X1199000Y539417D01*
X1199333Y538917D01*
X1199733Y538583D01*
X1200200Y538500D01*
X1200667Y538667D01*
X1201133Y539167D01*
G01X1211400Y538500D02*
Y541833D01*
G01Y541250D02*
X1211133Y541583D01*
X1210733Y541750D01*
X1210267Y541833D01*
X1209800Y541667D01*
X1209400Y541333D01*
X1209133Y540833D01*
X1209000Y540167D01*
X1209133Y539500D01*
X1209400Y539000D01*
X1209800Y538667D01*
X1210267Y538500D01*
X1210733Y538583D01*
X1211133Y538833D01*
X1211400Y539167D01*
G01X1214167Y538500D02*
Y541833D01*
G01Y541000D02*
X1214433Y541417D01*
X1214833Y541750D01*
X1215367Y541833D01*
X1215833Y541750D01*
X1216233Y541417D01*
X1216433Y540833D01*
Y538500D01*
G01X1219267D02*
Y541833D01*
G01Y541000D02*
X1219533Y541417D01*
X1219933Y541750D01*
X1220467Y541833D01*
X1220933Y541750D01*
X1221333Y541417D01*
X1221533Y540833D01*
Y538500D01*
G01X1224367Y541833D02*
Y539500D01*
X1224633Y538917D01*
X1225033Y538583D01*
X1225500Y538500D01*
X1225967Y538583D01*
X1226367Y538917D01*
X1226633Y539500D01*
G01Y538500D02*
Y541833D01*
G01X1231800Y538500D02*
Y541833D01*
G01Y541250D02*
X1231533Y541583D01*
X1231133Y541750D01*
X1230667Y541833D01*
X1230200Y541667D01*
X1229800Y541333D01*
X1229533Y540833D01*
X1229400Y540167D01*
X1229533Y539500D01*
X1229800Y539000D01*
X1230200Y538667D01*
X1230667Y538500D01*
X1231133Y538583D01*
X1231533Y538833D01*
X1231800Y539167D01*
G01X1235700Y538500D02*
Y543500D01*
G01X1244967Y538500D02*
Y541833D01*
G01Y541167D02*
X1245300Y541500D01*
X1245633Y541750D01*
X1246100Y541833D01*
X1246433Y541750D01*
X1246833Y541500D01*
G01X1251000Y541833D02*
Y538500D01*
G01Y543167D02*
X1250867Y543250D01*
Y543417D01*
X1251000Y543500D01*
X1251133Y543417D01*
Y543250D01*
X1251000Y543167D01*
G01X1254967Y538500D02*
Y541833D01*
G01Y541000D02*
X1255233Y541417D01*
X1255633Y541750D01*
X1256167Y541833D01*
X1256633Y541750D01*
X1257033Y541417D01*
X1257233Y540833D01*
Y538500D01*
G01X1260267Y537250D02*
X1260733Y536917D01*
X1261267Y536833D01*
X1261733Y536917D01*
X1262133Y537333D01*
X1262400Y537917D01*
Y541833D01*
G01Y541167D02*
X1262133Y541500D01*
X1261733Y541750D01*
X1261267Y541833D01*
X1260733Y541667D01*
X1260400Y541333D01*
X1260133Y540750D01*
X1260000Y540167D01*
X1260067Y539667D01*
X1260333Y539083D01*
X1260733Y538667D01*
X1261267Y538500D01*
X1261667Y538583D01*
X1262133Y538917D01*
X1262400Y539250D01*
G01X1270400Y539083D02*
X1270733Y538750D01*
X1271200Y538500D01*
X1271600D01*
X1272000Y538667D01*
X1272267Y538917D01*
X1272400Y539250D01*
X1272333Y539750D01*
X1272067Y540000D01*
X1270867Y540500D01*
X1270600Y541083D01*
X1270733Y541500D01*
X1271000Y541750D01*
X1271400Y541833D01*
X1271800Y541750D01*
X1272200Y541500D01*
G01X1275367Y538500D02*
Y543500D01*
G01Y541083D02*
X1275700Y541500D01*
X1276033Y541750D01*
X1276567Y541833D01*
X1276967Y541750D01*
X1277433Y541417D01*
X1277633Y540917D01*
Y538500D01*
G01X1281600D02*
X1281200Y538583D01*
X1280800Y538917D01*
X1280533Y539500D01*
X1280400Y540167D01*
X1280533Y540833D01*
X1280800Y541417D01*
X1281200Y541750D01*
X1281600Y541833D01*
X1282000Y541750D01*
X1282400Y541417D01*
X1282667Y540833D01*
X1282733Y540167D01*
X1282667Y539500D01*
X1282400Y538917D01*
X1282000Y538583D01*
X1281600Y538500D01*
G01X1285567Y541833D02*
Y539500D01*
X1285833Y538917D01*
X1286233Y538583D01*
X1286700Y538500D01*
X1287167Y538583D01*
X1287567Y538917D01*
X1287833Y539500D01*
G01Y538500D02*
Y541833D01*
G01X1291800Y538500D02*
Y543500D01*
G01X1298100D02*
Y538500D01*
G01Y539250D02*
X1297833Y538833D01*
X1297433Y538583D01*
X1296967Y538500D01*
X1296433Y538667D01*
X1296033Y539083D01*
X1295767Y539583D01*
X1295700Y540167D01*
X1295767Y540750D01*
X1296033Y541250D01*
X1296433Y541667D01*
X1296967Y541833D01*
X1297433Y541750D01*
X1297767Y541583D01*
X1298100Y541250D01*
G01X1032300Y552500D02*
Y557500D01*
G01Y555000D02*
X1032633Y555500D01*
X1033033Y555750D01*
X1033433Y555833D01*
X1034033Y555667D01*
X1034433Y555333D01*
X1034700Y554750D01*
Y554083D01*
X1034567Y553417D01*
X1034300Y552917D01*
X1033833Y552583D01*
X1033433Y552500D01*
X1033033Y552583D01*
X1032633Y552833D01*
X1032300Y553250D01*
G01X1037600Y554750D02*
X1039733D01*
X1039533Y555333D01*
X1039200Y555667D01*
X1038733Y555833D01*
X1038267Y555750D01*
X1037867Y555500D01*
X1037600Y554917D01*
X1037467Y554417D01*
Y553917D01*
X1037600Y553417D01*
X1037933Y552917D01*
X1038333Y552583D01*
X1038800Y552500D01*
X1039267Y552667D01*
X1039733Y553167D01*
G01X1048800Y557500D02*
Y552500D01*
G01X1047867Y555833D02*
X1049733D01*
G01X1052900Y554750D02*
X1055033D01*
X1054833Y555333D01*
X1054500Y555667D01*
X1054033Y555833D01*
X1053567Y555750D01*
X1053167Y555500D01*
X1052900Y554917D01*
X1052767Y554417D01*
Y553917D01*
X1052900Y553417D01*
X1053233Y552917D01*
X1053633Y552583D01*
X1054100Y552500D01*
X1054567Y552667D01*
X1055033Y553167D01*
G01X1057867Y552500D02*
Y555833D01*
G01Y555000D02*
X1058133Y555417D01*
X1058533Y555750D01*
X1059067Y555833D01*
X1059533Y555750D01*
X1059933Y555417D01*
X1060133Y554833D01*
Y552500D01*
G01X1064100Y557500D02*
Y552500D01*
G01X1063167Y555833D02*
X1065033D01*
G01X1068200Y554750D02*
X1070333D01*
X1070133Y555333D01*
X1069800Y555667D01*
X1069333Y555833D01*
X1068867Y555750D01*
X1068467Y555500D01*
X1068200Y554917D01*
X1068067Y554417D01*
Y553917D01*
X1068200Y553417D01*
X1068533Y552917D01*
X1068933Y552583D01*
X1069400Y552500D01*
X1069867Y552667D01*
X1070333Y553167D01*
G01X1075500Y557500D02*
Y552500D01*
G01Y553250D02*
X1075233Y552833D01*
X1074833Y552583D01*
X1074367Y552500D01*
X1073833Y552667D01*
X1073433Y553083D01*
X1073167Y553583D01*
X1073100Y554167D01*
X1073167Y554750D01*
X1073433Y555250D01*
X1073833Y555667D01*
X1074367Y555833D01*
X1074833Y555750D01*
X1075167Y555583D01*
X1075500Y555250D01*
G01X1082833Y555833D02*
X1083633Y552500D01*
X1084500Y555833D01*
X1085367Y552500D01*
X1086167Y555833D01*
G01X1089600D02*
Y552500D01*
G01Y557167D02*
X1089467Y557250D01*
Y557417D01*
X1089600Y557500D01*
X1089733Y557417D01*
Y557250D01*
X1089600Y557167D01*
G01X1094700Y557500D02*
Y552500D01*
G01X1093767Y555833D02*
X1095633D01*
G01X1098667Y552500D02*
Y557500D01*
G01Y555083D02*
X1099000Y555500D01*
X1099333Y555750D01*
X1099867Y555833D01*
X1100267Y555750D01*
X1100733Y555417D01*
X1100933Y554917D01*
Y552500D01*
G01X1109000Y553083D02*
X1109333Y552750D01*
X1109800Y552500D01*
X1110200D01*
X1110600Y552667D01*
X1110867Y552917D01*
X1111000Y553250D01*
X1110933Y553750D01*
X1110667Y554000D01*
X1109467Y554500D01*
X1109200Y555083D01*
X1109333Y555500D01*
X1109600Y555750D01*
X1110000Y555833D01*
X1110400Y555750D01*
X1110800Y555500D01*
G01X1115100Y552500D02*
X1114700Y552583D01*
X1114300Y552917D01*
X1114033Y553500D01*
X1113900Y554167D01*
X1114033Y554833D01*
X1114300Y555417D01*
X1114700Y555750D01*
X1115100Y555833D01*
X1115500Y555750D01*
X1115900Y555417D01*
X1116167Y554833D01*
X1116233Y554167D01*
X1116167Y553500D01*
X1115900Y552917D01*
X1115500Y552583D01*
X1115100Y552500D01*
G01X1120200D02*
Y557500D01*
G01X1126500D02*
Y552500D01*
G01Y553250D02*
X1126233Y552833D01*
X1125833Y552583D01*
X1125367Y552500D01*
X1124833Y552667D01*
X1124433Y553083D01*
X1124167Y553583D01*
X1124100Y554167D01*
X1124167Y554750D01*
X1124433Y555250D01*
X1124833Y555667D01*
X1125367Y555833D01*
X1125833Y555750D01*
X1126167Y555583D01*
X1126500Y555250D01*
G01X1129400Y554750D02*
X1131533D01*
X1131333Y555333D01*
X1131000Y555667D01*
X1130533Y555833D01*
X1130067Y555750D01*
X1129667Y555500D01*
X1129400Y554917D01*
X1129267Y554417D01*
Y553917D01*
X1129400Y553417D01*
X1129733Y552917D01*
X1130133Y552583D01*
X1130600Y552500D01*
X1131067Y552667D01*
X1131533Y553167D01*
G01X1134567Y552500D02*
Y555833D01*
G01Y555167D02*
X1134900Y555500D01*
X1135233Y555750D01*
X1135700Y555833D01*
X1136033Y555750D01*
X1136433Y555500D01*
G01X1143700Y552500D02*
Y555833D01*
G01Y554917D02*
X1143900Y555333D01*
X1144233Y555667D01*
X1144700Y555833D01*
X1145167Y555667D01*
X1145500Y555333D01*
X1145700Y554917D01*
Y552500D01*
G01Y554917D02*
X1145900Y555333D01*
X1146233Y555667D01*
X1146700Y555833D01*
X1147167Y555667D01*
X1147500Y555333D01*
X1147700Y554833D01*
Y552500D01*
G01X1152000D02*
Y555833D01*
G01Y555250D02*
X1151733Y555583D01*
X1151333Y555750D01*
X1150867Y555833D01*
X1150400Y555667D01*
X1150000Y555333D01*
X1149733Y554833D01*
X1149600Y554167D01*
X1149733Y553500D01*
X1150000Y553000D01*
X1150400Y552667D01*
X1150867Y552500D01*
X1151333Y552583D01*
X1151733Y552833D01*
X1152000Y553167D01*
G01X1154900Y553083D02*
X1155233Y552750D01*
X1155700Y552500D01*
X1156100D01*
X1156500Y552667D01*
X1156767Y552917D01*
X1156900Y553250D01*
X1156833Y553750D01*
X1156567Y554000D01*
X1155367Y554500D01*
X1155100Y555083D01*
X1155233Y555500D01*
X1155500Y555750D01*
X1155900Y555833D01*
X1156300Y555750D01*
X1156700Y555500D01*
G01X1159867Y552500D02*
Y557500D01*
G01X1162000Y555833D02*
X1159867Y553917D01*
G01X1160733Y554667D02*
X1162133Y552500D01*
G01X1166100Y552333D02*
X1165967Y552417D01*
Y552583D01*
X1166100Y552667D01*
X1166233Y552583D01*
Y552417D01*
X1166100Y552333D01*
G01X1033500Y566500D02*
Y561500D01*
G01X1032567Y564833D02*
X1034433D01*
G01X1038600Y561500D02*
X1038200Y561583D01*
X1037800Y561917D01*
X1037533Y562500D01*
X1037400Y563167D01*
X1037533Y563833D01*
X1037800Y564417D01*
X1038200Y564750D01*
X1038600Y564833D01*
X1039000Y564750D01*
X1039400Y564417D01*
X1039667Y563833D01*
X1039733Y563167D01*
X1039667Y562500D01*
X1039400Y561917D01*
X1039000Y561583D01*
X1038600Y561500D01*
G01X1047600D02*
Y566500D01*
G01Y564000D02*
X1047933Y564500D01*
X1048333Y564750D01*
X1048733Y564833D01*
X1049333Y564667D01*
X1049733Y564333D01*
X1050000Y563750D01*
Y563083D01*
X1049867Y562417D01*
X1049600Y561917D01*
X1049133Y561583D01*
X1048733Y561500D01*
X1048333Y561583D01*
X1047933Y561833D01*
X1047600Y562250D01*
G01X1052900Y563750D02*
X1055033D01*
X1054833Y564333D01*
X1054500Y564667D01*
X1054033Y564833D01*
X1053567Y564750D01*
X1053167Y564500D01*
X1052900Y563917D01*
X1052767Y563417D01*
Y562917D01*
X1052900Y562417D01*
X1053233Y561917D01*
X1053633Y561583D01*
X1054100Y561500D01*
X1054567Y561667D01*
X1055033Y562167D01*
G01X1065167Y564417D02*
X1064700Y564750D01*
X1064300Y564833D01*
X1063767Y564667D01*
X1063367Y564333D01*
X1063100Y563750D01*
X1063033Y563167D01*
X1063100Y562583D01*
X1063367Y562083D01*
X1063767Y561667D01*
X1064300Y561500D01*
X1064767Y561667D01*
X1065167Y562000D01*
G01X1069200Y561500D02*
X1068800Y561583D01*
X1068400Y561917D01*
X1068133Y562500D01*
X1068000Y563167D01*
X1068133Y563833D01*
X1068400Y564417D01*
X1068800Y564750D01*
X1069200Y564833D01*
X1069600Y564750D01*
X1070000Y564417D01*
X1070267Y563833D01*
X1070333Y563167D01*
X1070267Y562500D01*
X1070000Y561917D01*
X1069600Y561583D01*
X1069200Y561500D01*
G01X1073100Y564833D02*
X1074300Y561500D01*
X1075500Y564833D01*
G01X1078400Y563750D02*
X1080533D01*
X1080333Y564333D01*
X1080000Y564667D01*
X1079533Y564833D01*
X1079067Y564750D01*
X1078667Y564500D01*
X1078400Y563917D01*
X1078267Y563417D01*
Y562917D01*
X1078400Y562417D01*
X1078733Y561917D01*
X1079133Y561583D01*
X1079600Y561500D01*
X1080067Y561667D01*
X1080533Y562167D01*
G01X1083567Y561500D02*
Y564833D01*
G01Y564167D02*
X1083900Y564500D01*
X1084233Y564750D01*
X1084700Y564833D01*
X1085033Y564750D01*
X1085433Y564500D01*
G01X1088600Y563750D02*
X1090733D01*
X1090533Y564333D01*
X1090200Y564667D01*
X1089733Y564833D01*
X1089267Y564750D01*
X1088867Y564500D01*
X1088600Y563917D01*
X1088467Y563417D01*
Y562917D01*
X1088600Y562417D01*
X1088933Y561917D01*
X1089333Y561583D01*
X1089800Y561500D01*
X1090267Y561667D01*
X1090733Y562167D01*
G01X1095900Y566500D02*
Y561500D01*
G01Y562250D02*
X1095633Y561833D01*
X1095233Y561583D01*
X1094767Y561500D01*
X1094233Y561667D01*
X1093833Y562083D01*
X1093567Y562583D01*
X1093500Y563167D01*
X1093567Y563750D01*
X1093833Y564250D01*
X1094233Y564667D01*
X1094767Y564833D01*
X1095233Y564750D01*
X1095567Y564583D01*
X1095900Y564250D01*
G01X1103700Y561500D02*
Y566500D01*
G01Y564000D02*
X1104033Y564500D01*
X1104433Y564750D01*
X1104833Y564833D01*
X1105433Y564667D01*
X1105833Y564333D01*
X1106100Y563750D01*
Y563083D01*
X1105967Y562417D01*
X1105700Y561917D01*
X1105233Y561583D01*
X1104833Y561500D01*
X1104433Y561583D01*
X1104033Y561833D01*
X1103700Y562250D01*
G01X1108600Y560000D02*
X1109000Y559833D01*
X1109533Y560000D01*
X1109867Y560333D01*
X1110133Y560750D01*
X1110533Y562083D01*
X1111400Y564833D01*
G01X1109267D02*
X1110533Y562083D01*
G01X1119200D02*
X1119533Y561750D01*
X1120000Y561500D01*
X1120400D01*
X1120800Y561667D01*
X1121067Y561917D01*
X1121200Y562250D01*
X1121133Y562750D01*
X1120867Y563000D01*
X1119667Y563500D01*
X1119400Y564083D01*
X1119533Y564500D01*
X1119800Y564750D01*
X1120200Y564833D01*
X1120600Y564750D01*
X1121000Y564500D01*
G01X1125300Y561500D02*
X1124900Y561583D01*
X1124500Y561917D01*
X1124233Y562500D01*
X1124100Y563167D01*
X1124233Y563833D01*
X1124500Y564417D01*
X1124900Y564750D01*
X1125300Y564833D01*
X1125700Y564750D01*
X1126100Y564417D01*
X1126367Y563833D01*
X1126433Y563167D01*
X1126367Y562500D01*
X1126100Y561917D01*
X1125700Y561583D01*
X1125300Y561500D01*
G01X1130400D02*
Y566500D01*
G01X1136700D02*
Y561500D01*
G01Y562250D02*
X1136433Y561833D01*
X1136033Y561583D01*
X1135567Y561500D01*
X1135033Y561667D01*
X1134633Y562083D01*
X1134367Y562583D01*
X1134300Y563167D01*
X1134367Y563750D01*
X1134633Y564250D01*
X1135033Y564667D01*
X1135567Y564833D01*
X1136033Y564750D01*
X1136367Y564583D01*
X1136700Y564250D01*
G01X1139600Y563750D02*
X1141733D01*
X1141533Y564333D01*
X1141200Y564667D01*
X1140733Y564833D01*
X1140267Y564750D01*
X1139867Y564500D01*
X1139600Y563917D01*
X1139467Y563417D01*
Y562917D01*
X1139600Y562417D01*
X1139933Y561917D01*
X1140333Y561583D01*
X1140800Y561500D01*
X1141267Y561667D01*
X1141733Y562167D01*
G01X1144767Y561500D02*
Y564833D01*
G01Y564167D02*
X1145100Y564500D01*
X1145433Y564750D01*
X1145900Y564833D01*
X1146233Y564750D01*
X1146633Y564500D01*
G01X1153900Y561500D02*
Y564833D01*
G01Y563917D02*
X1154100Y564333D01*
X1154433Y564667D01*
X1154900Y564833D01*
X1155367Y564667D01*
X1155700Y564333D01*
X1155900Y563917D01*
Y561500D01*
G01Y563917D02*
X1156100Y564333D01*
X1156433Y564667D01*
X1156900Y564833D01*
X1157367Y564667D01*
X1157700Y564333D01*
X1157900Y563833D01*
Y561500D01*
G01X1162200D02*
Y564833D01*
G01Y564250D02*
X1161933Y564583D01*
X1161533Y564750D01*
X1161067Y564833D01*
X1160600Y564667D01*
X1160200Y564333D01*
X1159933Y563833D01*
X1159800Y563167D01*
X1159933Y562500D01*
X1160200Y562000D01*
X1160600Y561667D01*
X1161067Y561500D01*
X1161533Y561583D01*
X1161933Y561833D01*
X1162200Y562167D01*
G01X1165100Y562083D02*
X1165433Y561750D01*
X1165900Y561500D01*
X1166300D01*
X1166700Y561667D01*
X1166967Y561917D01*
X1167100Y562250D01*
X1167033Y562750D01*
X1166767Y563000D01*
X1165567Y563500D01*
X1165300Y564083D01*
X1165433Y564500D01*
X1165700Y564750D01*
X1166100Y564833D01*
X1166500Y564750D01*
X1166900Y564500D01*
G01X1170067Y561500D02*
Y566500D01*
G01X1172200Y564833D02*
X1170067Y562917D01*
G01X1170933Y563667D02*
X1172333Y561500D01*
G01X1182600D02*
Y564833D01*
G01Y564250D02*
X1182333Y564583D01*
X1181933Y564750D01*
X1181467Y564833D01*
X1181000Y564667D01*
X1180600Y564333D01*
X1180333Y563833D01*
X1180200Y563167D01*
X1180333Y562500D01*
X1180600Y562000D01*
X1181000Y561667D01*
X1181467Y561500D01*
X1181933Y561583D01*
X1182333Y561833D01*
X1182600Y562167D01*
G01X1185367Y561500D02*
Y564833D01*
G01Y564000D02*
X1185633Y564417D01*
X1186033Y564750D01*
X1186567Y564833D01*
X1187033Y564750D01*
X1187433Y564417D01*
X1187633Y563833D01*
Y561500D01*
G01X1192800Y566500D02*
Y561500D01*
G01Y562250D02*
X1192533Y561833D01*
X1192133Y561583D01*
X1191667Y561500D01*
X1191133Y561667D01*
X1190733Y562083D01*
X1190467Y562583D01*
X1190400Y563167D01*
X1190467Y563750D01*
X1190733Y564250D01*
X1191133Y564667D01*
X1191667Y564833D01*
X1192133Y564750D01*
X1192467Y564583D01*
X1192800Y564250D01*
G01X1200667Y561500D02*
Y566500D01*
G01Y564083D02*
X1201000Y564500D01*
X1201333Y564750D01*
X1201867Y564833D01*
X1202267Y564750D01*
X1202733Y564417D01*
X1202933Y563917D01*
Y561500D01*
G01X1206900D02*
X1206500Y561583D01*
X1206100Y561917D01*
X1205833Y562500D01*
X1205700Y563167D01*
X1205833Y563833D01*
X1206100Y564417D01*
X1206500Y564750D01*
X1206900Y564833D01*
X1207300Y564750D01*
X1207700Y564417D01*
X1207967Y563833D01*
X1208033Y563167D01*
X1207967Y562500D01*
X1207700Y561917D01*
X1207300Y561583D01*
X1206900Y561500D01*
G01X1212000D02*
Y566500D01*
G01X1216100Y563750D02*
X1218233D01*
X1218033Y564333D01*
X1217700Y564667D01*
X1217233Y564833D01*
X1216767Y564750D01*
X1216367Y564500D01*
X1216100Y563917D01*
X1215967Y563417D01*
Y562917D01*
X1216100Y562417D01*
X1216433Y561917D01*
X1216833Y561583D01*
X1217300Y561500D01*
X1217767Y561667D01*
X1218233Y562167D01*
G01X1228500Y561500D02*
Y564833D01*
G01Y564250D02*
X1228233Y564583D01*
X1227833Y564750D01*
X1227367Y564833D01*
X1226900Y564667D01*
X1226500Y564333D01*
X1226233Y563833D01*
X1226100Y563167D01*
X1226233Y562500D01*
X1226500Y562000D01*
X1226900Y561667D01*
X1227367Y561500D01*
X1227833Y561583D01*
X1228233Y561833D01*
X1228500Y562167D01*
G01X1232400Y561500D02*
Y566500D01*
G01X1236500Y562083D02*
X1236833Y561750D01*
X1237300Y561500D01*
X1237700D01*
X1238100Y561667D01*
X1238367Y561917D01*
X1238500Y562250D01*
X1238433Y562750D01*
X1238167Y563000D01*
X1236967Y563500D01*
X1236700Y564083D01*
X1236833Y564500D01*
X1237100Y564750D01*
X1237500Y564833D01*
X1237900Y564750D01*
X1238300Y564500D01*
G01X1242600Y561500D02*
X1242200Y561583D01*
X1241800Y561917D01*
X1241533Y562500D01*
X1241400Y563167D01*
X1241533Y563833D01*
X1241800Y564417D01*
X1242200Y564750D01*
X1242600Y564833D01*
X1243000Y564750D01*
X1243400Y564417D01*
X1243667Y563833D01*
X1243733Y563167D01*
X1243667Y562500D01*
X1243400Y561917D01*
X1243000Y561583D01*
X1242600Y561500D01*
G01X1251667D02*
Y564833D01*
G01Y564000D02*
X1251933Y564417D01*
X1252333Y564750D01*
X1252867Y564833D01*
X1253333Y564750D01*
X1253733Y564417D01*
X1253933Y563833D01*
Y561500D01*
G01X1256900Y563750D02*
X1259033D01*
X1258833Y564333D01*
X1258500Y564667D01*
X1258033Y564833D01*
X1257567Y564750D01*
X1257167Y564500D01*
X1256900Y563917D01*
X1256767Y563417D01*
Y562917D01*
X1256900Y562417D01*
X1257233Y561917D01*
X1257633Y561583D01*
X1258100Y561500D01*
X1258567Y561667D01*
X1259033Y562167D01*
G01X1262000Y563750D02*
X1264133D01*
X1263933Y564333D01*
X1263600Y564667D01*
X1263133Y564833D01*
X1262667Y564750D01*
X1262267Y564500D01*
X1262000Y563917D01*
X1261867Y563417D01*
Y562917D01*
X1262000Y562417D01*
X1262333Y561917D01*
X1262733Y561583D01*
X1263200Y561500D01*
X1263667Y561667D01*
X1264133Y562167D01*
G01X1269300Y566500D02*
Y561500D01*
G01Y562250D02*
X1269033Y561833D01*
X1268633Y561583D01*
X1268167Y561500D01*
X1267633Y561667D01*
X1267233Y562083D01*
X1266967Y562583D01*
X1266900Y563167D01*
X1266967Y563750D01*
X1267233Y564250D01*
X1267633Y564667D01*
X1268167Y564833D01*
X1268633Y564750D01*
X1268967Y564583D01*
X1269300Y564250D01*
G01X1278300Y566500D02*
Y561500D01*
G01X1277367Y564833D02*
X1279233D01*
G01X1283400Y561500D02*
X1283000Y561583D01*
X1282600Y561917D01*
X1282333Y562500D01*
X1282200Y563167D01*
X1282333Y563833D01*
X1282600Y564417D01*
X1283000Y564750D01*
X1283400Y564833D01*
X1283800Y564750D01*
X1284200Y564417D01*
X1284467Y563833D01*
X1284533Y563167D01*
X1284467Y562500D01*
X1284200Y561917D01*
X1283800Y561583D01*
X1283400Y561500D01*
G01X1021500Y569500D02*
Y574500D01*
X1020700Y573500D01*
G01Y569500D02*
X1022300D01*
G01X1026600Y569333D02*
X1026467Y569417D01*
Y569583D01*
X1026600Y569667D01*
X1026733Y569583D01*
Y569417D01*
X1026600Y569333D01*
G01X1031700Y574500D02*
Y569500D01*
G01X1030167Y574500D02*
X1033233D01*
G01X1035667Y569500D02*
Y574500D01*
G01Y572083D02*
X1036000Y572500D01*
X1036333Y572750D01*
X1036867Y572833D01*
X1037267Y572750D01*
X1037733Y572417D01*
X1037933Y571917D01*
Y569500D01*
G01X1040900Y571750D02*
X1043033D01*
X1042833Y572333D01*
X1042500Y572667D01*
X1042033Y572833D01*
X1041567Y572750D01*
X1041167Y572500D01*
X1040900Y571917D01*
X1040767Y571417D01*
Y570917D01*
X1040900Y570417D01*
X1041233Y569917D01*
X1041633Y569583D01*
X1042100Y569500D01*
X1042567Y569667D01*
X1043033Y570167D01*
G01X1051100Y570083D02*
X1051433Y569750D01*
X1051900Y569500D01*
X1052300D01*
X1052700Y569667D01*
X1052967Y569917D01*
X1053100Y570250D01*
X1053033Y570750D01*
X1052767Y571000D01*
X1051567Y571500D01*
X1051300Y572083D01*
X1051433Y572500D01*
X1051700Y572750D01*
X1052100Y572833D01*
X1052500Y572750D01*
X1052900Y572500D01*
G01X1057200Y572833D02*
Y569500D01*
G01Y574167D02*
X1057067Y574250D01*
Y574417D01*
X1057200Y574500D01*
X1057333Y574417D01*
Y574250D01*
X1057200Y574167D01*
G01X1063500Y574500D02*
Y569500D01*
G01Y570250D02*
X1063233Y569833D01*
X1062833Y569583D01*
X1062367Y569500D01*
X1061833Y569667D01*
X1061433Y570083D01*
X1061167Y570583D01*
X1061100Y571167D01*
X1061167Y571750D01*
X1061433Y572250D01*
X1061833Y572667D01*
X1062367Y572833D01*
X1062833Y572750D01*
X1063167Y572583D01*
X1063500Y572250D01*
G01X1066400Y571750D02*
X1068533D01*
X1068333Y572333D01*
X1068000Y572667D01*
X1067533Y572833D01*
X1067067Y572750D01*
X1066667Y572500D01*
X1066400Y571917D01*
X1066267Y571417D01*
Y570917D01*
X1066400Y570417D01*
X1066733Y569917D01*
X1067133Y569583D01*
X1067600Y569500D01*
X1068067Y569667D01*
X1068533Y570167D01*
G01X1075933Y572833D02*
X1076733Y569500D01*
X1077600Y572833D01*
X1078467Y569500D01*
X1079267Y572833D01*
G01X1082700D02*
Y569500D01*
G01Y574167D02*
X1082567Y574250D01*
Y574417D01*
X1082700Y574500D01*
X1082833Y574417D01*
Y574250D01*
X1082700Y574167D01*
G01X1087800Y574500D02*
Y569500D01*
G01X1086867Y572833D02*
X1088733D01*
G01X1091767Y569500D02*
Y574500D01*
G01Y572083D02*
X1092100Y572500D01*
X1092433Y572750D01*
X1092967Y572833D01*
X1093367Y572750D01*
X1093833Y572417D01*
X1094033Y571917D01*
Y569500D01*
G01X1098000D02*
X1097600Y569583D01*
X1097200Y569917D01*
X1096933Y570500D01*
X1096800Y571167D01*
X1096933Y571833D01*
X1097200Y572417D01*
X1097600Y572750D01*
X1098000Y572833D01*
X1098400Y572750D01*
X1098800Y572417D01*
X1099067Y571833D01*
X1099133Y571167D01*
X1099067Y570500D01*
X1098800Y569917D01*
X1098400Y569583D01*
X1098000Y569500D01*
G01X1101967Y572833D02*
Y570500D01*
X1102233Y569917D01*
X1102633Y569583D01*
X1103100Y569500D01*
X1103567Y569583D01*
X1103967Y569917D01*
X1104233Y570500D01*
G01Y569500D02*
Y572833D01*
G01X1108200Y574500D02*
Y569500D01*
G01X1107267Y572833D02*
X1109133D01*
G01X1117400Y570083D02*
X1117733Y569750D01*
X1118200Y569500D01*
X1118600D01*
X1119000Y569667D01*
X1119267Y569917D01*
X1119400Y570250D01*
X1119333Y570750D01*
X1119067Y571000D01*
X1117867Y571500D01*
X1117600Y572083D01*
X1117733Y572500D01*
X1118000Y572750D01*
X1118400Y572833D01*
X1118800Y572750D01*
X1119200Y572500D01*
G01X1123500Y569500D02*
X1123100Y569583D01*
X1122700Y569917D01*
X1122433Y570500D01*
X1122300Y571167D01*
X1122433Y571833D01*
X1122700Y572417D01*
X1123100Y572750D01*
X1123500Y572833D01*
X1123900Y572750D01*
X1124300Y572417D01*
X1124567Y571833D01*
X1124633Y571167D01*
X1124567Y570500D01*
X1124300Y569917D01*
X1123900Y569583D01*
X1123500Y569500D01*
G01X1128600D02*
Y574500D01*
G01X1134900D02*
Y569500D01*
G01Y570250D02*
X1134633Y569833D01*
X1134233Y569583D01*
X1133767Y569500D01*
X1133233Y569667D01*
X1132833Y570083D01*
X1132567Y570583D01*
X1132500Y571167D01*
X1132567Y571750D01*
X1132833Y572250D01*
X1133233Y572667D01*
X1133767Y572833D01*
X1134233Y572750D01*
X1134567Y572583D01*
X1134900Y572250D01*
G01X1137800Y571750D02*
X1139933D01*
X1139733Y572333D01*
X1139400Y572667D01*
X1138933Y572833D01*
X1138467Y572750D01*
X1138067Y572500D01*
X1137800Y571917D01*
X1137667Y571417D01*
Y570917D01*
X1137800Y570417D01*
X1138133Y569917D01*
X1138533Y569583D01*
X1139000Y569500D01*
X1139467Y569667D01*
X1139933Y570167D01*
G01X1142967Y569500D02*
Y572833D01*
G01Y572167D02*
X1143300Y572500D01*
X1143633Y572750D01*
X1144100Y572833D01*
X1144433Y572750D01*
X1144833Y572500D01*
G01X1152100Y569500D02*
Y572833D01*
G01Y571917D02*
X1152300Y572333D01*
X1152633Y572667D01*
X1153100Y572833D01*
X1153567Y572667D01*
X1153900Y572333D01*
X1154100Y571917D01*
Y569500D01*
G01Y571917D02*
X1154300Y572333D01*
X1154633Y572667D01*
X1155100Y572833D01*
X1155567Y572667D01*
X1155900Y572333D01*
X1156100Y571833D01*
Y569500D01*
G01X1160400D02*
Y572833D01*
G01Y572250D02*
X1160133Y572583D01*
X1159733Y572750D01*
X1159267Y572833D01*
X1158800Y572667D01*
X1158400Y572333D01*
X1158133Y571833D01*
X1158000Y571167D01*
X1158133Y570500D01*
X1158400Y570000D01*
X1158800Y569667D01*
X1159267Y569500D01*
X1159733Y569583D01*
X1160133Y569833D01*
X1160400Y570167D01*
G01X1163300Y570083D02*
X1163633Y569750D01*
X1164100Y569500D01*
X1164500D01*
X1164900Y569667D01*
X1165167Y569917D01*
X1165300Y570250D01*
X1165233Y570750D01*
X1164967Y571000D01*
X1163767Y571500D01*
X1163500Y572083D01*
X1163633Y572500D01*
X1163900Y572750D01*
X1164300Y572833D01*
X1164700Y572750D01*
X1165100Y572500D01*
G01X1168267Y569500D02*
Y574500D01*
G01X1170400Y572833D02*
X1168267Y570917D01*
G01X1169133Y571667D02*
X1170533Y569500D01*
G01X1178400Y567833D02*
Y572833D01*
G01Y572083D02*
X1178733Y572500D01*
X1179067Y572750D01*
X1179600Y572833D01*
X1180067Y572750D01*
X1180533Y572333D01*
X1180733Y571750D01*
X1180800Y571167D01*
X1180733Y570583D01*
X1180533Y570000D01*
X1180133Y569667D01*
X1179600Y569500D01*
X1179133Y569583D01*
X1178667Y569833D01*
X1178400Y570167D01*
G01X1185900Y569500D02*
Y572833D01*
G01Y572250D02*
X1185633Y572583D01*
X1185233Y572750D01*
X1184767Y572833D01*
X1184300Y572667D01*
X1183900Y572333D01*
X1183633Y571833D01*
X1183500Y571167D01*
X1183633Y570500D01*
X1183900Y570000D01*
X1184300Y569667D01*
X1184767Y569500D01*
X1185233Y569583D01*
X1185633Y569833D01*
X1185900Y570167D01*
G01X1191000Y574500D02*
Y569500D01*
G01Y570250D02*
X1190733Y569833D01*
X1190333Y569583D01*
X1189867Y569500D01*
X1189333Y569667D01*
X1188933Y570083D01*
X1188667Y570583D01*
X1188600Y571167D01*
X1188667Y571750D01*
X1188933Y572250D01*
X1189333Y572667D01*
X1189867Y572833D01*
X1190333Y572750D01*
X1190667Y572583D01*
X1191000Y572250D01*
G01X1199867Y568583D02*
X1200133Y569667D01*
G01X1211400Y569500D02*
Y572833D01*
G01Y572250D02*
X1211133Y572583D01*
X1210733Y572750D01*
X1210267Y572833D01*
X1209800Y572667D01*
X1209400Y572333D01*
X1209133Y571833D01*
X1209000Y571167D01*
X1209133Y570500D01*
X1209400Y570000D01*
X1209800Y569667D01*
X1210267Y569500D01*
X1210733Y569583D01*
X1211133Y569833D01*
X1211400Y570167D01*
G01X1214167Y569500D02*
Y572833D01*
G01Y572000D02*
X1214433Y572417D01*
X1214833Y572750D01*
X1215367Y572833D01*
X1215833Y572750D01*
X1216233Y572417D01*
X1216433Y571833D01*
Y569500D01*
G01X1219267D02*
Y572833D01*
G01Y572000D02*
X1219533Y572417D01*
X1219933Y572750D01*
X1220467Y572833D01*
X1220933Y572750D01*
X1221333Y572417D01*
X1221533Y571833D01*
Y569500D01*
G01X1224367Y572833D02*
Y570500D01*
X1224633Y569917D01*
X1225033Y569583D01*
X1225500Y569500D01*
X1225967Y569583D01*
X1226367Y569917D01*
X1226633Y570500D01*
G01Y569500D02*
Y572833D01*
G01X1231800Y569500D02*
Y572833D01*
G01Y572250D02*
X1231533Y572583D01*
X1231133Y572750D01*
X1230667Y572833D01*
X1230200Y572667D01*
X1229800Y572333D01*
X1229533Y571833D01*
X1229400Y571167D01*
X1229533Y570500D01*
X1229800Y570000D01*
X1230200Y569667D01*
X1230667Y569500D01*
X1231133Y569583D01*
X1231533Y569833D01*
X1231800Y570167D01*
G01X1235700Y569500D02*
Y574500D01*
G01X1244967Y569500D02*
Y572833D01*
G01Y572167D02*
X1245300Y572500D01*
X1245633Y572750D01*
X1246100Y572833D01*
X1246433Y572750D01*
X1246833Y572500D01*
G01X1251000Y572833D02*
Y569500D01*
G01Y574167D02*
X1250867Y574250D01*
Y574417D01*
X1251000Y574500D01*
X1251133Y574417D01*
Y574250D01*
X1251000Y574167D01*
G01X1254967Y569500D02*
Y572833D01*
G01Y572000D02*
X1255233Y572417D01*
X1255633Y572750D01*
X1256167Y572833D01*
X1256633Y572750D01*
X1257033Y572417D01*
X1257233Y571833D01*
Y569500D01*
G01X1260267Y568250D02*
X1260733Y567917D01*
X1261267Y567833D01*
X1261733Y567917D01*
X1262133Y568333D01*
X1262400Y568917D01*
Y572833D01*
G01Y572167D02*
X1262133Y572500D01*
X1261733Y572750D01*
X1261267Y572833D01*
X1260733Y572667D01*
X1260400Y572333D01*
X1260133Y571750D01*
X1260000Y571167D01*
X1260067Y570667D01*
X1260333Y570083D01*
X1260733Y569667D01*
X1261267Y569500D01*
X1261667Y569583D01*
X1262133Y569917D01*
X1262400Y570250D01*
G01X1270267Y569500D02*
Y572833D01*
G01Y572000D02*
X1270533Y572417D01*
X1270933Y572750D01*
X1271467Y572833D01*
X1271933Y572750D01*
X1272333Y572417D01*
X1272533Y571833D01*
Y569500D01*
G01X1275500Y571750D02*
X1277633D01*
X1277433Y572333D01*
X1277100Y572667D01*
X1276633Y572833D01*
X1276167Y572750D01*
X1275767Y572500D01*
X1275500Y571917D01*
X1275367Y571417D01*
Y570917D01*
X1275500Y570417D01*
X1275833Y569917D01*
X1276233Y569583D01*
X1276700Y569500D01*
X1277167Y569667D01*
X1277633Y570167D01*
G01X1280600Y571750D02*
X1282733D01*
X1282533Y572333D01*
X1282200Y572667D01*
X1281733Y572833D01*
X1281267Y572750D01*
X1280867Y572500D01*
X1280600Y571917D01*
X1280467Y571417D01*
Y570917D01*
X1280600Y570417D01*
X1280933Y569917D01*
X1281333Y569583D01*
X1281800Y569500D01*
X1282267Y569667D01*
X1282733Y570167D01*
G01X1287900Y574500D02*
Y569500D01*
G01Y570250D02*
X1287633Y569833D01*
X1287233Y569583D01*
X1286767Y569500D01*
X1286233Y569667D01*
X1285833Y570083D01*
X1285567Y570583D01*
X1285500Y571167D01*
X1285567Y571750D01*
X1285833Y572250D01*
X1286233Y572667D01*
X1286767Y572833D01*
X1287233Y572750D01*
X1287567Y572583D01*
X1287900Y572250D01*
G01X1011867Y730500D02*
Y733833D01*
G01Y733000D02*
X1012133Y733417D01*
X1012533Y733750D01*
X1013067Y733833D01*
X1013533Y733750D01*
X1013933Y733417D01*
X1014133Y732833D01*
Y730500D01*
G01X1018100D02*
X1017700Y730583D01*
X1017300Y730917D01*
X1017033Y731500D01*
X1016900Y732167D01*
X1017033Y732833D01*
X1017300Y733417D01*
X1017700Y733750D01*
X1018100Y733833D01*
X1018500Y733750D01*
X1018900Y733417D01*
X1019167Y732833D01*
X1019233Y732167D01*
X1019167Y731500D01*
X1018900Y730917D01*
X1018500Y730583D01*
X1018100Y730500D01*
G01X1027100Y728833D02*
Y733833D01*
G01Y733083D02*
X1027433Y733500D01*
X1027767Y733750D01*
X1028300Y733833D01*
X1028767Y733750D01*
X1029233Y733333D01*
X1029433Y732750D01*
X1029500Y732167D01*
X1029433Y731583D01*
X1029233Y731000D01*
X1028833Y730667D01*
X1028300Y730500D01*
X1027833Y730583D01*
X1027367Y730833D01*
X1027100Y731167D01*
G01X1033400Y730500D02*
Y735500D01*
G01X1037367Y733833D02*
Y731500D01*
X1037633Y730917D01*
X1038033Y730583D01*
X1038500Y730500D01*
X1038967Y730583D01*
X1039367Y730917D01*
X1039633Y731500D01*
G01Y730500D02*
Y733833D01*
G01X1042667Y729250D02*
X1043133Y728917D01*
X1043667Y728833D01*
X1044133Y728917D01*
X1044533Y729333D01*
X1044800Y729917D01*
Y733833D01*
G01Y733167D02*
X1044533Y733500D01*
X1044133Y733750D01*
X1043667Y733833D01*
X1043133Y733667D01*
X1042800Y733333D01*
X1042533Y732750D01*
X1042400Y732167D01*
X1042467Y731667D01*
X1042733Y731083D01*
X1043133Y730667D01*
X1043667Y730500D01*
X1044067Y730583D01*
X1044533Y730917D01*
X1044800Y731250D01*
G01X1047767Y729250D02*
X1048233Y728917D01*
X1048767Y728833D01*
X1049233Y728917D01*
X1049633Y729333D01*
X1049900Y729917D01*
Y733833D01*
G01Y733167D02*
X1049633Y733500D01*
X1049233Y733750D01*
X1048767Y733833D01*
X1048233Y733667D01*
X1047900Y733333D01*
X1047633Y732750D01*
X1047500Y732167D01*
X1047567Y731667D01*
X1047833Y731083D01*
X1048233Y730667D01*
X1048767Y730500D01*
X1049167Y730583D01*
X1049633Y730917D01*
X1049900Y731250D01*
G01X1053800Y733833D02*
Y730500D01*
G01Y735167D02*
X1053667Y735250D01*
Y735417D01*
X1053800Y735500D01*
X1053933Y735417D01*
Y735250D01*
X1053800Y735167D01*
G01X1057767Y730500D02*
Y733833D01*
G01Y733000D02*
X1058033Y733417D01*
X1058433Y733750D01*
X1058967Y733833D01*
X1059433Y733750D01*
X1059833Y733417D01*
X1060033Y732833D01*
Y730500D01*
G01X1063067Y729250D02*
X1063533Y728917D01*
X1064067Y728833D01*
X1064533Y728917D01*
X1064933Y729333D01*
X1065200Y729917D01*
Y733833D01*
G01Y733167D02*
X1064933Y733500D01*
X1064533Y733750D01*
X1064067Y733833D01*
X1063533Y733667D01*
X1063200Y733333D01*
X1062933Y732750D01*
X1062800Y732167D01*
X1062867Y731667D01*
X1063133Y731083D01*
X1063533Y730667D01*
X1064067Y730500D01*
X1064467Y730583D01*
X1064933Y730917D01*
X1065200Y731250D01*
G01X1087533Y124000D02*
Y129000D01*
X1088867D01*
X1089400Y128750D01*
X1089800Y128417D01*
X1090133Y127917D01*
X1090400Y127333D01*
X1090467Y126500D01*
X1090400Y125667D01*
X1090133Y125083D01*
X1089800Y124583D01*
X1089400Y124250D01*
X1088867Y124000D01*
X1087533D01*
G01X1093167D02*
Y127333D01*
G01Y126667D02*
X1093500Y127000D01*
X1093833Y127250D01*
X1094300Y127333D01*
X1094633Y127250D01*
X1095033Y127000D01*
G01X1099200Y127333D02*
Y124000D01*
G01Y128667D02*
X1099067Y128750D01*
Y128917D01*
X1099200Y129000D01*
X1099333Y128917D01*
Y128750D01*
X1099200Y128667D01*
G01X1104300Y124000D02*
Y129000D01*
G01X1109400Y124000D02*
Y129000D01*
G01X1118333Y124000D02*
Y129000D01*
X1120867D01*
G01X1119933Y126583D02*
X1118333D01*
G01X1123767Y124000D02*
Y127333D01*
G01Y126667D02*
X1124100Y127000D01*
X1124433Y127250D01*
X1124900Y127333D01*
X1125233Y127250D01*
X1125633Y127000D01*
G01X1129800Y124000D02*
X1129400Y124083D01*
X1129000Y124417D01*
X1128733Y125000D01*
X1128600Y125667D01*
X1128733Y126333D01*
X1129000Y126917D01*
X1129400Y127250D01*
X1129800Y127333D01*
X1130200Y127250D01*
X1130600Y126917D01*
X1130867Y126333D01*
X1130933Y125667D01*
X1130867Y125000D01*
X1130600Y124417D01*
X1130200Y124083D01*
X1129800Y124000D01*
G01X1132900D02*
Y127333D01*
G01Y126417D02*
X1133100Y126833D01*
X1133433Y127167D01*
X1133900Y127333D01*
X1134367Y127167D01*
X1134700Y126833D01*
X1134900Y126417D01*
Y124000D01*
G01Y126417D02*
X1135100Y126833D01*
X1135433Y127167D01*
X1135900Y127333D01*
X1136367Y127167D01*
X1136700Y126833D01*
X1136900Y126333D01*
Y124000D01*
G01X1160067Y122333D02*
X1159400Y123167D01*
X1159067Y124000D01*
Y127333D01*
X1159400Y128167D01*
X1160067Y129000D01*
G01X1166033Y126667D02*
X1166300Y126917D01*
X1166500Y127333D01*
X1166633Y127917D01*
X1166500Y128417D01*
X1166233Y128750D01*
X1165767Y129000D01*
X1163967D01*
Y124000D01*
X1166167D01*
X1166633Y124333D01*
X1166900Y124833D01*
X1167033Y125417D01*
X1166900Y126000D01*
X1166500Y126500D01*
X1166033Y126667D01*
X1163967D01*
G01X1170600Y124000D02*
X1170067Y124083D01*
X1169600Y124417D01*
X1169200Y124917D01*
X1168933Y125500D01*
X1168800Y126167D01*
Y126833D01*
X1168933Y127500D01*
X1169200Y128083D01*
X1169600Y128583D01*
X1170067Y128917D01*
X1170600Y129000D01*
X1171133Y128917D01*
X1171600Y128583D01*
X1172000Y128083D01*
X1172267Y127500D01*
X1172400Y126833D01*
Y126167D01*
X1172267Y125500D01*
X1172000Y124917D01*
X1171600Y124417D01*
X1171133Y124083D01*
X1170600Y124000D01*
G01X1175700Y129000D02*
Y124000D01*
G01X1174167Y129000D02*
X1177233D01*
G01X1180800D02*
Y124000D01*
G01X1179267Y129000D02*
X1182333D01*
G01X1185900Y124000D02*
X1185367Y124083D01*
X1184900Y124417D01*
X1184500Y124917D01*
X1184233Y125500D01*
X1184100Y126167D01*
Y126833D01*
X1184233Y127500D01*
X1184500Y128083D01*
X1184900Y128583D01*
X1185367Y128917D01*
X1185900Y129000D01*
X1186433Y128917D01*
X1186900Y128583D01*
X1187300Y128083D01*
X1187567Y127500D01*
X1187700Y126833D01*
Y126167D01*
X1187567Y125500D01*
X1187300Y124917D01*
X1186900Y124417D01*
X1186433Y124083D01*
X1185900Y124000D01*
G01X1189267D02*
Y129000D01*
X1191000Y124833D01*
X1192733Y129000D01*
Y124000D01*
G01X1196433Y122333D02*
X1197100Y123167D01*
X1197433Y124000D01*
Y127333D01*
X1197100Y128167D01*
X1196433Y129000D01*
G01X1206300D02*
Y124000D01*
G01X1205367Y127333D02*
X1207233D01*
G01X1211400Y124000D02*
X1211000Y124083D01*
X1210600Y124417D01*
X1210333Y125000D01*
X1210200Y125667D01*
X1210333Y126333D01*
X1210600Y126917D01*
X1211000Y127250D01*
X1211400Y127333D01*
X1211800Y127250D01*
X1212200Y126917D01*
X1212467Y126333D01*
X1212533Y125667D01*
X1212467Y125000D01*
X1212200Y124417D01*
X1211800Y124083D01*
X1211400Y124000D01*
G01X1220267Y129000D02*
Y124000D01*
X1222933D01*
G01X1225700Y127333D02*
X1227700Y124000D01*
G01Y127333D02*
X1225700Y124000D01*
G01X1089327Y104700D02*
Y99700D01*
X1091993D01*
G01X1094760Y103033D02*
X1096760Y99700D01*
G01Y103033D02*
X1094760Y99700D01*
G01X1100860Y99533D02*
X1100727Y99617D01*
Y99783D01*
X1100860Y99867D01*
X1100993Y99783D01*
Y99617D01*
X1100860Y99533D01*
G01Y101783D02*
X1100727Y101867D01*
Y102033D01*
X1100860Y102117D01*
X1100993Y102033D01*
Y101867D01*
X1100860Y101783D01*
G01X1109060Y99700D02*
Y103033D01*
G01Y102117D02*
X1109260Y102533D01*
X1109593Y102867D01*
X1110060Y103033D01*
X1110527Y102867D01*
X1110860Y102533D01*
X1111060Y102117D01*
Y99700D01*
G01Y102117D02*
X1111260Y102533D01*
X1111593Y102867D01*
X1112060Y103033D01*
X1112527Y102867D01*
X1112860Y102533D01*
X1113060Y102033D01*
Y99700D01*
G01X1115027Y103033D02*
Y100700D01*
X1115293Y100117D01*
X1115693Y99783D01*
X1116160Y99700D01*
X1116627Y99783D01*
X1117027Y100117D01*
X1117293Y100700D01*
G01Y99700D02*
Y103033D01*
G01X1120260Y100283D02*
X1120593Y99950D01*
X1121060Y99700D01*
X1121460D01*
X1121860Y99867D01*
X1122127Y100117D01*
X1122260Y100450D01*
X1122193Y100950D01*
X1121927Y101200D01*
X1120727Y101700D01*
X1120460Y102283D01*
X1120593Y102700D01*
X1120860Y102950D01*
X1121260Y103033D01*
X1121660Y102950D01*
X1122060Y102700D01*
G01X1126360Y104700D02*
Y99700D01*
G01X1125427Y103033D02*
X1127293D01*
G01X1135360Y99700D02*
Y104700D01*
G01Y102200D02*
X1135693Y102700D01*
X1136093Y102950D01*
X1136493Y103033D01*
X1137093Y102867D01*
X1137493Y102533D01*
X1137760Y101950D01*
Y101283D01*
X1137627Y100617D01*
X1137360Y100117D01*
X1136893Y99783D01*
X1136493Y99700D01*
X1136093Y99783D01*
X1135693Y100033D01*
X1135360Y100450D01*
G01X1140660Y101950D02*
X1142793D01*
X1142593Y102533D01*
X1142260Y102867D01*
X1141793Y103033D01*
X1141327Y102950D01*
X1140927Y102700D01*
X1140660Y102117D01*
X1140527Y101617D01*
Y101117D01*
X1140660Y100617D01*
X1140993Y100117D01*
X1141393Y99783D01*
X1141860Y99700D01*
X1142327Y99867D01*
X1142793Y100367D01*
G01X1150660Y99700D02*
Y104700D01*
G01Y102200D02*
X1150993Y102700D01*
X1151393Y102950D01*
X1151793Y103033D01*
X1152393Y102867D01*
X1152793Y102533D01*
X1153060Y101950D01*
Y101283D01*
X1152927Y100617D01*
X1152660Y100117D01*
X1152193Y99783D01*
X1151793Y99700D01*
X1151393Y99783D01*
X1150993Y100033D01*
X1150660Y100450D01*
G01X1156027Y99700D02*
Y103033D01*
G01Y102367D02*
X1156360Y102700D01*
X1156693Y102950D01*
X1157160Y103033D01*
X1157493Y102950D01*
X1157893Y102700D01*
G01X1162060Y99700D02*
X1161660Y99783D01*
X1161260Y100117D01*
X1160993Y100700D01*
X1160860Y101367D01*
X1160993Y102033D01*
X1161260Y102617D01*
X1161660Y102950D01*
X1162060Y103033D01*
X1162460Y102950D01*
X1162860Y102617D01*
X1163127Y102033D01*
X1163193Y101367D01*
X1163127Y100700D01*
X1162860Y100117D01*
X1162460Y99783D01*
X1162060Y99700D01*
G01X1166027D02*
Y104700D01*
G01X1168160Y103033D02*
X1166027Y101117D01*
G01X1166893Y101867D02*
X1168293Y99700D01*
G01X1171260Y101950D02*
X1173393D01*
X1173193Y102533D01*
X1172860Y102867D01*
X1172393Y103033D01*
X1171927Y102950D01*
X1171527Y102700D01*
X1171260Y102117D01*
X1171127Y101617D01*
Y101117D01*
X1171260Y100617D01*
X1171593Y100117D01*
X1171993Y99783D01*
X1172460Y99700D01*
X1172927Y99867D01*
X1173393Y100367D01*
G01X1176227Y99700D02*
Y103033D01*
G01Y102200D02*
X1176493Y102617D01*
X1176893Y102950D01*
X1177427Y103033D01*
X1177893Y102950D01*
X1178293Y102617D01*
X1178493Y102033D01*
Y99700D01*
G01X1187560D02*
Y104700D01*
G01X1193860Y99700D02*
Y103033D01*
G01Y102450D02*
X1193593Y102783D01*
X1193193Y102950D01*
X1192727Y103033D01*
X1192260Y102867D01*
X1191860Y102533D01*
X1191593Y102033D01*
X1191460Y101367D01*
X1191593Y100700D01*
X1191860Y100200D01*
X1192260Y99867D01*
X1192727Y99700D01*
X1193193Y99783D01*
X1193593Y100033D01*
X1193860Y100367D01*
G01X1196360Y98200D02*
X1196760Y98033D01*
X1197293Y98200D01*
X1197627Y98533D01*
X1197893Y98950D01*
X1198293Y100283D01*
X1199160Y103033D01*
G01X1197027D02*
X1198293Y100283D01*
G01X1201860Y101950D02*
X1203993D01*
X1203793Y102533D01*
X1203460Y102867D01*
X1202993Y103033D01*
X1202527Y102950D01*
X1202127Y102700D01*
X1201860Y102117D01*
X1201727Y101617D01*
Y101117D01*
X1201860Y100617D01*
X1202193Y100117D01*
X1202593Y99783D01*
X1203060Y99700D01*
X1203527Y99867D01*
X1203993Y100367D01*
G01X1207027Y99700D02*
Y103033D01*
G01Y102367D02*
X1207360Y102700D01*
X1207693Y102950D01*
X1208160Y103033D01*
X1208493Y102950D01*
X1208893Y102700D01*
G01X1088727Y117200D02*
Y112200D01*
X1091393D01*
G01X1094027D02*
Y115533D01*
G01Y114700D02*
X1094293Y115117D01*
X1094693Y115450D01*
X1095227Y115533D01*
X1095693Y115450D01*
X1096093Y115117D01*
X1096293Y114533D01*
Y112200D01*
G01X1100260Y112033D02*
X1100127Y112117D01*
Y112283D01*
X1100260Y112367D01*
X1100393Y112283D01*
Y112117D01*
X1100260Y112033D01*
G01Y114283D02*
X1100127Y114367D01*
Y114533D01*
X1100260Y114617D01*
X1100393Y114533D01*
Y114367D01*
X1100260Y114283D01*
G01X1111527Y115117D02*
X1111060Y115450D01*
X1110660Y115533D01*
X1110127Y115367D01*
X1109727Y115033D01*
X1109460Y114450D01*
X1109393Y113867D01*
X1109460Y113283D01*
X1109727Y112783D01*
X1110127Y112367D01*
X1110660Y112200D01*
X1111127Y112367D01*
X1111527Y112700D01*
G01X1116760Y112200D02*
Y115533D01*
G01Y114950D02*
X1116493Y115283D01*
X1116093Y115450D01*
X1115627Y115533D01*
X1115160Y115367D01*
X1114760Y115033D01*
X1114493Y114533D01*
X1114360Y113867D01*
X1114493Y113200D01*
X1114760Y112700D01*
X1115160Y112367D01*
X1115627Y112200D01*
X1116093Y112283D01*
X1116493Y112533D01*
X1116760Y112867D01*
G01X1119527Y112200D02*
Y115533D01*
G01Y114700D02*
X1119793Y115117D01*
X1120193Y115450D01*
X1120727Y115533D01*
X1121193Y115450D01*
X1121593Y115117D01*
X1121793Y114533D01*
Y112200D01*
G01X1125760Y115533D02*
X1126427Y116575D01*
Y117200D01*
X1125927D01*
Y116575D01*
X1126427D01*
G01X1130860Y117200D02*
Y112200D01*
G01X1129927Y115533D02*
X1131793D01*
G01X1139860Y112200D02*
Y117200D01*
G01Y114700D02*
X1140193Y115200D01*
X1140593Y115450D01*
X1140993Y115533D01*
X1141593Y115367D01*
X1141993Y115033D01*
X1142260Y114450D01*
Y113783D01*
X1142127Y113117D01*
X1141860Y112617D01*
X1141393Y112283D01*
X1140993Y112200D01*
X1140593Y112283D01*
X1140193Y112533D01*
X1139860Y112950D01*
G01X1145160Y114450D02*
X1147293D01*
X1147093Y115033D01*
X1146760Y115367D01*
X1146293Y115533D01*
X1145827Y115450D01*
X1145427Y115200D01*
X1145160Y114617D01*
X1145027Y114117D01*
Y113617D01*
X1145160Y113117D01*
X1145493Y112617D01*
X1145893Y112283D01*
X1146360Y112200D01*
X1146827Y112367D01*
X1147293Y112867D01*
G01X1155160Y112200D02*
Y117200D01*
G01Y114700D02*
X1155493Y115200D01*
X1155893Y115450D01*
X1156293Y115533D01*
X1156893Y115367D01*
X1157293Y115033D01*
X1157560Y114450D01*
Y113783D01*
X1157427Y113117D01*
X1157160Y112617D01*
X1156693Y112283D01*
X1156293Y112200D01*
X1155893Y112283D01*
X1155493Y112533D01*
X1155160Y112950D01*
G01X1160527Y112200D02*
Y115533D01*
G01Y114867D02*
X1160860Y115200D01*
X1161193Y115450D01*
X1161660Y115533D01*
X1161993Y115450D01*
X1162393Y115200D01*
G01X1166560Y112200D02*
X1166160Y112283D01*
X1165760Y112617D01*
X1165493Y113200D01*
X1165360Y113867D01*
X1165493Y114533D01*
X1165760Y115117D01*
X1166160Y115450D01*
X1166560Y115533D01*
X1166960Y115450D01*
X1167360Y115117D01*
X1167627Y114533D01*
X1167693Y113867D01*
X1167627Y113200D01*
X1167360Y112617D01*
X1166960Y112283D01*
X1166560Y112200D01*
G01X1170527D02*
Y117200D01*
G01X1172660Y115533D02*
X1170527Y113617D01*
G01X1171393Y114367D02*
X1172793Y112200D01*
G01X1175760Y114450D02*
X1177893D01*
X1177693Y115033D01*
X1177360Y115367D01*
X1176893Y115533D01*
X1176427Y115450D01*
X1176027Y115200D01*
X1175760Y114617D01*
X1175627Y114117D01*
Y113617D01*
X1175760Y113117D01*
X1176093Y112617D01*
X1176493Y112283D01*
X1176960Y112200D01*
X1177427Y112367D01*
X1177893Y112867D01*
G01X1180727Y112200D02*
Y115533D01*
G01Y114700D02*
X1180993Y115117D01*
X1181393Y115450D01*
X1181927Y115533D01*
X1182393Y115450D01*
X1182793Y115117D01*
X1182993Y114533D01*
Y112200D01*
G01X1192060D02*
Y117200D01*
G01X1198360Y112200D02*
Y115533D01*
G01Y114950D02*
X1198093Y115283D01*
X1197693Y115450D01*
X1197227Y115533D01*
X1196760Y115367D01*
X1196360Y115033D01*
X1196093Y114533D01*
X1195960Y113867D01*
X1196093Y113200D01*
X1196360Y112700D01*
X1196760Y112367D01*
X1197227Y112200D01*
X1197693Y112283D01*
X1198093Y112533D01*
X1198360Y112867D01*
G01X1200860Y110700D02*
X1201260Y110533D01*
X1201793Y110700D01*
X1202127Y111033D01*
X1202393Y111450D01*
X1202793Y112783D01*
X1203660Y115533D01*
G01X1201527D02*
X1202793Y112783D01*
G01X1206360Y114450D02*
X1208493D01*
X1208293Y115033D01*
X1207960Y115367D01*
X1207493Y115533D01*
X1207027Y115450D01*
X1206627Y115200D01*
X1206360Y114617D01*
X1206227Y114117D01*
Y113617D01*
X1206360Y113117D01*
X1206693Y112617D01*
X1207093Y112283D01*
X1207560Y112200D01*
X1208027Y112367D01*
X1208493Y112867D01*
G01X1211527Y112200D02*
Y115533D01*
G01Y114867D02*
X1211860Y115200D01*
X1212193Y115450D01*
X1212660Y115533D01*
X1212993Y115450D01*
X1213393Y115200D01*
G01X1046300Y485833D02*
X1047500Y482500D01*
X1048700Y485833D01*
G01X1052600D02*
Y482500D01*
G01Y487167D02*
X1052467Y487250D01*
Y487417D01*
X1052600Y487500D01*
X1052733Y487417D01*
Y487250D01*
X1052600Y487167D01*
G01X1058900Y482500D02*
Y485833D01*
G01Y485250D02*
X1058633Y485583D01*
X1058233Y485750D01*
X1057767Y485833D01*
X1057300Y485667D01*
X1056900Y485333D01*
X1056633Y484833D01*
X1056500Y484167D01*
X1056633Y483500D01*
X1056900Y483000D01*
X1057300Y482667D01*
X1057767Y482500D01*
X1058233Y482583D01*
X1058633Y482833D01*
X1058900Y483167D01*
G01X1066900Y483083D02*
X1067233Y482750D01*
X1067700Y482500D01*
X1068100D01*
X1068500Y482667D01*
X1068767Y482917D01*
X1068900Y483250D01*
X1068833Y483750D01*
X1068567Y484000D01*
X1067367Y484500D01*
X1067100Y485083D01*
X1067233Y485500D01*
X1067500Y485750D01*
X1067900Y485833D01*
X1068300Y485750D01*
X1068700Y485500D01*
G01X1071867Y482500D02*
Y487500D01*
G01Y485083D02*
X1072200Y485500D01*
X1072533Y485750D01*
X1073067Y485833D01*
X1073467Y485750D01*
X1073933Y485417D01*
X1074133Y484917D01*
Y482500D01*
G01X1079300D02*
Y485833D01*
G01Y485250D02*
X1079033Y485583D01*
X1078633Y485750D01*
X1078167Y485833D01*
X1077700Y485667D01*
X1077300Y485333D01*
X1077033Y484833D01*
X1076900Y484167D01*
X1077033Y483500D01*
X1077300Y483000D01*
X1077700Y482667D01*
X1078167Y482500D01*
X1078633Y482583D01*
X1079033Y482833D01*
X1079300Y483167D01*
G01X1083200Y482500D02*
Y487500D01*
G01X1088300Y482500D02*
Y487500D01*
G01X1097300Y482500D02*
Y487500D01*
G01Y485000D02*
X1097633Y485500D01*
X1098033Y485750D01*
X1098433Y485833D01*
X1099033Y485667D01*
X1099433Y485333D01*
X1099700Y484750D01*
Y484083D01*
X1099567Y483417D01*
X1099300Y482917D01*
X1098833Y482583D01*
X1098433Y482500D01*
X1098033Y482583D01*
X1097633Y482833D01*
X1097300Y483250D01*
G01X1102600Y484750D02*
X1104733D01*
X1104533Y485333D01*
X1104200Y485667D01*
X1103733Y485833D01*
X1103267Y485750D01*
X1102867Y485500D01*
X1102600Y484917D01*
X1102467Y484417D01*
Y483917D01*
X1102600Y483417D01*
X1102933Y482917D01*
X1103333Y482583D01*
X1103800Y482500D01*
X1104267Y482667D01*
X1104733Y483167D01*
G01X1112133Y485833D02*
X1112933Y482500D01*
X1113800Y485833D01*
X1114667Y482500D01*
X1115467Y485833D01*
G01X1118900D02*
Y482500D01*
G01Y487167D02*
X1118767Y487250D01*
Y487417D01*
X1118900Y487500D01*
X1119033Y487417D01*
Y487250D01*
X1118900Y487167D01*
G01X1124000Y487500D02*
Y482500D01*
G01X1123067Y485833D02*
X1124933D01*
G01X1127967Y482500D02*
Y487500D01*
G01Y485083D02*
X1128300Y485500D01*
X1128633Y485750D01*
X1129167Y485833D01*
X1129567Y485750D01*
X1130033Y485417D01*
X1130233Y484917D01*
Y482500D01*
G01X1140633D02*
X1137967Y484167D01*
X1140633Y485833D01*
G01X1149500Y482500D02*
X1149967Y482583D01*
X1150500Y482833D01*
X1150833Y483250D01*
X1150967Y483833D01*
X1150833Y484417D01*
X1150433Y484917D01*
X1149833Y485167D01*
X1149167D01*
X1148767Y485333D01*
X1148433Y485750D01*
X1148300Y486333D01*
X1148500Y486917D01*
X1148967Y487333D01*
X1149500Y487500D01*
X1150033Y487333D01*
X1150500Y486917D01*
X1150700Y486333D01*
X1150567Y485750D01*
X1150233Y485333D01*
X1149833Y485167D01*
X1149167D01*
X1148567Y484917D01*
X1148167Y484417D01*
X1148033Y483833D01*
X1148167Y483250D01*
X1148500Y482833D01*
X1149033Y482583D01*
X1149500Y482500D01*
G01X1154600Y487500D02*
X1154067Y487333D01*
X1153667Y486917D01*
X1153400Y486417D01*
X1153200Y485750D01*
X1153133Y485000D01*
X1153200Y484250D01*
X1153400Y483583D01*
X1153667Y483083D01*
X1154067Y482667D01*
X1154600Y482500D01*
X1155133Y482667D01*
X1155533Y483083D01*
X1155800Y483583D01*
X1156000Y484250D01*
X1156067Y485000D01*
X1156000Y485750D01*
X1155800Y486417D01*
X1155533Y486917D01*
X1155133Y487333D01*
X1154600Y487500D01*
G01X1163600Y482333D02*
X1166000Y487500D01*
G01X1163600D02*
X1163200Y487333D01*
X1163000Y487083D01*
X1162867Y486583D01*
X1163000Y486083D01*
X1163200Y485833D01*
X1163600Y485667D01*
X1164000Y485833D01*
X1164200Y486083D01*
X1164333Y486583D01*
X1164200Y487083D01*
X1164000Y487333D01*
X1163600Y487500D01*
G01X1166000Y484167D02*
X1165600Y484000D01*
X1165400Y483750D01*
X1165267Y483250D01*
X1165400Y482750D01*
X1165600Y482500D01*
X1166000Y482333D01*
X1166400Y482500D01*
X1166600Y482750D01*
X1166733Y483250D01*
X1166600Y483750D01*
X1166400Y484000D01*
X1166000Y484167D01*
G01X1174000Y483083D02*
X1174333Y482750D01*
X1174800Y482500D01*
X1175200D01*
X1175600Y482667D01*
X1175867Y482917D01*
X1176000Y483250D01*
X1175933Y483750D01*
X1175667Y484000D01*
X1174467Y484500D01*
X1174200Y485083D01*
X1174333Y485500D01*
X1174600Y485750D01*
X1175000Y485833D01*
X1175400Y485750D01*
X1175800Y485500D01*
G01X1180100Y482500D02*
X1179700Y482583D01*
X1179300Y482917D01*
X1179033Y483500D01*
X1178900Y484167D01*
X1179033Y484833D01*
X1179300Y485417D01*
X1179700Y485750D01*
X1180100Y485833D01*
X1180500Y485750D01*
X1180900Y485417D01*
X1181167Y484833D01*
X1181233Y484167D01*
X1181167Y483500D01*
X1180900Y482917D01*
X1180500Y482583D01*
X1180100Y482500D01*
G01X1185200D02*
Y487500D01*
G01X1191500D02*
Y482500D01*
G01Y483250D02*
X1191233Y482833D01*
X1190833Y482583D01*
X1190367Y482500D01*
X1189833Y482667D01*
X1189433Y483083D01*
X1189167Y483583D01*
X1189100Y484167D01*
X1189167Y484750D01*
X1189433Y485250D01*
X1189833Y485667D01*
X1190367Y485833D01*
X1190833Y485750D01*
X1191167Y485583D01*
X1191500Y485250D01*
G01X1194400Y484750D02*
X1196533D01*
X1196333Y485333D01*
X1196000Y485667D01*
X1195533Y485833D01*
X1195067Y485750D01*
X1194667Y485500D01*
X1194400Y484917D01*
X1194267Y484417D01*
Y483917D01*
X1194400Y483417D01*
X1194733Y482917D01*
X1195133Y482583D01*
X1195600Y482500D01*
X1196067Y482667D01*
X1196533Y483167D01*
G01X1199567Y482500D02*
Y485833D01*
G01Y485167D02*
X1199900Y485500D01*
X1200233Y485750D01*
X1200700Y485833D01*
X1201033Y485750D01*
X1201433Y485500D01*
G01X1208700Y482500D02*
Y485833D01*
G01Y484917D02*
X1208900Y485333D01*
X1209233Y485667D01*
X1209700Y485833D01*
X1210167Y485667D01*
X1210500Y485333D01*
X1210700Y484917D01*
Y482500D01*
G01Y484917D02*
X1210900Y485333D01*
X1211233Y485667D01*
X1211700Y485833D01*
X1212167Y485667D01*
X1212500Y485333D01*
X1212700Y484833D01*
Y482500D01*
G01X1217000D02*
Y485833D01*
G01Y485250D02*
X1216733Y485583D01*
X1216333Y485750D01*
X1215867Y485833D01*
X1215400Y485667D01*
X1215000Y485333D01*
X1214733Y484833D01*
X1214600Y484167D01*
X1214733Y483500D01*
X1215000Y483000D01*
X1215400Y482667D01*
X1215867Y482500D01*
X1216333Y482583D01*
X1216733Y482833D01*
X1217000Y483167D01*
G01X1219900Y483083D02*
X1220233Y482750D01*
X1220700Y482500D01*
X1221100D01*
X1221500Y482667D01*
X1221767Y482917D01*
X1221900Y483250D01*
X1221833Y483750D01*
X1221567Y484000D01*
X1220367Y484500D01*
X1220100Y485083D01*
X1220233Y485500D01*
X1220500Y485750D01*
X1220900Y485833D01*
X1221300Y485750D01*
X1221700Y485500D01*
G01X1224867Y482500D02*
Y487500D01*
G01X1227000Y485833D02*
X1224867Y483917D01*
G01X1225733Y484667D02*
X1227133Y482500D01*
G01X1035300Y491500D02*
Y496500D01*
G01Y494000D02*
X1035633Y494500D01*
X1036033Y494750D01*
X1036433Y494833D01*
X1037033Y494667D01*
X1037433Y494333D01*
X1037700Y493750D01*
Y493083D01*
X1037567Y492417D01*
X1037300Y491917D01*
X1036833Y491583D01*
X1036433Y491500D01*
X1036033Y491583D01*
X1035633Y491833D01*
X1035300Y492250D01*
G01X1041600Y491333D02*
X1041467Y491417D01*
Y491583D01*
X1041600Y491667D01*
X1041733Y491583D01*
Y491417D01*
X1041600Y491333D01*
G01X1047233Y494167D02*
X1047500Y494417D01*
X1047700Y494833D01*
X1047833Y495417D01*
X1047700Y495917D01*
X1047433Y496250D01*
X1046967Y496500D01*
X1045167D01*
Y491500D01*
X1047367D01*
X1047833Y491833D01*
X1048100Y492333D01*
X1048233Y492917D01*
X1048100Y493500D01*
X1047700Y494000D01*
X1047233Y494167D01*
X1045167D01*
G01X1051800Y491500D02*
X1051400Y491583D01*
X1051000Y491917D01*
X1050733Y492500D01*
X1050600Y493167D01*
X1050733Y493833D01*
X1051000Y494417D01*
X1051400Y494750D01*
X1051800Y494833D01*
X1052200Y494750D01*
X1052600Y494417D01*
X1052867Y493833D01*
X1052933Y493167D01*
X1052867Y492500D01*
X1052600Y491917D01*
X1052200Y491583D01*
X1051800Y491500D01*
G01X1058100D02*
Y494833D01*
G01Y494250D02*
X1057833Y494583D01*
X1057433Y494750D01*
X1056967Y494833D01*
X1056500Y494667D01*
X1056100Y494333D01*
X1055833Y493833D01*
X1055700Y493167D01*
X1055833Y492500D01*
X1056100Y492000D01*
X1056500Y491667D01*
X1056967Y491500D01*
X1057433Y491583D01*
X1057833Y491833D01*
X1058100Y492167D01*
G01X1061067Y491500D02*
Y494833D01*
G01Y494167D02*
X1061400Y494500D01*
X1061733Y494750D01*
X1062200Y494833D01*
X1062533Y494750D01*
X1062933Y494500D01*
G01X1068300Y496500D02*
Y491500D01*
G01Y492250D02*
X1068033Y491833D01*
X1067633Y491583D01*
X1067167Y491500D01*
X1066633Y491667D01*
X1066233Y492083D01*
X1065967Y492583D01*
X1065900Y493167D01*
X1065967Y493750D01*
X1066233Y494250D01*
X1066633Y494667D01*
X1067167Y494833D01*
X1067633Y494750D01*
X1067967Y494583D01*
X1068300Y494250D01*
G01X1077300Y496500D02*
Y491500D01*
G01X1076367Y494833D02*
X1078233D01*
G01X1081267Y491500D02*
Y496500D01*
G01Y494083D02*
X1081600Y494500D01*
X1081933Y494750D01*
X1082467Y494833D01*
X1082867Y494750D01*
X1083333Y494417D01*
X1083533Y493917D01*
Y491500D01*
G01X1087500Y494833D02*
Y491500D01*
G01Y496167D02*
X1087367Y496250D01*
Y496417D01*
X1087500Y496500D01*
X1087633Y496417D01*
Y496250D01*
X1087500Y496167D01*
G01X1093667Y494417D02*
X1093200Y494750D01*
X1092800Y494833D01*
X1092267Y494667D01*
X1091867Y494333D01*
X1091600Y493750D01*
X1091533Y493167D01*
X1091600Y492583D01*
X1091867Y492083D01*
X1092267Y491667D01*
X1092800Y491500D01*
X1093267Y491667D01*
X1093667Y492000D01*
G01X1096567Y491500D02*
Y496500D01*
G01X1098700Y494833D02*
X1096567Y492917D01*
G01X1097433Y493667D02*
X1098833Y491500D01*
G01X1101667D02*
Y494833D01*
G01Y494000D02*
X1101933Y494417D01*
X1102333Y494750D01*
X1102867Y494833D01*
X1103333Y494750D01*
X1103733Y494417D01*
X1103933Y493833D01*
Y491500D01*
G01X1106900Y493750D02*
X1109033D01*
X1108833Y494333D01*
X1108500Y494667D01*
X1108033Y494833D01*
X1107567Y494750D01*
X1107167Y494500D01*
X1106900Y493917D01*
X1106767Y493417D01*
Y492917D01*
X1106900Y492417D01*
X1107233Y491917D01*
X1107633Y491583D01*
X1108100Y491500D01*
X1108567Y491667D01*
X1109033Y492167D01*
G01X1112000Y492083D02*
X1112333Y491750D01*
X1112800Y491500D01*
X1113200D01*
X1113600Y491667D01*
X1113867Y491917D01*
X1114000Y492250D01*
X1113933Y492750D01*
X1113667Y493000D01*
X1112467Y493500D01*
X1112200Y494083D01*
X1112333Y494500D01*
X1112600Y494750D01*
X1113000Y494833D01*
X1113400Y494750D01*
X1113800Y494500D01*
G01X1117100Y492083D02*
X1117433Y491750D01*
X1117900Y491500D01*
X1118300D01*
X1118700Y491667D01*
X1118967Y491917D01*
X1119100Y492250D01*
X1119033Y492750D01*
X1118767Y493000D01*
X1117567Y493500D01*
X1117300Y494083D01*
X1117433Y494500D01*
X1117700Y494750D01*
X1118100Y494833D01*
X1118500Y494750D01*
X1118900Y494500D01*
G01X1129633Y491500D02*
X1126967Y493167D01*
X1129633Y494833D01*
G01X1138500Y496500D02*
X1137967Y496333D01*
X1137567Y495917D01*
X1137300Y495417D01*
X1137100Y494750D01*
X1137033Y494000D01*
X1137100Y493250D01*
X1137300Y492583D01*
X1137567Y492083D01*
X1137967Y491667D01*
X1138500Y491500D01*
X1139033Y491667D01*
X1139433Y492083D01*
X1139700Y492583D01*
X1139900Y493250D01*
X1139967Y494000D01*
X1139900Y494750D01*
X1139700Y495417D01*
X1139433Y495917D01*
X1139033Y496333D01*
X1138500Y496500D01*
G01X1143600Y491333D02*
X1143467Y491417D01*
Y491583D01*
X1143600Y491667D01*
X1143733Y491583D01*
Y491417D01*
X1143600Y491333D01*
G01X1147567Y492083D02*
X1148033Y491667D01*
X1148567Y491500D01*
X1149100Y491667D01*
X1149567Y492167D01*
X1149900Y492917D01*
X1150033Y493667D01*
Y494583D01*
X1149900Y495333D01*
X1149567Y496000D01*
X1149167Y496333D01*
X1148700Y496500D01*
X1148167Y496333D01*
X1147767Y496000D01*
X1147500Y495500D01*
X1147367Y494833D01*
X1147500Y494250D01*
X1147833Y493667D01*
X1148233Y493333D01*
X1148700Y493250D01*
X1149233Y493417D01*
X1149633Y493833D01*
X1150033Y494583D01*
G01X1151800Y491500D02*
Y494833D01*
G01Y493917D02*
X1152000Y494333D01*
X1152333Y494667D01*
X1152800Y494833D01*
X1153267Y494667D01*
X1153600Y494333D01*
X1153800Y493917D01*
Y491500D01*
G01Y493917D02*
X1154000Y494333D01*
X1154333Y494667D01*
X1154800Y494833D01*
X1155267Y494667D01*
X1155600Y494333D01*
X1155800Y493833D01*
Y491500D01*
G01X1156900D02*
Y494833D01*
G01Y493917D02*
X1157100Y494333D01*
X1157433Y494667D01*
X1157900Y494833D01*
X1158367Y494667D01*
X1158700Y494333D01*
X1158900Y493917D01*
Y491500D01*
G01Y493917D02*
X1159100Y494333D01*
X1159433Y494667D01*
X1159900Y494833D01*
X1160367Y494667D01*
X1160700Y494333D01*
X1160900Y493833D01*
Y491500D01*
G01X1164000Y491333D02*
X1163867Y491417D01*
Y491583D01*
X1164000Y491667D01*
X1164133Y491583D01*
Y491417D01*
X1164000Y491333D01*
G01Y493583D02*
X1163867Y493667D01*
Y493833D01*
X1164000Y493917D01*
X1164133Y493833D01*
Y493667D01*
X1164000Y493583D01*
G01X1045300Y504833D02*
X1046500Y501500D01*
X1047700Y504833D01*
G01X1051600D02*
Y501500D01*
G01Y506167D02*
X1051467Y506250D01*
Y506417D01*
X1051600Y506500D01*
X1051733Y506417D01*
Y506250D01*
X1051600Y506167D01*
G01X1057900Y501500D02*
Y504833D01*
G01Y504250D02*
X1057633Y504583D01*
X1057233Y504750D01*
X1056767Y504833D01*
X1056300Y504667D01*
X1055900Y504333D01*
X1055633Y503833D01*
X1055500Y503167D01*
X1055633Y502500D01*
X1055900Y502000D01*
X1056300Y501667D01*
X1056767Y501500D01*
X1057233Y501583D01*
X1057633Y501833D01*
X1057900Y502167D01*
G01X1065900Y502083D02*
X1066233Y501750D01*
X1066700Y501500D01*
X1067100D01*
X1067500Y501667D01*
X1067767Y501917D01*
X1067900Y502250D01*
X1067833Y502750D01*
X1067567Y503000D01*
X1066367Y503500D01*
X1066100Y504083D01*
X1066233Y504500D01*
X1066500Y504750D01*
X1066900Y504833D01*
X1067300Y504750D01*
X1067700Y504500D01*
G01X1070867Y501500D02*
Y506500D01*
G01Y504083D02*
X1071200Y504500D01*
X1071533Y504750D01*
X1072067Y504833D01*
X1072467Y504750D01*
X1072933Y504417D01*
X1073133Y503917D01*
Y501500D01*
G01X1078300D02*
Y504833D01*
G01Y504250D02*
X1078033Y504583D01*
X1077633Y504750D01*
X1077167Y504833D01*
X1076700Y504667D01*
X1076300Y504333D01*
X1076033Y503833D01*
X1075900Y503167D01*
X1076033Y502500D01*
X1076300Y502000D01*
X1076700Y501667D01*
X1077167Y501500D01*
X1077633Y501583D01*
X1078033Y501833D01*
X1078300Y502167D01*
G01X1082200Y501500D02*
Y506500D01*
G01X1087300Y501500D02*
Y506500D01*
G01X1096300Y501500D02*
Y506500D01*
G01Y504000D02*
X1096633Y504500D01*
X1097033Y504750D01*
X1097433Y504833D01*
X1098033Y504667D01*
X1098433Y504333D01*
X1098700Y503750D01*
Y503083D01*
X1098567Y502417D01*
X1098300Y501917D01*
X1097833Y501583D01*
X1097433Y501500D01*
X1097033Y501583D01*
X1096633Y501833D01*
X1096300Y502250D01*
G01X1101600Y503750D02*
X1103733D01*
X1103533Y504333D01*
X1103200Y504667D01*
X1102733Y504833D01*
X1102267Y504750D01*
X1101867Y504500D01*
X1101600Y503917D01*
X1101467Y503417D01*
Y502917D01*
X1101600Y502417D01*
X1101933Y501917D01*
X1102333Y501583D01*
X1102800Y501500D01*
X1103267Y501667D01*
X1103733Y502167D01*
G01X1111600Y499833D02*
Y504833D01*
G01Y504083D02*
X1111933Y504500D01*
X1112267Y504750D01*
X1112800Y504833D01*
X1113267Y504750D01*
X1113733Y504333D01*
X1113933Y503750D01*
X1114000Y503167D01*
X1113933Y502583D01*
X1113733Y502000D01*
X1113333Y501667D01*
X1112800Y501500D01*
X1112333Y501583D01*
X1111867Y501833D01*
X1111600Y502167D01*
G01X1117900Y501500D02*
Y506500D01*
G01X1121867Y504833D02*
Y502500D01*
X1122133Y501917D01*
X1122533Y501583D01*
X1123000Y501500D01*
X1123467Y501583D01*
X1123867Y501917D01*
X1124133Y502500D01*
G01Y501500D02*
Y504833D01*
G01X1127167Y500250D02*
X1127633Y499917D01*
X1128167Y499833D01*
X1128633Y499917D01*
X1129033Y500333D01*
X1129300Y500917D01*
Y504833D01*
G01Y504167D02*
X1129033Y504500D01*
X1128633Y504750D01*
X1128167Y504833D01*
X1127633Y504667D01*
X1127300Y504333D01*
X1127033Y503750D01*
X1126900Y503167D01*
X1126967Y502667D01*
X1127233Y502083D01*
X1127633Y501667D01*
X1128167Y501500D01*
X1128567Y501583D01*
X1129033Y501917D01*
X1129300Y502250D01*
G01X1132267Y500250D02*
X1132733Y499917D01*
X1133267Y499833D01*
X1133733Y499917D01*
X1134133Y500333D01*
X1134400Y500917D01*
Y504833D01*
G01Y504167D02*
X1134133Y504500D01*
X1133733Y504750D01*
X1133267Y504833D01*
X1132733Y504667D01*
X1132400Y504333D01*
X1132133Y503750D01*
X1132000Y503167D01*
X1132067Y502667D01*
X1132333Y502083D01*
X1132733Y501667D01*
X1133267Y501500D01*
X1133667Y501583D01*
X1134133Y501917D01*
X1134400Y502250D01*
G01X1137300Y503750D02*
X1139433D01*
X1139233Y504333D01*
X1138900Y504667D01*
X1138433Y504833D01*
X1137967Y504750D01*
X1137567Y504500D01*
X1137300Y503917D01*
X1137167Y503417D01*
Y502917D01*
X1137300Y502417D01*
X1137633Y501917D01*
X1138033Y501583D01*
X1138500Y501500D01*
X1138967Y501667D01*
X1139433Y502167D01*
G01X1144600Y506500D02*
Y501500D01*
G01Y502250D02*
X1144333Y501833D01*
X1143933Y501583D01*
X1143467Y501500D01*
X1142933Y501667D01*
X1142533Y502083D01*
X1142267Y502583D01*
X1142200Y503167D01*
X1142267Y503750D01*
X1142533Y504250D01*
X1142933Y504667D01*
X1143467Y504833D01*
X1143933Y504750D01*
X1144267Y504583D01*
X1144600Y504250D01*
G01X1151933Y504833D02*
X1152733Y501500D01*
X1153600Y504833D01*
X1154467Y501500D01*
X1155267Y504833D01*
G01X1158700D02*
Y501500D01*
G01Y506167D02*
X1158567Y506250D01*
Y506417D01*
X1158700Y506500D01*
X1158833Y506417D01*
Y506250D01*
X1158700Y506167D01*
G01X1163800Y506500D02*
Y501500D01*
G01X1162867Y504833D02*
X1164733D01*
G01X1167767Y501500D02*
Y506500D01*
G01Y504083D02*
X1168100Y504500D01*
X1168433Y504750D01*
X1168967Y504833D01*
X1169367Y504750D01*
X1169833Y504417D01*
X1170033Y503917D01*
Y501500D01*
G01X1180433D02*
X1177767Y503167D01*
X1180433Y504833D01*
G01X1187833Y502250D02*
X1188233Y501833D01*
X1188700Y501583D01*
X1189300Y501500D01*
X1189900Y501667D01*
X1190367Y502000D01*
X1190700Y502583D01*
X1190767Y503250D01*
X1190633Y503917D01*
X1190300Y504333D01*
X1189833Y504667D01*
X1189367Y504750D01*
X1188900Y504667D01*
X1188300Y504333D01*
X1188500Y506500D01*
X1190300D01*
G01X1194400D02*
X1193867Y506333D01*
X1193467Y505917D01*
X1193200Y505417D01*
X1193000Y504750D01*
X1192933Y504000D01*
X1193000Y503250D01*
X1193200Y502583D01*
X1193467Y502083D01*
X1193867Y501667D01*
X1194400Y501500D01*
X1194933Y501667D01*
X1195333Y502083D01*
X1195600Y502583D01*
X1195800Y503250D01*
X1195867Y504000D01*
X1195800Y504750D01*
X1195600Y505417D01*
X1195333Y505917D01*
X1194933Y506333D01*
X1194400Y506500D01*
G01X1203400Y501333D02*
X1205800Y506500D01*
G01X1203400D02*
X1203000Y506333D01*
X1202800Y506083D01*
X1202667Y505583D01*
X1202800Y505083D01*
X1203000Y504833D01*
X1203400Y504667D01*
X1203800Y504833D01*
X1204000Y505083D01*
X1204133Y505583D01*
X1204000Y506083D01*
X1203800Y506333D01*
X1203400Y506500D01*
G01X1205800Y503167D02*
X1205400Y503000D01*
X1205200Y502750D01*
X1205067Y502250D01*
X1205200Y501750D01*
X1205400Y501500D01*
X1205800Y501333D01*
X1206200Y501500D01*
X1206400Y501750D01*
X1206533Y502250D01*
X1206400Y502750D01*
X1206200Y503000D01*
X1205800Y503167D01*
G01X1213800Y502083D02*
X1214133Y501750D01*
X1214600Y501500D01*
X1215000D01*
X1215400Y501667D01*
X1215667Y501917D01*
X1215800Y502250D01*
X1215733Y502750D01*
X1215467Y503000D01*
X1214267Y503500D01*
X1214000Y504083D01*
X1214133Y504500D01*
X1214400Y504750D01*
X1214800Y504833D01*
X1215200Y504750D01*
X1215600Y504500D01*
G01X1219900Y501500D02*
X1219500Y501583D01*
X1219100Y501917D01*
X1218833Y502500D01*
X1218700Y503167D01*
X1218833Y503833D01*
X1219100Y504417D01*
X1219500Y504750D01*
X1219900Y504833D01*
X1220300Y504750D01*
X1220700Y504417D01*
X1220967Y503833D01*
X1221033Y503167D01*
X1220967Y502500D01*
X1220700Y501917D01*
X1220300Y501583D01*
X1219900Y501500D01*
G01X1225000D02*
Y506500D01*
G01X1231300D02*
Y501500D01*
G01Y502250D02*
X1231033Y501833D01*
X1230633Y501583D01*
X1230167Y501500D01*
X1229633Y501667D01*
X1229233Y502083D01*
X1228967Y502583D01*
X1228900Y503167D01*
X1228967Y503750D01*
X1229233Y504250D01*
X1229633Y504667D01*
X1230167Y504833D01*
X1230633Y504750D01*
X1230967Y504583D01*
X1231300Y504250D01*
G01X1234200Y503750D02*
X1236333D01*
X1236133Y504333D01*
X1235800Y504667D01*
X1235333Y504833D01*
X1234867Y504750D01*
X1234467Y504500D01*
X1234200Y503917D01*
X1234067Y503417D01*
Y502917D01*
X1234200Y502417D01*
X1234533Y501917D01*
X1234933Y501583D01*
X1235400Y501500D01*
X1235867Y501667D01*
X1236333Y502167D01*
G01X1239367Y501500D02*
Y504833D01*
G01Y504167D02*
X1239700Y504500D01*
X1240033Y504750D01*
X1240500Y504833D01*
X1240833Y504750D01*
X1241233Y504500D01*
G01X1248500Y501500D02*
Y504833D01*
G01Y503917D02*
X1248700Y504333D01*
X1249033Y504667D01*
X1249500Y504833D01*
X1249967Y504667D01*
X1250300Y504333D01*
X1250500Y503917D01*
Y501500D01*
G01Y503917D02*
X1250700Y504333D01*
X1251033Y504667D01*
X1251500Y504833D01*
X1251967Y504667D01*
X1252300Y504333D01*
X1252500Y503833D01*
Y501500D01*
G01X1256800D02*
Y504833D01*
G01Y504250D02*
X1256533Y504583D01*
X1256133Y504750D01*
X1255667Y504833D01*
X1255200Y504667D01*
X1254800Y504333D01*
X1254533Y503833D01*
X1254400Y503167D01*
X1254533Y502500D01*
X1254800Y502000D01*
X1255200Y501667D01*
X1255667Y501500D01*
X1256133Y501583D01*
X1256533Y501833D01*
X1256800Y502167D01*
G01X1259700Y502083D02*
X1260033Y501750D01*
X1260500Y501500D01*
X1260900D01*
X1261300Y501667D01*
X1261567Y501917D01*
X1261700Y502250D01*
X1261633Y502750D01*
X1261367Y503000D01*
X1260167Y503500D01*
X1259900Y504083D01*
X1260033Y504500D01*
X1260300Y504750D01*
X1260700Y504833D01*
X1261100Y504750D01*
X1261500Y504500D01*
G01X1264667Y501500D02*
Y506500D01*
G01X1266800Y504833D02*
X1264667Y502917D01*
G01X1265533Y503667D02*
X1266933Y501500D01*
G01X1270767Y500583D02*
X1271033Y501667D01*
G01X1037700Y510500D02*
Y513833D01*
G01Y513250D02*
X1037433Y513583D01*
X1037033Y513750D01*
X1036567Y513833D01*
X1036100Y513667D01*
X1035700Y513333D01*
X1035433Y512833D01*
X1035300Y512167D01*
X1035433Y511500D01*
X1035700Y511000D01*
X1036100Y510667D01*
X1036567Y510500D01*
X1037033Y510583D01*
X1037433Y510833D01*
X1037700Y511167D01*
G01X1041600Y510333D02*
X1041467Y510417D01*
Y510583D01*
X1041600Y510667D01*
X1041733Y510583D01*
Y510417D01*
X1041600Y510333D01*
G01X1047233Y513167D02*
X1047500Y513417D01*
X1047700Y513833D01*
X1047833Y514417D01*
X1047700Y514917D01*
X1047433Y515250D01*
X1046967Y515500D01*
X1045167D01*
Y510500D01*
X1047367D01*
X1047833Y510833D01*
X1048100Y511333D01*
X1048233Y511917D01*
X1048100Y512500D01*
X1047700Y513000D01*
X1047233Y513167D01*
X1045167D01*
G01X1051800Y510500D02*
X1051400Y510583D01*
X1051000Y510917D01*
X1050733Y511500D01*
X1050600Y512167D01*
X1050733Y512833D01*
X1051000Y513417D01*
X1051400Y513750D01*
X1051800Y513833D01*
X1052200Y513750D01*
X1052600Y513417D01*
X1052867Y512833D01*
X1052933Y512167D01*
X1052867Y511500D01*
X1052600Y510917D01*
X1052200Y510583D01*
X1051800Y510500D01*
G01X1058100D02*
Y513833D01*
G01Y513250D02*
X1057833Y513583D01*
X1057433Y513750D01*
X1056967Y513833D01*
X1056500Y513667D01*
X1056100Y513333D01*
X1055833Y512833D01*
X1055700Y512167D01*
X1055833Y511500D01*
X1056100Y511000D01*
X1056500Y510667D01*
X1056967Y510500D01*
X1057433Y510583D01*
X1057833Y510833D01*
X1058100Y511167D01*
G01X1061067Y510500D02*
Y513833D01*
G01Y513167D02*
X1061400Y513500D01*
X1061733Y513750D01*
X1062200Y513833D01*
X1062533Y513750D01*
X1062933Y513500D01*
G01X1068300Y515500D02*
Y510500D01*
G01Y511250D02*
X1068033Y510833D01*
X1067633Y510583D01*
X1067167Y510500D01*
X1066633Y510667D01*
X1066233Y511083D01*
X1065967Y511583D01*
X1065900Y512167D01*
X1065967Y512750D01*
X1066233Y513250D01*
X1066633Y513667D01*
X1067167Y513833D01*
X1067633Y513750D01*
X1067967Y513583D01*
X1068300Y513250D01*
G01X1077300Y515500D02*
Y510500D01*
G01X1076367Y513833D02*
X1078233D01*
G01X1081267Y510500D02*
Y515500D01*
G01Y513083D02*
X1081600Y513500D01*
X1081933Y513750D01*
X1082467Y513833D01*
X1082867Y513750D01*
X1083333Y513417D01*
X1083533Y512917D01*
Y510500D01*
G01X1087500Y513833D02*
Y510500D01*
G01Y515167D02*
X1087367Y515250D01*
Y515417D01*
X1087500Y515500D01*
X1087633Y515417D01*
Y515250D01*
X1087500Y515167D01*
G01X1093667Y513417D02*
X1093200Y513750D01*
X1092800Y513833D01*
X1092267Y513667D01*
X1091867Y513333D01*
X1091600Y512750D01*
X1091533Y512167D01*
X1091600Y511583D01*
X1091867Y511083D01*
X1092267Y510667D01*
X1092800Y510500D01*
X1093267Y510667D01*
X1093667Y511000D01*
G01X1096567Y510500D02*
Y515500D01*
G01X1098700Y513833D02*
X1096567Y511917D01*
G01X1097433Y512667D02*
X1098833Y510500D01*
G01X1101667D02*
Y513833D01*
G01Y513000D02*
X1101933Y513417D01*
X1102333Y513750D01*
X1102867Y513833D01*
X1103333Y513750D01*
X1103733Y513417D01*
X1103933Y512833D01*
Y510500D01*
G01X1106900Y512750D02*
X1109033D01*
X1108833Y513333D01*
X1108500Y513667D01*
X1108033Y513833D01*
X1107567Y513750D01*
X1107167Y513500D01*
X1106900Y512917D01*
X1106767Y512417D01*
Y511917D01*
X1106900Y511417D01*
X1107233Y510917D01*
X1107633Y510583D01*
X1108100Y510500D01*
X1108567Y510667D01*
X1109033Y511167D01*
G01X1112000Y511083D02*
X1112333Y510750D01*
X1112800Y510500D01*
X1113200D01*
X1113600Y510667D01*
X1113867Y510917D01*
X1114000Y511250D01*
X1113933Y511750D01*
X1113667Y512000D01*
X1112467Y512500D01*
X1112200Y513083D01*
X1112333Y513500D01*
X1112600Y513750D01*
X1113000Y513833D01*
X1113400Y513750D01*
X1113800Y513500D01*
G01X1117100Y511083D02*
X1117433Y510750D01*
X1117900Y510500D01*
X1118300D01*
X1118700Y510667D01*
X1118967Y510917D01*
X1119100Y511250D01*
X1119033Y511750D01*
X1118767Y512000D01*
X1117567Y512500D01*
X1117300Y513083D01*
X1117433Y513500D01*
X1117700Y513750D01*
X1118100Y513833D01*
X1118500Y513750D01*
X1118900Y513500D01*
G01X1121867Y510500D02*
X1124533Y512167D01*
X1121867Y513833D01*
G01X1127433Y511417D02*
X1129167D01*
G01Y512917D02*
X1127433D01*
G01X1138500Y515500D02*
X1137967Y515333D01*
X1137567Y514917D01*
X1137300Y514417D01*
X1137100Y513750D01*
X1137033Y513000D01*
X1137100Y512250D01*
X1137300Y511583D01*
X1137567Y511083D01*
X1137967Y510667D01*
X1138500Y510500D01*
X1139033Y510667D01*
X1139433Y511083D01*
X1139700Y511583D01*
X1139900Y512250D01*
X1139967Y513000D01*
X1139900Y513750D01*
X1139700Y514417D01*
X1139433Y514917D01*
X1139033Y515333D01*
X1138500Y515500D01*
G01X1143600Y510333D02*
X1143467Y510417D01*
Y510583D01*
X1143600Y510667D01*
X1143733Y510583D01*
Y510417D01*
X1143600Y510333D01*
G01X1147567Y511083D02*
X1148033Y510667D01*
X1148567Y510500D01*
X1149100Y510667D01*
X1149567Y511167D01*
X1149900Y511917D01*
X1150033Y512667D01*
Y513583D01*
X1149900Y514333D01*
X1149567Y515000D01*
X1149167Y515333D01*
X1148700Y515500D01*
X1148167Y515333D01*
X1147767Y515000D01*
X1147500Y514500D01*
X1147367Y513833D01*
X1147500Y513250D01*
X1147833Y512667D01*
X1148233Y512333D01*
X1148700Y512250D01*
X1149233Y512417D01*
X1149633Y512833D01*
X1150033Y513583D01*
G01X1151800Y510500D02*
Y513833D01*
G01Y512917D02*
X1152000Y513333D01*
X1152333Y513667D01*
X1152800Y513833D01*
X1153267Y513667D01*
X1153600Y513333D01*
X1153800Y512917D01*
Y510500D01*
G01Y512917D02*
X1154000Y513333D01*
X1154333Y513667D01*
X1154800Y513833D01*
X1155267Y513667D01*
X1155600Y513333D01*
X1155800Y512833D01*
Y510500D01*
G01X1158900Y510333D02*
X1158767Y510417D01*
Y510583D01*
X1158900Y510667D01*
X1159033Y510583D01*
Y510417D01*
X1158900Y510333D01*
G01Y512583D02*
X1158767Y512667D01*
Y512833D01*
X1158900Y512917D01*
X1159033Y512833D01*
Y512667D01*
X1158900Y512583D01*
G01X1136033Y157700D02*
Y162700D01*
X1137367D01*
X1137900Y162450D01*
X1138300Y162117D01*
X1138633Y161617D01*
X1138900Y161033D01*
X1138967Y160200D01*
X1138900Y159367D01*
X1138633Y158783D01*
X1138300Y158283D01*
X1137900Y157950D01*
X1137367Y157700D01*
X1136033D01*
G01X1141333Y161867D02*
X1141733Y162367D01*
X1142200Y162617D01*
X1142733Y162700D01*
X1143400Y162533D01*
X1143867Y162117D01*
X1144000Y161617D01*
X1143933Y161117D01*
X1143667Y160700D01*
X1142333Y159867D01*
X1141733Y159283D01*
X1141333Y158450D01*
X1141200Y157700D01*
X1144000D01*
G01X1135033Y315700D02*
Y320700D01*
X1136367D01*
X1136900Y320450D01*
X1137300Y320117D01*
X1137633Y319617D01*
X1137900Y319033D01*
X1137967Y318200D01*
X1137900Y317367D01*
X1137633Y316783D01*
X1137300Y316283D01*
X1136900Y315950D01*
X1136367Y315700D01*
X1135033D01*
G01X1141600D02*
Y320700D01*
X1140800Y319700D01*
G01Y315700D02*
X1142400D01*
G01X1136067Y619917D02*
X1135600Y620250D01*
X1135200Y620333D01*
X1134667Y620167D01*
X1134267Y619833D01*
X1134000Y619250D01*
X1133933Y618667D01*
X1134000Y618083D01*
X1134267Y617583D01*
X1134667Y617167D01*
X1135200Y617000D01*
X1135667Y617167D01*
X1136067Y617500D01*
G01X1140100Y617000D02*
X1139700Y617083D01*
X1139300Y617417D01*
X1139033Y618000D01*
X1138900Y618667D01*
X1139033Y619333D01*
X1139300Y619917D01*
X1139700Y620250D01*
X1140100Y620333D01*
X1140500Y620250D01*
X1140900Y619917D01*
X1141167Y619333D01*
X1141233Y618667D01*
X1141167Y618000D01*
X1140900Y617417D01*
X1140500Y617083D01*
X1140100Y617000D01*
G01X1144000Y615333D02*
Y620333D01*
G01Y619583D02*
X1144333Y620000D01*
X1144667Y620250D01*
X1145200Y620333D01*
X1145667Y620250D01*
X1146133Y619833D01*
X1146333Y619250D01*
X1146400Y618667D01*
X1146333Y618083D01*
X1146133Y617500D01*
X1145733Y617167D01*
X1145200Y617000D01*
X1144733Y617083D01*
X1144267Y617333D01*
X1144000Y617667D01*
G01X1149100Y615333D02*
Y620333D01*
G01Y619583D02*
X1149433Y620000D01*
X1149767Y620250D01*
X1150300Y620333D01*
X1150767Y620250D01*
X1151233Y619833D01*
X1151433Y619250D01*
X1151500Y618667D01*
X1151433Y618083D01*
X1151233Y617500D01*
X1150833Y617167D01*
X1150300Y617000D01*
X1149833Y617083D01*
X1149367Y617333D01*
X1149100Y617667D01*
G01X1154400Y619250D02*
X1156533D01*
X1156333Y619833D01*
X1156000Y620167D01*
X1155533Y620333D01*
X1155067Y620250D01*
X1154667Y620000D01*
X1154400Y619417D01*
X1154267Y618917D01*
Y618417D01*
X1154400Y617917D01*
X1154733Y617417D01*
X1155133Y617083D01*
X1155600Y617000D01*
X1156067Y617167D01*
X1156533Y617667D01*
G01X1159567Y617000D02*
Y620333D01*
G01Y619667D02*
X1159900Y620000D01*
X1160233Y620250D01*
X1160700Y620333D01*
X1161033Y620250D01*
X1161433Y620000D01*
G01X1109667Y590500D02*
Y595500D01*
X1111267D01*
X1111800Y595250D01*
X1112200Y594667D01*
X1112333Y594000D01*
X1112200Y593333D01*
X1111867Y592833D01*
X1111267Y592583D01*
X1109667D01*
G01X1116100Y590500D02*
Y595500D01*
G01X1120067Y593833D02*
Y591500D01*
X1120333Y590917D01*
X1120733Y590583D01*
X1121200Y590500D01*
X1121667Y590583D01*
X1122067Y590917D01*
X1122333Y591500D01*
G01Y590500D02*
Y593833D01*
G01X1125367Y589250D02*
X1125833Y588917D01*
X1126367Y588833D01*
X1126833Y588917D01*
X1127233Y589333D01*
X1127500Y589917D01*
Y593833D01*
G01Y593167D02*
X1127233Y593500D01*
X1126833Y593750D01*
X1126367Y593833D01*
X1125833Y593667D01*
X1125500Y593333D01*
X1125233Y592750D01*
X1125100Y592167D01*
X1125167Y591667D01*
X1125433Y591083D01*
X1125833Y590667D01*
X1126367Y590500D01*
X1126767Y590583D01*
X1127233Y590917D01*
X1127500Y591250D01*
G01X1130467Y589250D02*
X1130933Y588917D01*
X1131467Y588833D01*
X1131933Y588917D01*
X1132333Y589333D01*
X1132600Y589917D01*
Y593833D01*
G01Y593167D02*
X1132333Y593500D01*
X1131933Y593750D01*
X1131467Y593833D01*
X1130933Y593667D01*
X1130600Y593333D01*
X1130333Y592750D01*
X1130200Y592167D01*
X1130267Y591667D01*
X1130533Y591083D01*
X1130933Y590667D01*
X1131467Y590500D01*
X1131867Y590583D01*
X1132333Y590917D01*
X1132600Y591250D01*
G01X1136500Y593833D02*
Y590500D01*
G01Y595167D02*
X1136367Y595250D01*
Y595417D01*
X1136500Y595500D01*
X1136633Y595417D01*
Y595250D01*
X1136500Y595167D01*
G01X1140467Y590500D02*
Y593833D01*
G01Y593000D02*
X1140733Y593417D01*
X1141133Y593750D01*
X1141667Y593833D01*
X1142133Y593750D01*
X1142533Y593417D01*
X1142733Y592833D01*
Y590500D01*
G01X1145767Y589250D02*
X1146233Y588917D01*
X1146767Y588833D01*
X1147233Y588917D01*
X1147633Y589333D01*
X1147900Y589917D01*
Y593833D01*
G01Y593167D02*
X1147633Y593500D01*
X1147233Y593750D01*
X1146767Y593833D01*
X1146233Y593667D01*
X1145900Y593333D01*
X1145633Y592750D01*
X1145500Y592167D01*
X1145567Y591667D01*
X1145833Y591083D01*
X1146233Y590667D01*
X1146767Y590500D01*
X1147167Y590583D01*
X1147633Y590917D01*
X1147900Y591250D01*
G01X1157967Y593417D02*
X1157500Y593750D01*
X1157100Y593833D01*
X1156567Y593667D01*
X1156167Y593333D01*
X1155900Y592750D01*
X1155833Y592167D01*
X1155900Y591583D01*
X1156167Y591083D01*
X1156567Y590667D01*
X1157100Y590500D01*
X1157567Y590667D01*
X1157967Y591000D01*
G01X1161067Y590500D02*
Y593833D01*
G01Y593167D02*
X1161400Y593500D01*
X1161733Y593750D01*
X1162200Y593833D01*
X1162533Y593750D01*
X1162933Y593500D01*
G01X1167100Y593833D02*
Y590500D01*
G01Y595167D02*
X1166967Y595250D01*
Y595417D01*
X1167100Y595500D01*
X1167233Y595417D01*
Y595250D01*
X1167100Y595167D01*
G01X1172200Y595500D02*
Y590500D01*
G01X1171267Y593833D02*
X1173133D01*
G01X1176300Y592750D02*
X1178433D01*
X1178233Y593333D01*
X1177900Y593667D01*
X1177433Y593833D01*
X1176967Y593750D01*
X1176567Y593500D01*
X1176300Y592917D01*
X1176167Y592417D01*
Y591917D01*
X1176300Y591417D01*
X1176633Y590917D01*
X1177033Y590583D01*
X1177500Y590500D01*
X1177967Y590667D01*
X1178433Y591167D01*
G01X1181467Y590500D02*
Y593833D01*
G01Y593167D02*
X1181800Y593500D01*
X1182133Y593750D01*
X1182600Y593833D01*
X1182933Y593750D01*
X1183333Y593500D01*
G01X1187500Y593833D02*
Y590500D01*
G01Y595167D02*
X1187367Y595250D01*
Y595417D01*
X1187500Y595500D01*
X1187633Y595417D01*
Y595250D01*
X1187500Y595167D01*
G01X1193800Y590500D02*
Y593833D01*
G01Y593250D02*
X1193533Y593583D01*
X1193133Y593750D01*
X1192667Y593833D01*
X1192200Y593667D01*
X1191800Y593333D01*
X1191533Y592833D01*
X1191400Y592167D01*
X1191533Y591500D01*
X1191800Y591000D01*
X1192200Y590667D01*
X1192667Y590500D01*
X1193133Y590583D01*
X1193533Y590833D01*
X1193800Y591167D01*
G01X1106333Y735500D02*
X1108000Y730500D01*
X1109667Y735500D01*
G01X1112300D02*
X1113900D01*
G01X1113100D02*
Y730500D01*
G01X1112300D02*
X1113900D01*
G01X1116867D02*
Y735500D01*
X1118467D01*
X1119000Y735250D01*
X1119400Y734667D01*
X1119533Y734000D01*
X1119400Y733333D01*
X1119067Y732833D01*
X1118467Y732583D01*
X1116867D01*
G01X1184033Y150367D02*
X1184300Y150617D01*
X1184500Y151033D01*
X1184633Y151617D01*
X1184500Y152117D01*
X1184233Y152450D01*
X1183767Y152700D01*
X1181967D01*
Y147700D01*
X1184167D01*
X1184633Y148033D01*
X1184900Y148533D01*
X1185033Y149117D01*
X1184900Y149700D01*
X1184500Y150200D01*
X1184033Y150367D01*
X1181967D01*
G01X1186933Y147700D02*
X1188600Y152700D01*
X1190267Y147700D01*
G01X1189667Y149450D02*
X1187533D01*
G01X1195167Y152283D02*
X1194767Y152533D01*
X1194300Y152700D01*
X1193767D01*
X1193167Y152450D01*
X1192700Y152033D01*
X1192367Y151533D01*
X1192100Y150700D01*
X1192033Y149950D01*
X1192167Y149200D01*
X1192367Y148700D01*
X1192767Y148200D01*
X1193233Y147867D01*
X1193700Y147700D01*
X1194167D01*
X1194633Y147867D01*
X1195033Y148117D01*
X1195367Y148450D01*
G01X1197333Y147700D02*
Y152700D01*
G01X1199867D02*
X1197333Y149617D01*
G01X1200267Y147700D02*
X1198467Y151033D01*
G01X1207533Y147700D02*
Y152700D01*
X1208867D01*
X1209400Y152450D01*
X1209800Y152117D01*
X1210133Y151617D01*
X1210400Y151033D01*
X1210467Y150200D01*
X1210400Y149367D01*
X1210133Y148783D01*
X1209800Y148283D01*
X1209400Y147950D01*
X1208867Y147700D01*
X1207533D01*
G01X1212767D02*
Y152700D01*
X1214433D01*
X1214967Y152450D01*
X1215300Y152117D01*
X1215433Y151450D01*
X1215300Y150783D01*
X1214900Y150367D01*
X1214433Y150117D01*
X1212767D01*
G01X1214433D02*
X1215433Y147700D01*
G01X1218400Y152700D02*
X1220000D01*
G01X1219200D02*
Y147700D01*
G01X1218400D02*
X1220000D01*
G01X1222967Y152700D02*
Y147700D01*
X1225633D01*
G01X1228067Y152700D02*
Y147700D01*
X1230733D01*
G01X1252900D02*
Y151033D01*
G01Y150117D02*
X1253100Y150533D01*
X1253433Y150867D01*
X1253900Y151033D01*
X1254367Y150867D01*
X1254700Y150533D01*
X1254900Y150117D01*
Y147700D01*
G01Y150117D02*
X1255100Y150533D01*
X1255433Y150867D01*
X1255900Y151033D01*
X1256367Y150867D01*
X1256700Y150533D01*
X1256900Y150033D01*
Y147700D01*
G01X1260000Y151033D02*
Y147700D01*
G01Y152367D02*
X1259867Y152450D01*
Y152617D01*
X1260000Y152700D01*
X1260133Y152617D01*
Y152450D01*
X1260000Y152367D01*
G01X1265100Y147700D02*
Y152700D01*
G01X1269200Y148283D02*
X1269533Y147950D01*
X1270000Y147700D01*
X1270400D01*
X1270800Y147867D01*
X1271067Y148117D01*
X1271200Y148450D01*
X1271133Y148950D01*
X1270867Y149200D01*
X1269667Y149700D01*
X1269400Y150283D01*
X1269533Y150700D01*
X1269800Y150950D01*
X1270200Y151033D01*
X1270600Y150950D01*
X1271000Y150700D01*
G01X1274967Y146033D02*
X1274300Y146867D01*
X1273967Y147700D01*
Y151033D01*
X1274300Y151867D01*
X1274967Y152700D01*
G01X1278867Y147700D02*
Y152700D01*
X1281933Y147700D01*
Y152700D01*
G01X1284167Y147700D02*
Y152700D01*
X1285767D01*
X1286300Y152450D01*
X1286700Y151867D01*
X1286833Y151200D01*
X1286700Y150533D01*
X1286367Y150033D01*
X1285767Y149783D01*
X1284167D01*
G01X1290600Y152700D02*
Y147700D01*
G01X1289067Y152700D02*
X1292133D01*
G01X1294300Y147700D02*
Y152700D01*
G01X1297100D02*
Y147700D01*
G01Y150200D02*
X1294300D01*
G01X1301133Y146033D02*
X1301800Y146867D01*
X1302133Y147700D01*
Y151033D01*
X1301800Y151867D01*
X1301133Y152700D01*
G01X1210167Y218700D02*
Y213700D01*
X1212833D01*
G01X1215600Y217033D02*
X1217600Y213700D01*
G01Y217033D02*
X1215600Y213700D01*
G01X1218000Y281583D02*
X1218333Y281250D01*
X1218800Y281000D01*
X1219200D01*
X1219600Y281167D01*
X1219867Y281417D01*
X1220000Y281750D01*
X1219933Y282250D01*
X1219667Y282500D01*
X1218467Y283000D01*
X1218200Y283583D01*
X1218333Y284000D01*
X1218600Y284250D01*
X1219000Y284333D01*
X1219400Y284250D01*
X1219800Y284000D01*
G01X1224100Y286000D02*
Y281000D01*
G01X1223167Y284333D02*
X1225033D01*
G01X1228067D02*
Y282000D01*
X1228333Y281417D01*
X1228733Y281083D01*
X1229200Y281000D01*
X1229667Y281083D01*
X1230067Y281417D01*
X1230333Y282000D01*
G01Y281000D02*
Y284333D01*
G01X1233100Y281000D02*
Y286000D01*
G01Y283500D02*
X1233433Y284000D01*
X1233833Y284250D01*
X1234233Y284333D01*
X1234833Y284167D01*
X1235233Y283833D01*
X1235500Y283250D01*
Y282583D01*
X1235367Y281917D01*
X1235100Y281417D01*
X1234633Y281083D01*
X1234233Y281000D01*
X1233833Y281083D01*
X1233433Y281333D01*
X1233100Y281750D01*
G01X1244500Y281000D02*
Y286000D01*
G01X1248600Y283250D02*
X1250733D01*
X1250533Y283833D01*
X1250200Y284167D01*
X1249733Y284333D01*
X1249267Y284250D01*
X1248867Y284000D01*
X1248600Y283417D01*
X1248467Y282917D01*
Y282417D01*
X1248600Y281917D01*
X1248933Y281417D01*
X1249333Y281083D01*
X1249800Y281000D01*
X1250267Y281167D01*
X1250733Y281667D01*
G01X1253567Y281000D02*
Y284333D01*
G01Y283500D02*
X1253833Y283917D01*
X1254233Y284250D01*
X1254767Y284333D01*
X1255233Y284250D01*
X1255633Y283917D01*
X1255833Y283333D01*
Y281000D01*
G01X1258867Y279750D02*
X1259333Y279417D01*
X1259867Y279333D01*
X1260333Y279417D01*
X1260733Y279833D01*
X1261000Y280417D01*
Y284333D01*
G01Y283667D02*
X1260733Y284000D01*
X1260333Y284250D01*
X1259867Y284333D01*
X1259333Y284167D01*
X1259000Y283833D01*
X1258733Y283250D01*
X1258600Y282667D01*
X1258667Y282167D01*
X1258933Y281583D01*
X1259333Y281167D01*
X1259867Y281000D01*
X1260267Y281083D01*
X1260733Y281417D01*
X1261000Y281750D01*
G01X1264900Y286000D02*
Y281000D01*
G01X1263967Y284333D02*
X1265833D01*
G01X1268867Y281000D02*
Y286000D01*
G01Y283583D02*
X1269200Y284000D01*
X1269533Y284250D01*
X1270067Y284333D01*
X1270467Y284250D01*
X1270933Y283917D01*
X1271133Y283417D01*
Y281000D01*
G01X1274233Y281917D02*
X1275967D01*
G01Y283417D02*
X1274233D01*
G01X1278933Y283083D02*
X1279400Y283667D01*
X1279800Y284000D01*
X1280333Y284167D01*
X1280800Y284000D01*
X1281133Y283667D01*
X1281400Y283167D01*
X1281467Y282583D01*
X1281400Y282083D01*
X1281133Y281583D01*
X1280733Y281167D01*
X1280267Y281000D01*
X1279733Y281167D01*
X1279267Y281667D01*
X1279000Y282417D01*
X1278933Y283250D01*
X1279067Y284333D01*
X1279267Y284917D01*
X1279600Y285500D01*
X1280067Y285917D01*
X1280533Y286000D01*
X1281000Y285833D01*
X1281333Y285417D01*
G01X1284567Y282667D02*
X1286167D01*
G01X1285300Y283750D02*
Y281583D01*
G01X1289200Y280833D02*
X1291600Y286000D01*
G01X1294633Y282667D02*
X1296367D01*
G01X1299133Y281750D02*
X1299533Y281333D01*
X1300000Y281083D01*
X1300600Y281000D01*
X1301200Y281167D01*
X1301667Y281500D01*
X1302000Y282083D01*
X1302067Y282750D01*
X1301933Y283417D01*
X1301600Y283833D01*
X1301133Y284167D01*
X1300667Y284250D01*
X1300200Y284167D01*
X1299600Y283833D01*
X1299800Y286000D01*
X1301600D01*
G01X1303700Y281000D02*
Y284333D01*
G01Y283417D02*
X1303900Y283833D01*
X1304233Y284167D01*
X1304700Y284333D01*
X1305167Y284167D01*
X1305500Y283833D01*
X1305700Y283417D01*
Y281000D01*
G01Y283417D02*
X1305900Y283833D01*
X1306233Y284167D01*
X1306700Y284333D01*
X1307167Y284167D01*
X1307500Y283833D01*
X1307700Y283333D01*
Y281000D01*
G01X1310800Y284333D02*
Y281000D01*
G01Y285667D02*
X1310667Y285750D01*
Y285917D01*
X1310800Y286000D01*
X1310933Y285917D01*
Y285750D01*
X1310800Y285667D01*
G01X1315900Y281000D02*
Y286000D01*
G01X1207167Y260500D02*
Y255500D01*
X1209833D01*
G01X1212467D02*
Y258833D01*
G01Y258000D02*
X1212733Y258417D01*
X1213133Y258750D01*
X1213667Y258833D01*
X1214133Y258750D01*
X1214533Y258417D01*
X1214733Y257833D01*
Y255500D01*
G01X1178600Y315500D02*
Y320500D01*
G01X1181400D02*
Y315500D01*
G01Y318000D02*
X1178600D01*
G01X1185100Y315500D02*
X1184567Y315583D01*
X1184100Y315917D01*
X1183700Y316417D01*
X1183433Y317000D01*
X1183300Y317667D01*
Y318333D01*
X1183433Y319000D01*
X1183700Y319583D01*
X1184100Y320083D01*
X1184567Y320417D01*
X1185100Y320500D01*
X1185633Y320417D01*
X1186100Y320083D01*
X1186500Y319583D01*
X1186767Y319000D01*
X1186900Y318333D01*
Y317667D01*
X1186767Y317000D01*
X1186500Y316417D01*
X1186100Y315917D01*
X1185633Y315583D01*
X1185100Y315500D01*
G01X1188867Y320500D02*
Y315500D01*
X1191533D01*
G01X1196633D02*
X1193967D01*
Y320500D01*
X1196633D01*
G01X1195567Y318083D02*
X1193967D01*
G01X1218800Y315500D02*
Y318833D01*
G01Y317917D02*
X1219000Y318333D01*
X1219333Y318667D01*
X1219800Y318833D01*
X1220267Y318667D01*
X1220600Y318333D01*
X1220800Y317917D01*
Y315500D01*
G01Y317917D02*
X1221000Y318333D01*
X1221333Y318667D01*
X1221800Y318833D01*
X1222267Y318667D01*
X1222600Y318333D01*
X1222800Y317833D01*
Y315500D01*
G01X1225900Y318833D02*
Y315500D01*
G01Y320167D02*
X1225767Y320250D01*
Y320417D01*
X1225900Y320500D01*
X1226033Y320417D01*
Y320250D01*
X1225900Y320167D01*
G01X1231000Y315500D02*
Y320500D01*
G01X1235100Y316083D02*
X1235433Y315750D01*
X1235900Y315500D01*
X1236300D01*
X1236700Y315667D01*
X1236967Y315917D01*
X1237100Y316250D01*
X1237033Y316750D01*
X1236767Y317000D01*
X1235567Y317500D01*
X1235300Y318083D01*
X1235433Y318500D01*
X1235700Y318750D01*
X1236100Y318833D01*
X1236500Y318750D01*
X1236900Y318500D01*
G01X1240867Y313833D02*
X1240200Y314667D01*
X1239867Y315500D01*
Y318833D01*
X1240200Y319667D01*
X1240867Y320500D01*
G01X1244967Y315500D02*
Y320500D01*
X1246567D01*
X1247100Y320250D01*
X1247500Y319667D01*
X1247633Y319000D01*
X1247500Y318333D01*
X1247167Y317833D01*
X1246567Y317583D01*
X1244967D01*
G01X1251400Y320500D02*
Y315500D01*
G01X1249867Y320500D02*
X1252933D01*
G01X1255100Y315500D02*
Y320500D01*
G01X1257900D02*
Y315500D01*
G01Y318000D02*
X1255100D01*
G01X1261933Y313833D02*
X1262600Y314667D01*
X1262933Y315500D01*
Y318833D01*
X1262600Y319667D01*
X1261933Y320500D01*
G01X1180333Y734500D02*
X1182000Y729500D01*
X1183667Y734500D01*
G01X1187100Y729500D02*
X1186567Y729583D01*
X1186100Y729917D01*
X1185700Y730417D01*
X1185433Y731000D01*
X1185300Y731667D01*
Y732333D01*
X1185433Y733000D01*
X1185700Y733583D01*
X1186100Y734083D01*
X1186567Y734417D01*
X1187100Y734500D01*
X1187633Y734417D01*
X1188100Y734083D01*
X1188500Y733583D01*
X1188767Y733000D01*
X1188900Y732333D01*
Y731667D01*
X1188767Y731000D01*
X1188500Y730417D01*
X1188100Y729917D01*
X1187633Y729583D01*
X1187100Y729500D01*
G01X1190867D02*
Y734500D01*
X1192467D01*
X1193000Y734250D01*
X1193400Y733667D01*
X1193533Y733000D01*
X1193400Y732333D01*
X1193067Y731833D01*
X1192467Y731583D01*
X1190867D01*
G01X1240767Y826667D02*
X1242367D01*
G01X1241500Y827750D02*
Y825583D01*
G01X1245400Y824833D02*
X1247800Y830000D01*
G01X1250833Y826667D02*
X1252567D01*
G01X1255333Y825750D02*
X1255733Y825333D01*
X1256200Y825083D01*
X1256800Y825000D01*
X1257400Y825167D01*
X1257867Y825500D01*
X1258200Y826083D01*
X1258267Y826750D01*
X1258133Y827417D01*
X1257800Y827833D01*
X1257333Y828167D01*
X1256867Y828250D01*
X1256400Y828167D01*
X1255800Y827833D01*
X1256000Y830000D01*
X1257800D01*
G01X1259900Y825000D02*
Y828333D01*
G01Y827417D02*
X1260100Y827833D01*
X1260433Y828167D01*
X1260900Y828333D01*
X1261367Y828167D01*
X1261700Y827833D01*
X1261900Y827417D01*
Y825000D01*
G01Y827417D02*
X1262100Y827833D01*
X1262433Y828167D01*
X1262900Y828333D01*
X1263367Y828167D01*
X1263700Y827833D01*
X1263900Y827333D01*
Y825000D01*
G01X1267000Y828333D02*
Y825000D01*
G01Y829667D02*
X1266867Y829750D01*
Y829917D01*
X1267000Y830000D01*
X1267133Y829917D01*
Y829750D01*
X1267000Y829667D01*
G01X1272100Y825000D02*
Y830000D01*
G01X1240767Y811667D02*
X1242367D01*
G01X1241500Y812750D02*
Y810583D01*
G01X1245400Y809833D02*
X1247800Y815000D01*
G01X1250833Y811667D02*
X1252567D01*
G01X1255533Y814167D02*
X1255933Y814667D01*
X1256400Y814917D01*
X1256933Y815000D01*
X1257600Y814833D01*
X1258067Y814417D01*
X1258200Y813917D01*
X1258133Y813417D01*
X1257867Y813000D01*
X1256533Y812167D01*
X1255933Y811583D01*
X1255533Y810750D01*
X1255400Y810000D01*
X1258200D01*
G01X1259900D02*
Y813333D01*
G01Y812417D02*
X1260100Y812833D01*
X1260433Y813167D01*
X1260900Y813333D01*
X1261367Y813167D01*
X1261700Y812833D01*
X1261900Y812417D01*
Y810000D01*
G01Y812417D02*
X1262100Y812833D01*
X1262433Y813167D01*
X1262900Y813333D01*
X1263367Y813167D01*
X1263700Y812833D01*
X1263900Y812333D01*
Y810000D01*
G01X1267000Y813333D02*
Y810000D01*
G01Y814667D02*
X1266867Y814750D01*
Y814917D01*
X1267000Y815000D01*
X1267133Y814917D01*
Y814750D01*
X1267000Y814667D01*
G01X1272100Y810000D02*
Y815000D01*
G01X1242377Y785443D02*
X1241710Y786277D01*
X1241377Y787110D01*
Y790443D01*
X1241710Y791277D01*
X1242377Y792110D01*
G01X1247810Y787110D02*
Y792110D01*
X1247010Y791110D01*
G01Y787110D02*
X1248610D01*
G01X1252910Y786943D02*
X1252777Y787027D01*
Y787193D01*
X1252910Y787277D01*
X1253043Y787193D01*
Y787027D01*
X1252910Y786943D01*
G01X1256743Y791277D02*
X1257143Y791777D01*
X1257610Y792027D01*
X1258143Y792110D01*
X1258810Y791943D01*
X1259277Y791527D01*
X1259410Y791027D01*
X1259343Y790527D01*
X1259077Y790110D01*
X1257743Y789277D01*
X1257143Y788693D01*
X1256743Y787860D01*
X1256610Y787110D01*
X1259410D01*
G01X1261110D02*
Y790443D01*
G01Y789527D02*
X1261310Y789943D01*
X1261643Y790277D01*
X1262110Y790443D01*
X1262577Y790277D01*
X1262910Y789943D01*
X1263110Y789527D01*
Y787110D01*
G01Y789527D02*
X1263310Y789943D01*
X1263643Y790277D01*
X1264110Y790443D01*
X1264577Y790277D01*
X1264910Y789943D01*
X1265110Y789443D01*
Y787110D01*
G01X1266210D02*
Y790443D01*
G01Y789527D02*
X1266410Y789943D01*
X1266743Y790277D01*
X1267210Y790443D01*
X1267677Y790277D01*
X1268010Y789943D01*
X1268210Y789527D01*
Y787110D01*
G01Y789527D02*
X1268410Y789943D01*
X1268743Y790277D01*
X1269210Y790443D01*
X1269677Y790277D01*
X1270010Y789943D01*
X1270210Y789443D01*
Y787110D01*
G01X1276677D02*
Y792110D01*
X1278410Y787943D01*
X1280143Y792110D01*
Y787110D01*
G01X1284710D02*
Y790443D01*
G01Y789860D02*
X1284443Y790193D01*
X1284043Y790360D01*
X1283577Y790443D01*
X1283110Y790277D01*
X1282710Y789943D01*
X1282443Y789443D01*
X1282310Y788777D01*
X1282443Y788110D01*
X1282710Y787610D01*
X1283110Y787277D01*
X1283577Y787110D01*
X1284043Y787193D01*
X1284443Y787443D01*
X1284710Y787777D01*
G01X1287610Y790443D02*
X1289610Y787110D01*
G01Y790443D02*
X1287610Y787110D01*
G01X1294043Y785443D02*
X1294710Y786277D01*
X1295043Y787110D01*
Y790443D01*
X1294710Y791277D01*
X1294043Y792110D01*
G01X1244043Y797230D02*
X1241377Y798897D01*
X1244043Y800563D01*
G01X1246943Y798147D02*
X1248677D01*
G01Y799647D02*
X1246943D01*
G01X1252910Y802230D02*
X1252377Y802063D01*
X1251977Y801647D01*
X1251710Y801147D01*
X1251510Y800480D01*
X1251443Y799730D01*
X1251510Y798980D01*
X1251710Y798313D01*
X1251977Y797813D01*
X1252377Y797397D01*
X1252910Y797230D01*
X1253443Y797397D01*
X1253843Y797813D01*
X1254110Y798313D01*
X1254310Y798980D01*
X1254377Y799730D01*
X1254310Y800480D01*
X1254110Y801147D01*
X1253843Y801647D01*
X1253443Y802063D01*
X1252910Y802230D01*
G01X1258010Y797063D02*
X1257877Y797147D01*
Y797313D01*
X1258010Y797397D01*
X1258143Y797313D01*
Y797147D01*
X1258010Y797063D01*
G01X1262977Y797230D02*
X1263110Y798313D01*
X1263310Y799230D01*
X1263577Y800063D01*
X1263910Y800980D01*
X1264443Y802230D01*
X1261777D01*
G01X1266743Y797980D02*
X1267143Y797563D01*
X1267610Y797313D01*
X1268210Y797230D01*
X1268810Y797397D01*
X1269277Y797730D01*
X1269610Y798313D01*
X1269677Y798980D01*
X1269543Y799647D01*
X1269210Y800063D01*
X1268743Y800397D01*
X1268277Y800480D01*
X1267810Y800397D01*
X1267210Y800063D01*
X1267410Y802230D01*
X1269210D01*
G01X1272110Y797063D02*
X1274510Y802230D01*
G01X1272110D02*
X1271710Y802063D01*
X1271510Y801813D01*
X1271377Y801313D01*
X1271510Y800813D01*
X1271710Y800563D01*
X1272110Y800397D01*
X1272510Y800563D01*
X1272710Y800813D01*
X1272843Y801313D01*
X1272710Y801813D01*
X1272510Y802063D01*
X1272110Y802230D01*
G01X1274510Y798897D02*
X1274110Y798730D01*
X1273910Y798480D01*
X1273777Y797980D01*
X1273910Y797480D01*
X1274110Y797230D01*
X1274510Y797063D01*
X1274910Y797230D01*
X1275110Y797480D01*
X1275243Y797980D01*
X1275110Y798480D01*
X1274910Y798730D01*
X1274510Y798897D01*
G01X1234540Y850500D02*
Y782000D01*
G01X1240767Y841667D02*
X1242367D01*
G01X1241500Y842750D02*
Y840583D01*
G01X1245400Y839833D02*
X1247800Y845000D01*
G01X1250833Y841667D02*
X1252567D01*
G01X1255333Y840750D02*
X1255733Y840333D01*
X1256200Y840083D01*
X1256800Y840000D01*
X1257400Y840167D01*
X1257867Y840500D01*
X1258200Y841083D01*
X1258267Y841750D01*
X1258133Y842417D01*
X1257800Y842833D01*
X1257333Y843167D01*
X1256867Y843250D01*
X1256400Y843167D01*
X1255800Y842833D01*
X1256000Y845000D01*
X1257800D01*
G01X1259900Y840000D02*
Y843333D01*
G01Y842417D02*
X1260100Y842833D01*
X1260433Y843167D01*
X1260900Y843333D01*
X1261367Y843167D01*
X1261700Y842833D01*
X1261900Y842417D01*
Y840000D01*
G01Y842417D02*
X1262100Y842833D01*
X1262433Y843167D01*
X1262900Y843333D01*
X1263367Y843167D01*
X1263700Y842833D01*
X1263900Y842333D01*
Y840000D01*
G01X1267000Y843333D02*
Y840000D01*
G01Y844667D02*
X1266867Y844750D01*
Y844917D01*
X1267000Y845000D01*
X1267133Y844917D01*
Y844750D01*
X1267000Y844667D01*
G01X1272100Y840000D02*
Y845000D01*
G01X1343000Y850610D02*
Y782110D01*
G54D12*
G01X865852Y635354D02*
X843852D01*
G01D02*
Y712354D01*
G01D02*
X865852D01*
G01X898852D02*
Y635354D01*
G01D02*
X942852D01*
G01X907102Y628479D02*
Y635354D01*
G01X891977Y628479D02*
X907102D01*
G01X891977Y721979D02*
Y628479D01*
G01X865852Y712354D02*
Y635354D01*
G01X872727Y628479D02*
Y721979D01*
G01X857602Y628479D02*
X872727D01*
G01X857602Y635354D02*
Y628479D01*
G01X942852Y712354D02*
X898852D01*
G01X907102Y715104D02*
Y721979D01*
G01D02*
X891977D01*
G01X857602D02*
Y715104D01*
G01X872727Y721979D02*
X857602D01*
G01X968977Y628479D02*
X984102D01*
G01X968977Y721979D02*
Y628479D01*
G01X949727D02*
Y721979D01*
G01X934602Y628479D02*
X949727D01*
G01X934602Y635354D02*
Y628479D01*
G01X942852Y635354D02*
Y712354D01*
G01X984102Y721979D02*
X968977D01*
G01X934602D02*
Y715104D01*
G01X949727Y721979D02*
X934602D01*
G01X1026727Y628479D02*
Y719229D01*
G01X1019852Y635354D02*
Y712354D01*
G01X1011602Y628479D02*
X1026727D01*
G01X1011602Y635354D02*
Y628479D01*
G01X984102D02*
Y635354D01*
G01X975852Y712354D02*
Y635354D01*
G01D02*
X1019852D01*
G01X1011602Y719229D02*
Y712354D01*
G01X1026727Y719229D02*
X1011602D01*
G01X984102Y715104D02*
Y721979D01*
G01X1019852Y712354D02*
X975852D01*
G01X1088602Y628479D02*
X1122977D01*
G01X1088602Y635354D02*
Y628479D01*
G01X1061102D02*
Y635354D01*
G01X1045977Y628479D02*
X1061102D01*
G01X1045977Y719229D02*
Y628479D01*
G01X1052852Y712354D02*
Y635354D01*
G01D02*
X1096852D01*
G01X1088602Y719229D02*
Y712354D01*
G01X1103727Y719229D02*
X1088602D01*
G01X1061102D02*
X1045977D01*
G01X1061102Y712354D02*
Y719229D01*
G01X1096852Y712354D02*
X1052852D01*
G01X1129852D02*
Y635354D01*
G01D02*
X1173852D01*
G01X1138102Y628479D02*
Y635354D01*
G01X1122977Y628479D02*
X1138102D01*
G01X1096852Y635354D02*
Y712354D01*
G01X1173852D02*
X1129852D01*
G01X1138102D02*
Y719229D01*
G01D02*
X1103727D01*
G01X1215102Y628479D02*
Y635354D01*
G01X1206852Y712354D02*
Y635354D01*
G01D02*
X1250852D01*
G01X1199977Y628479D02*
X1215102D01*
G01X1199977Y719229D02*
Y628479D01*
G01X1180727D02*
Y719229D01*
G01X1165602Y628479D02*
X1180727D01*
G01X1165602Y635354D02*
Y628479D01*
G01X1173852Y635354D02*
Y712354D01*
G01X1215102D02*
Y719229D01*
G01X1250852Y712354D02*
X1206852D01*
G01X1215102Y719229D02*
X1199977D01*
G01X1165602D02*
Y712354D01*
G01X1180727Y719229D02*
X1165602D01*
G01X1250852Y635354D02*
Y712354D01*
G54D13*
G01X292090Y340830D02*
Y357830D01*
G01X341590Y319830D02*
Y303830D01*
G01X303090Y319830D02*
Y303830D01*
G01X352590Y340830D02*
Y357830D01*
G01X356482Y330153D02*
X352452Y324663D01*
X356652Y324643D01*
G01X345680Y327680D02*
G02X350362Y319860I-4190J-7820D01*
G01X348190Y321780D01*
X351420Y321950D01*
X350460Y319850D01*
G01X439562Y301543D02*
X435532Y296053D01*
X439732Y296033D01*
G54D14*
G01X891702Y710347D02*
X883070Y718978D01*
G01X891702Y708014D02*
X880607Y719107D01*
G01X891702Y675345D02*
X891096Y675951D01*
G01X890957Y676193D02*
X891702Y676936D01*
G01X889988Y677557D02*
X891702Y679270D01*
G01X888823Y678725D02*
X891702Y681604D01*
G01X887462Y679697D02*
X891702Y683937D01*
G01X885887Y680455D02*
X891702Y686270D01*
G01X884054Y680956D02*
X891702Y688604D01*
G01X881854Y681089D02*
X891702Y690937D01*
G01Y674644D02*
X891701Y674645D01*
G01X891702Y719229D02*
Y674644D01*
G01Y705679D02*
X876553Y720829D01*
G01X891702Y703346D02*
X869219Y725829D01*
G01X891702Y701013D02*
X866886Y725829D01*
G01X891702Y698679D02*
X873002Y717379D01*
G01X891702Y696346D02*
X873002Y715046D01*
G01X891702Y694013D02*
X873002Y712712D01*
G01X891702Y691679D02*
X873002Y710379D01*
G01X891702Y689346D02*
X873002Y708046D01*
G01X891702Y687012D02*
X873002Y705711D01*
G01X891702Y684678D02*
X873002Y703378D01*
G01X891702Y682345D02*
X873002Y701045D01*
G01X891702Y680012D02*
X873002Y698711D01*
G01Y690905D02*
X891702Y709604D01*
G01X873002Y693238D02*
X891702Y711938D01*
G01X873002Y695572D02*
X891702Y714272D01*
G01X873002Y697906D02*
X891702Y716605D01*
G01X873002Y700239D02*
X891702Y718939D01*
G01X873002Y702572D02*
X896258Y725829D01*
G01X873002Y704906D02*
X893925Y725829D01*
G01X873002Y707239D02*
X885106Y719344D01*
G01X873002Y709572D02*
X882382Y718952D01*
G01X891702Y677678D02*
X873002Y696378D01*
G01X887198Y679848D02*
X873002Y694045D01*
G01X883703Y681010D02*
X873002Y691711D01*
G01X881330Y681049D02*
X873002Y689377D01*
G01X879392Y680653D02*
X873002Y687044D01*
G01X877738Y679974D02*
X873002Y684711D01*
G01X876310Y679069D02*
X873002Y682377D01*
G01X875080Y677966D02*
X873002Y680044D01*
G01X874045Y676668D02*
X873002Y677711D01*
G01X873215Y675163D02*
X873002Y675377D01*
G01X878929Y680497D02*
X891702Y693270D01*
G01X873002Y676905D02*
X891702Y695603D01*
G01X873002Y679238D02*
X891702Y697938D01*
G01X873002Y681571D02*
X891702Y700271D01*
G01X873002Y683905D02*
X891702Y702604D01*
G01X873002Y686238D02*
X891702Y704938D01*
G01X873002Y688571D02*
X891702Y707271D01*
G01X873002Y674644D02*
Y719229D01*
G01Y674645D02*
Y674644D01*
G01X891701Y674645D02*
G03X873003I-9349J-3541D01*
G01X891779Y725829D02*
X949925D01*
G01X922087Y712629D02*
X908887Y725829D01*
G01X919754Y712629D02*
X906554Y725829D01*
G01X917420Y712629D02*
X904221Y725829D01*
G01X915087Y712629D02*
X901887Y725829D01*
G01X912754Y712629D02*
X907377Y718006D01*
G01X905840Y719543D02*
X899554Y725829D01*
G01X910421Y712629D02*
X907377Y715673D01*
G01X903507Y719543D02*
X897221Y725829D01*
G01X908086Y712629D02*
X907377Y713339D01*
G01X901173Y719543D02*
X894886Y725829D01*
G01X898840Y719543D02*
X892553Y725829D01*
G01X896507Y719543D02*
X891342Y724707D01*
G01X894172Y719543D02*
X890494Y723221D01*
G01X891927Y719455D02*
X889440Y721942D01*
G01X891702Y717347D02*
X888191Y720857D01*
G01X891702Y715014D02*
X886738Y719977D01*
G01X891702Y712680D02*
X885053Y719328D01*
G01X908727Y712629D02*
X921927Y725829D01*
G01X907377Y713613D02*
X919592Y725828D01*
G01X907377Y715946D02*
X917259Y725829D01*
G01X907377Y718280D02*
X914926Y725829D01*
G01X906307Y719543D02*
X912592Y725828D01*
G01X903972Y719543D02*
X910259Y725829D01*
G01X901639Y719543D02*
X907926Y725829D01*
G01X899306Y719543D02*
X905593Y725829D01*
G01X896972Y719543D02*
X903258Y725829D01*
G01X894639Y719543D02*
X900925Y725829D01*
G01X892306Y719543D02*
X898592Y725829D01*
G01X892015Y719543D02*
X891702Y719229D01*
G01X907157Y719543D02*
X892015D01*
G01X907377Y719504D02*
X907157Y719543D01*
G01X907377Y712629D02*
Y719504D01*
G01X934327Y712629D02*
X907377D01*
G01X856340Y725829D02*
X872925D01*
G01X874327Y723054D02*
X871552Y725829D01*
G01X871152Y719229D02*
X864552Y725829D01*
G01X868819Y719229D02*
X862219Y725829D01*
G01X866485Y719229D02*
X859885Y725829D01*
G01X864151Y719229D02*
X857551Y725829D01*
G01X861818Y719229D02*
X855779Y725267D01*
G01X859485Y719229D02*
X854613Y724101D01*
G01X857327Y719053D02*
X853752Y722628D01*
G01X857327Y716720D02*
X853752Y720295D01*
G01X857327Y714387D02*
X853752Y717961D01*
G01X856750Y712629D02*
X853752Y715628D01*
G01X854417Y712629D02*
X853752Y713295D01*
G01X873002Y711907D02*
X880270Y719174D01*
G01X873002Y714240D02*
X878496Y719734D01*
G01X873002Y716573D02*
X876971Y720542D01*
G01X873002Y718907D02*
X875655Y721560D01*
G01X870991Y719229D02*
X874536Y722775D01*
G01X868658Y719229D02*
X873618Y724189D01*
G01X866324Y719229D02*
X872924Y725829D01*
G01X863991Y719229D02*
X870591Y725829D01*
G01X855058Y712629D02*
X857327Y714899D01*
G01X861658Y719229D02*
X868258Y725829D01*
G01X853752Y713657D02*
X857327Y717232D01*
G01X859323Y719229D02*
X865923Y725829D01*
G01X853752Y715991D02*
X863590Y725829D01*
G01X853752Y718324D02*
X861257Y725829D01*
G01X853752Y720657D02*
X858923Y725829D01*
G01X853752Y722991D02*
X856590Y725829D01*
G01X872925D02*
G03X891779I9427J3024D01*
G01X853752Y723240D02*
X856340Y725829D01*
G01X853752Y712629D02*
Y723240D01*
G01X857327Y712629D02*
X853752D01*
G01X857327Y719504D02*
Y712629D01*
G01X857602Y719229D02*
X857327Y719504D01*
G01X873002Y719229D02*
X857602D01*
G01X968702Y649681D02*
X950002Y668381D01*
G01X968702Y647348D02*
X950002Y666048D01*
G01X968702Y645013D02*
X950002Y663713D01*
G01X968702Y642680D02*
X950002Y661380D01*
G01X968702Y640347D02*
X950002Y659047D01*
G01X968702Y638014D02*
X950002Y656713D01*
G01X968702Y635680D02*
X950002Y654380D01*
G01X968702Y633347D02*
X950002Y652047D01*
G01X968702Y631014D02*
X950002Y649713D01*
G01X968702Y628679D02*
X950002Y647379D01*
G01Y630232D02*
X968702Y648932D01*
G01X950002Y632565D02*
X968702Y651265D01*
G01X950002Y634898D02*
X968702Y653598D01*
G01X950002Y637232D02*
X968702Y655931D01*
G01X950002Y639565D02*
X968702Y658265D01*
G01X950002Y641898D02*
X968702Y660598D01*
G01X950002Y644232D02*
X968702Y662931D01*
G01X950002Y646565D02*
X968702Y665265D01*
G01X950002Y648899D02*
X968702Y667599D01*
G01Y628204D02*
X984377D01*
G01X968702Y719504D02*
Y628204D01*
G01X950002D02*
Y719504D01*
G01X975085Y624629D02*
X971511Y628204D01*
G01X972752Y624629D02*
X969177Y628204D01*
G01X970419Y624629D02*
X950002Y645046D01*
G01X968086Y624629D02*
X950002Y642712D01*
G01X965752Y624629D02*
X950002Y640379D01*
G01X963419Y624629D02*
X950002Y638046D01*
G01X961085Y624629D02*
X950002Y635712D01*
G01X958751Y624629D02*
X950002Y633379D01*
G01X956418Y624629D02*
X950002Y631046D01*
G01X954085Y624629D02*
X950002Y628711D01*
G01X951751Y624629D02*
X948176Y628204D01*
G01X970068Y624629D02*
X973643Y628204D01*
G01X967734Y624629D02*
X971309Y628204D01*
G01X965401Y624629D02*
X968976Y628204D01*
G01X963068Y624629D02*
X968702Y630263D01*
G01X960733Y624629D02*
X968702Y632597D01*
G01X958400Y624629D02*
X968702Y634931D01*
G01X956067Y624629D02*
X968702Y637264D01*
G01X953733Y624629D02*
X968702Y639597D01*
G01X951400Y624629D02*
X968702Y641931D01*
G01X949067Y624629D02*
X968702Y644264D01*
G01X946733Y624629D02*
X968702Y646597D01*
G01X949418Y624629D02*
X945843Y628204D01*
G01X947085Y624629D02*
X943510Y628204D01*
G01X934327Y635053D02*
X934300Y635079D01*
G01X934327Y632720D02*
X931967Y635079D01*
G01X934327Y630387D02*
X930752Y633961D01*
G01X933037Y624933D02*
X936307Y628204D01*
G01X931869Y626100D02*
X934327Y628556D01*
G01X930752Y627315D02*
X934327Y630890D01*
G01X930752Y629649D02*
X934327Y633224D01*
G01X930752Y631983D02*
X933848Y635079D01*
G01X930752Y634316D02*
X931515Y635079D01*
G01X934327Y628204D02*
X950002D01*
G01X934327Y635079D02*
Y628204D01*
G01X930752Y635079D02*
X934327D01*
G01X930752Y627218D02*
Y635079D01*
G01X944750Y624629D02*
X941175Y628204D01*
G01X942417Y624629D02*
X938842Y628204D01*
G01X940084Y624629D02*
X936509Y628204D01*
G01X937750Y624629D02*
X930752Y631627D01*
G01X935417Y624629D02*
X930752Y629294D01*
G01X944400Y624629D02*
X947975Y628204D01*
G01X942066Y624629D02*
X945640Y628203D01*
G01X939733Y624629D02*
X943307Y628204D01*
G01X937399Y624629D02*
X940974Y628203D01*
G01X935066Y624629D02*
X938640Y628203D01*
G01X985362Y624629D02*
X933340D01*
G01D02*
X930752Y627218D01*
G01X968702Y710350D02*
X960073Y718978D01*
G01X968702Y708017D02*
X957613Y719106D01*
G01X968702Y705684D02*
X953567Y720819D01*
G01X968702Y698683D02*
X950002Y717383D01*
G01X968702Y696350D02*
X950002Y715049D01*
G01X968702Y694016D02*
X950002Y712716D01*
G01X968702Y691683D02*
X950002Y710383D01*
G01Y690901D02*
X968702Y709601D01*
G01X950002Y693234D02*
X968702Y711934D01*
G01X950002Y695568D02*
X968702Y714267D01*
G01X950002Y697901D02*
X968702Y716601D01*
G01X950002Y700234D02*
X968702Y718934D01*
G01X950002Y702569D02*
X973262Y725828D01*
G01X950002Y704902D02*
X970929Y725829D01*
G01X950002Y707235D02*
X962112Y719345D01*
G01X950002Y709569D02*
X959386Y718952D01*
G01X968702Y689350D02*
X950002Y708049D01*
G01X968702Y687016D02*
X950002Y705716D01*
G01X968702Y684683D02*
X950002Y703383D01*
G01X968702Y682350D02*
X950002Y701048D01*
G01X968702Y680015D02*
X950002Y698715D01*
G01X968702Y677682D02*
X950002Y696382D01*
G01X968702Y675349D02*
X950002Y694048D01*
G01X968702Y673015D02*
X950002Y691715D01*
G01X968702Y670682D02*
X950002Y689382D01*
G01X968702Y668349D02*
X950002Y687048D01*
G01X968702Y666015D02*
X950002Y684715D01*
G01X968702Y663681D02*
X950002Y682381D01*
G01X968702Y661348D02*
X950002Y680047D01*
G01X968702Y659014D02*
X950002Y677714D01*
G01Y658233D02*
X968702Y676932D01*
G01X950002Y660566D02*
X968702Y679266D01*
G01X950002Y662899D02*
X968702Y681599D01*
G01X950002Y665234D02*
X968702Y683932D01*
G01X950002Y667567D02*
X968702Y686267D01*
G01X950002Y669900D02*
X968702Y688600D01*
G01X950002Y672234D02*
X968702Y690933D01*
G01X950002Y674567D02*
X968702Y693267D01*
G01X950002Y676900D02*
X968702Y695600D01*
G01X950002Y679233D02*
X968702Y697933D01*
G01X950002Y681567D02*
X968702Y700267D01*
G01X950002Y683901D02*
X968702Y702601D01*
G01X950002Y686234D02*
X968702Y704934D01*
G01X950002Y688568D02*
X968702Y707268D01*
G01Y656681D02*
X950002Y675381D01*
G01X968702Y654348D02*
X950002Y673048D01*
G01X968702Y652014D02*
X950002Y670714D01*
G01Y651233D02*
X968702Y669932D01*
G01X950002Y653566D02*
X968702Y672266D01*
G01X950002Y655899D02*
X968702Y674599D01*
G01Y703350D02*
X946222Y725829D01*
G01X968702Y701017D02*
X943889Y725829D01*
G01X968779D02*
X985362D01*
G01X978216Y719504D02*
X971891Y725829D01*
G01X975883Y719504D02*
X969558Y725829D01*
G01X973548Y719504D02*
X968343Y724709D01*
G01X971215Y719504D02*
X967496Y723223D01*
G01X968882Y719504D02*
X966442Y721943D01*
G01X968702Y717350D02*
X965193Y720859D01*
G01X968702Y715017D02*
X963741Y719978D01*
G01X968702Y712684D02*
X962057Y719329D01*
G01X951317Y723067D02*
X948556Y725829D01*
G01X971605Y719504D02*
X977930Y725829D01*
G01X969271Y719504D02*
X975596Y725829D01*
G01X950002Y711902D02*
X957273Y719173D01*
G01X950002Y714235D02*
X955499Y719733D01*
G01X950002Y716569D02*
X953974Y720540D01*
G01X950002Y718903D02*
X952657Y721558D01*
G01X948269Y719504D02*
X951539Y722772D01*
G01X984377Y719504D02*
X968702D01*
G01X949925Y725829D02*
G03X968779I9427J3024D01*
G01X947881Y719504D02*
X941556Y725829D01*
G01X945548Y719504D02*
X939223Y725829D01*
G01X943214Y719504D02*
X936889Y725829D01*
G01X940881Y719504D02*
X934556Y725829D01*
G01X938546Y719504D02*
X932223Y725829D01*
G01X936213Y719504D02*
X929888Y725829D01*
G01X934327Y719058D02*
X927555Y725829D01*
G01X934327Y716725D02*
X925222Y725829D01*
G01X934327Y714390D02*
X922888Y725829D01*
G01X933755Y712629D02*
X920555Y725829D01*
G01X931422Y712629D02*
X918222Y725829D01*
G01X929088Y712629D02*
X915888Y725829D01*
G01X926754Y712629D02*
X913554Y725829D01*
G01X945936Y719504D02*
X950619Y724187D01*
G01X943603Y719504D02*
X949925Y725826D01*
G01X941270Y719504D02*
X947595Y725829D01*
G01X932061Y712629D02*
X934327Y714894D01*
G01X938936Y719504D02*
X945261Y725829D01*
G01X929728Y712629D02*
X934327Y717228D01*
G01X936603Y719504D02*
X942928Y725829D01*
G01X927395Y712629D02*
X940595Y725829D01*
G01X925062Y712629D02*
X938260Y725829D01*
G01X922727Y712629D02*
X935927Y725829D01*
G01X920394Y712629D02*
X933594Y725829D01*
G01X918061Y712629D02*
X931260Y725829D01*
G01X915727Y712629D02*
X928927Y725829D01*
G01X913394Y712629D02*
X926593Y725828D01*
G01X934327Y719504D02*
Y712629D01*
G01X950002Y719504D02*
X934327D01*
G01X924420Y712629D02*
X911221Y725829D01*
G01X911061Y712629D02*
X924260Y725829D01*
G01X987952Y632764D02*
X985637Y635078D01*
G01X987952Y630431D02*
X984377Y634006D01*
G01X987952Y628098D02*
X984377Y631673D01*
G01X987225Y626490D02*
X984377Y629338D01*
G01X986058Y625324D02*
X983178Y628204D01*
G01X984377Y629605D02*
X987952Y633180D01*
G01X984377Y631938D02*
X987517Y635079D01*
G01X984377Y634272D02*
X985184Y635079D01*
G01X987952D02*
Y627218D01*
G01X984377Y635079D02*
X987952D01*
G01X984377Y628204D02*
Y635079D01*
G01X984420Y624629D02*
X980845Y628204D01*
G01X984069Y624629D02*
X987952Y628512D01*
G01X981735Y624629D02*
X987952Y630845D01*
G01X979402Y624629D02*
X982977Y628204D01*
G01X987952Y627218D02*
X985362Y624629D01*
G01X982086D02*
X978512Y628204D01*
G01X979752Y624629D02*
X976177Y628204D01*
G01X977419Y624629D02*
X973844Y628204D01*
G01X977068Y624629D02*
X980642Y628204D01*
G01X974734Y624629D02*
X978309Y628204D01*
G01X972401Y624629D02*
X975976Y628204D01*
G01X987952Y721436D02*
X983558Y725829D01*
G01X987952Y719102D02*
X981224Y725829D01*
G01X987952Y714435D02*
X984377Y718009D01*
G01X987424Y712629D02*
X984377Y715676D01*
G01X985091Y712629D02*
X984377Y713343D01*
G01X985731Y712629D02*
X987952Y714850D01*
G01X984377Y713608D02*
X987952Y717183D01*
G01X984377Y715942D02*
X987952Y719517D01*
G01X984377Y718276D02*
X987952Y721851D01*
G01X983271Y719504D02*
X987480Y723712D01*
G01X980938Y719504D02*
X986313Y724879D01*
G01X984377Y712629D02*
Y719504D01*
G01X987952Y712629D02*
X984377D01*
G01X987952Y723240D02*
Y712629D01*
G01X985362Y725829D02*
X987952Y723240D01*
G01Y716769D02*
X978891Y725829D01*
G01X982883Y719504D02*
X976558Y725829D01*
G01X980549Y719504D02*
X974224Y725829D01*
G01X978605Y719504D02*
X984930Y725829D01*
G01X976271Y719504D02*
X982596Y725829D01*
G01X973938Y719504D02*
X980263Y725829D01*
G01X1120658Y632879D02*
X1122702Y634922D01*
G01X1118325Y632879D02*
X1122702Y637256D01*
G01X1115991Y632879D02*
X1122702Y639589D01*
G01X1113658Y632879D02*
X1122702Y641922D01*
G01X1111325Y632879D02*
X1122702Y644257D01*
G01Y714829D02*
Y632879D01*
G01Y649688D02*
X1104002Y668388D01*
G01X1122702Y647355D02*
X1104002Y666055D01*
G01X1108990Y632879D02*
X1122702Y646590D01*
G01X1106657Y632879D02*
X1122702Y648923D01*
G01X1104324Y632879D02*
X1122702Y651257D01*
G01X1104002Y634890D02*
X1122702Y653590D01*
G01X1104002Y637224D02*
X1122702Y655923D01*
G01X1104002Y639557D02*
X1122702Y658257D01*
G01X1104002Y641890D02*
X1122702Y660590D01*
G01X1104002Y644225D02*
X1122702Y662924D01*
G01X1104002Y646558D02*
X1122702Y665258D01*
G01X1104002Y648891D02*
X1122702Y667591D01*
G01Y645022D02*
X1104002Y663721D01*
G01X1122702Y642688D02*
X1104002Y661388D01*
G01X1122702Y640355D02*
X1104002Y659055D01*
G01X1122702Y638022D02*
X1104002Y656721D01*
G01X1122702Y635688D02*
X1104002Y654388D01*
G01X1122702Y633354D02*
X1104002Y652054D01*
G01X1120844Y632879D02*
X1104002Y649720D01*
G01X1118510Y632879D02*
X1104002Y647387D01*
G01X1116177Y632879D02*
X1104002Y645054D01*
G01X1113844Y632879D02*
X1104002Y642720D01*
G01X1111509Y632879D02*
X1104002Y640387D01*
G01X1109176Y632879D02*
X1104002Y638054D01*
G01X1106843Y632879D02*
X1104002Y635721D01*
G01X1104509Y632879D02*
X1104002Y633386D01*
G01X1122702Y632879D02*
X1104002D01*
G01D02*
Y714829D01*
G01X1122702Y710359D02*
X1118231Y714829D01*
G01X1122702Y708025D02*
X1115897Y714829D01*
G01X1122702Y705692D02*
X1113564Y714829D01*
G01X1104002Y690893D02*
X1122702Y709593D01*
G01X1104002Y693226D02*
X1122702Y711926D01*
G01X1104002Y695561D02*
X1122702Y714259D01*
G01X1104002Y697894D02*
X1120937Y714829D01*
G01X1104002Y700227D02*
X1118604Y714829D01*
G01X1104002Y702561D02*
X1116270Y714829D01*
G01X1104002Y704894D02*
X1113937Y714829D01*
G01X1104002Y707227D02*
X1111604Y714829D01*
G01X1104002Y709561D02*
X1109270Y714829D01*
G01X1122702Y703358D02*
X1111231Y714829D01*
G01X1122702Y701024D02*
X1108897Y714829D01*
G01X1122702Y698691D02*
X1106564Y714829D01*
G01X1122702Y696358D02*
X1104231Y714829D01*
G01X1122702Y694024D02*
X1104002Y712724D01*
G01X1122702Y691691D02*
X1104002Y710391D01*
G01X1122702Y689358D02*
X1104002Y708057D01*
G01X1122702Y687023D02*
X1104002Y705723D01*
G01X1122702Y684690D02*
X1104002Y703390D01*
G01X1122702Y682357D02*
X1104002Y701056D01*
G01X1122702Y680023D02*
X1104002Y698723D01*
G01Y658224D02*
X1122702Y676924D01*
G01X1104002Y660559D02*
X1122702Y679259D01*
G01X1104002Y662892D02*
X1122702Y681592D01*
G01X1104002Y665225D02*
X1122702Y683925D01*
G01X1104002Y667559D02*
X1122702Y686258D01*
G01X1104002Y669892D02*
X1122702Y688592D01*
G01X1104002Y672225D02*
X1122702Y690925D01*
G01X1104002Y674559D02*
X1122702Y693258D01*
G01X1104002Y676892D02*
X1122702Y695592D01*
G01X1104002Y679226D02*
X1122702Y697926D01*
G01X1104002Y681560D02*
X1122702Y700259D01*
G01X1104002Y683893D02*
X1122702Y702593D01*
G01X1104002Y686226D02*
X1122702Y704926D01*
G01X1104002Y688560D02*
X1122702Y707259D01*
G01Y677690D02*
X1104002Y696390D01*
G01X1122702Y675357D02*
X1104002Y694057D01*
G01X1122702Y673023D02*
X1104002Y691723D01*
G01X1122702Y670690D02*
X1104002Y689390D01*
G01X1122702Y668356D02*
X1104002Y687056D01*
G01X1122702Y666022D02*
X1104002Y684722D01*
G01X1122702Y663689D02*
X1104002Y682389D01*
G01X1122702Y661356D02*
X1104002Y680056D01*
G01X1122702Y659023D02*
X1104002Y677722D01*
G01X1122702Y656689D02*
X1104002Y675389D01*
G01X1122702Y654356D02*
X1104002Y673056D01*
G01X1122702Y652023D02*
X1104002Y670721D01*
G01Y651225D02*
X1122702Y669924D01*
G01X1104002Y653558D02*
X1122702Y672258D01*
G01X1104002Y655891D02*
X1122702Y674591D01*
G01Y712692D02*
X1120565Y714829D01*
G01X1104002Y711894D02*
X1106937Y714829D01*
G01X1104002Y714228D02*
X1104604Y714829D01*
G01X1104002D02*
X1122702D01*
G01X1197662Y632879D02*
X1199702Y634919D01*
G01X1195328Y632879D02*
X1199702Y637252D01*
G01X1192995Y632879D02*
X1199702Y639586D01*
G01X1190662Y632879D02*
X1199702Y641919D01*
G01X1188328Y632879D02*
X1199702Y644252D01*
G01X1185995Y632879D02*
X1199702Y646585D01*
G01X1183662Y632879D02*
X1199702Y648919D01*
G01X1181327Y632879D02*
X1199702Y651253D01*
G01X1181002Y634887D02*
X1199702Y653586D01*
G01X1181002Y637220D02*
X1199702Y655920D01*
G01X1181002Y639553D02*
X1199702Y658253D01*
G01X1181002Y641887D02*
X1199702Y660586D01*
G01X1181002Y644220D02*
X1199702Y662920D01*
G01X1181002Y646553D02*
X1199702Y665253D01*
G01X1181002Y648888D02*
X1199702Y667586D01*
G01Y649693D02*
X1181002Y668393D01*
G01X1199702Y647360D02*
X1181002Y666059D01*
G01X1199702Y645025D02*
X1181002Y663725D01*
G01X1199702Y642692D02*
X1181002Y661392D01*
G01X1199702Y640359D02*
X1181002Y659058D01*
G01X1199702Y638025D02*
X1181002Y656725D01*
G01X1199702Y635692D02*
X1181002Y654392D01*
G01X1199702Y633359D02*
X1181002Y652058D01*
G01X1197847Y632879D02*
X1181002Y649725D01*
G01X1195514Y632879D02*
X1181002Y647392D01*
G01X1193181Y632879D02*
X1181002Y645057D01*
G01X1190847Y632879D02*
X1181002Y642724D01*
G01X1188514Y632879D02*
X1181002Y640391D01*
G01X1186181Y632879D02*
X1181002Y638057D01*
G01X1183846Y632879D02*
X1181002Y635724D01*
G01X1181513Y632879D02*
X1181002Y633391D01*
G01X1199702Y632879D02*
X1181002D01*
G01X1199702Y714829D02*
Y632879D01*
G01X1181002D02*
Y714829D01*
G01Y690889D02*
X1199702Y709589D01*
G01X1181002Y693223D02*
X1199702Y711922D01*
G01X1181002Y695556D02*
X1199702Y714256D01*
G01X1181002Y697889D02*
X1197941Y714829D01*
G01X1181002Y700223D02*
X1195608Y714829D01*
G01X1181002Y702557D02*
X1193275Y714829D01*
G01X1181002Y704890D02*
X1190940Y714829D01*
G01X1181002Y707224D02*
X1188607Y714829D01*
G01X1181002Y709557D02*
X1186274Y714829D01*
G01X1199702Y710362D02*
X1195235Y714829D01*
G01X1199702Y708029D02*
X1192902Y714829D01*
G01X1199702Y705696D02*
X1190569Y714829D01*
G01X1199702Y703362D02*
X1188234Y714829D01*
G01X1199702Y701029D02*
X1185901Y714829D01*
G01X1199702Y698696D02*
X1183568Y714829D01*
G01X1199702Y696361D02*
X1181234Y714829D01*
G01X1199702Y694028D02*
X1181002Y712728D01*
G01X1199702Y691695D02*
X1181002Y710394D01*
G01Y658221D02*
X1199702Y676921D01*
G01X1181002Y660554D02*
X1199702Y679254D01*
G01X1181002Y662888D02*
X1199702Y681587D01*
G01X1181002Y665221D02*
X1199702Y683921D01*
G01X1181002Y667555D02*
X1199702Y686255D01*
G01X1181002Y669888D02*
X1199702Y688588D01*
G01X1181002Y672222D02*
X1199702Y690922D01*
G01X1181002Y674555D02*
X1199702Y693255D01*
G01X1181002Y676888D02*
X1199702Y695588D01*
G01X1181002Y679222D02*
X1199702Y697922D01*
G01X1181002Y681555D02*
X1199702Y700255D01*
G01X1181002Y683888D02*
X1199702Y702588D01*
G01X1181002Y686223D02*
X1199702Y704922D01*
G01X1181002Y688556D02*
X1199702Y707256D01*
G01Y689361D02*
X1181002Y708061D01*
G01X1199702Y687028D02*
X1181002Y705728D01*
G01X1199702Y684695D02*
X1181002Y703394D01*
G01X1199702Y682361D02*
X1181002Y701061D01*
G01X1199702Y680027D02*
X1181002Y698727D01*
G01X1199702Y677694D02*
X1181002Y696393D01*
G01X1199702Y675360D02*
X1181002Y694060D01*
G01X1199702Y673027D02*
X1181002Y691727D01*
G01X1199702Y670694D02*
X1181002Y689393D01*
G01X1199702Y668360D02*
X1181002Y687060D01*
G01X1199702Y666027D02*
X1181002Y684727D01*
G01X1199702Y663694D02*
X1181002Y682392D01*
G01X1199702Y661359D02*
X1181002Y680059D01*
G01X1199702Y659026D02*
X1181002Y677726D01*
G01Y651221D02*
X1199702Y669921D01*
G01X1181002Y653554D02*
X1199702Y672254D01*
G01X1181002Y655888D02*
X1199702Y674587D01*
G01Y656693D02*
X1181002Y675393D01*
G01X1199702Y654359D02*
X1181002Y673059D01*
G01X1199702Y652026D02*
X1181002Y670726D01*
G01Y711890D02*
X1183940Y714829D01*
G01X1181002Y714224D02*
X1181607Y714829D01*
G01X1199702Y712695D02*
X1197568Y714829D01*
G01X1181002D02*
X1199702D01*
M02*
